FILE_TYPE = MACRO_DRAWING;
SET COLOR_WIRE YELLOW;
SET COLOR_PROP ORANGE;
SET COLOR_DOT WHITE;
SET COLOR_ARC YELLOW;
SET COLOR_BODY GREEN;
SET COLOR_NOTE PURPLE;
SET PROP_DISPLAY VALUE;
SET PAGE_NUMBER P80;
FORCEADD OFFPAGE..1
(-7800 975);
FORCEPROP 2 LAST $XR1 147 
J 0
(-8172 975);
DISPLAY 0.638298 (-8172 975);
PAINT MONO (-8172 975);
FORCEPROP 2 LAST $XR0 146 
J 0
(-8052 975);
DISPLAY 0.638298 (-8052 975);
PAINT MONO (-8052 975);
FORCEPROP 2 LAST CDS_LIB standard
J 0
(-7800 975);
DISPLAY INVISIBLE (-7800 975);
FORCEPROP 1 LAST OFFPAGE TRUE
J 0
(-7475 850);
DISPLAY 0.872340 (-7475 850);
PAINT GREEN (-7475 850);
DISPLAY INVISIBLE (-7475 850);
FORCEPROP 1 LAST COMMENT_BODY TRUE
J 0
(-7675 875);
DISPLAY 0.872340 (-7675 875);
PAINT GREEN (-7675 875);
DISPLAY INVISIBLE (-7675 875);
FORCEPROP 2 LAST PATH I1
J 0
(-8075 1025);
DISPLAY 0.680851 (-8075 1025);
DISPLAY INVISIBLE (-8075 1025);
FORCEADD OFFPAGE..5
(-7800 1325);
FORCEPROP 2 LAST $XR0 132 
J 0
(-8055 1325);
DISPLAY 0.638298 (-8055 1325);
PAINT MONO (-8055 1325);
FORCEPROP 2 LAST CDS_LIB standard
J 0
(-7800 1325);
DISPLAY INVISIBLE (-7800 1325);
FORCEPROP 1 LAST OFFPAGE TRUE
J 0
(-7475 1200);
DISPLAY 0.872340 (-7475 1200);
PAINT GREEN (-7475 1200);
DISPLAY INVISIBLE (-7475 1200);
FORCEPROP 1 LAST COMMENT_BODY TRUE
J 0
(-7700 1250);
DISPLAY 0.872340 (-7700 1250);
PAINT GREEN (-7700 1250);
DISPLAY INVISIBLE (-7700 1250);
FORCEPROP 2 LAST PATH I10
J 0
(-7750 1400);
DISPLAY 0.680851 (-7750 1400);
DISPLAY INVISIBLE (-7750 1400);
FORCEADD Q_RES..1
(-6425 4125);
FORCEPROP 1 LAST LOCATION R194
J 0
(-6300 4125);
DISPLAY 0.489362 (-6300 4125);
PAINT SKYBLUE (-6300 4125);
FORCEPROP 0 LAST $SEC 1
J 2
(-6300 4175);
DISPLAY 0.680851 (-6300 4175);
PAINT MONO (-6300 4175);
DISPLAY INVISIBLE (-6300 4175);
FORCEPROP 0 LAST CDS_SEC 1
J 2
(-6300 4175);
DISPLAY 1.021277 (-6300 4175);
DISPLAY INVISIBLE (-6300 4175);
FORCEPROP 1 LASTPIN (-6525 4125) $PN 1
J 0
(-6513 4137);
DISPLAY 0.489362 (-6513 4137);
PAINT MONO (-6513 4137);
FORCEPROP 1 LASTPIN (-6325 4125) $PN 2
J 0
(-6363 4137);
DISPLAY 0.489362 (-6363 4137);
PAINT MONO (-6363 4137);
FORCEPROP 1 LAST VALUE 0
J 2
(-6550 4125);
DISPLAY 0.489362 (-6550 4125);
PAINT SKYBLUE (-6550 4125);
FORCEPROP 2 LAST CDS_LIB pure_quanta
J 2
(-6425 4125);
DISPLAY INVISIBLE (-6425 4125);
FORCEPROP 1 LAST PACK_TYPE 0402LF
J 2
(-6250 4050);
DISPLAY 0.489362 (-6250 4050);
PAINT SKYBLUE (-6250 4050);
DISPLAY INVISIBLE (-6250 4050);
FORCEPROP 1 LAST TOLERANCE 5%
J 0
(-6550 4100);
DISPLAY 0.489362 (-6550 4100);
PAINT SKYBLUE (-6550 4100);
DISPLAY INVISIBLE (-6550 4100);
FORCEPROP 1 LAST MATERIAL CHIP
J 2
(-6250 4100);
DISPLAY 0.489362 (-6250 4100);
PAINT SKYBLUE (-6250 4100);
DISPLAY INVISIBLE (-6250 4100);
FORCEPROP 1 LAST WATTAGE 1/16W
J 2
(-6500 4050);
DISPLAY 0.489362 (-6500 4050);
PAINT SKYBLUE (-6500 4050);
DISPLAY INVISIBLE (-6500 4050);
FORCEPROP 2 LAST BOM_COST MEM
J 2
(-6400 4275);
DISPLAY 0.744681 (-6400 4275);
PAINT WHITE (-6400 4275);
DISPLAY INVISIBLE (-6400 4275);
FORCEPROP 1 LAST PATH I100
J 0
(-6475 4275);
DISPLAY 0.978723 (-6475 4275);
PAINT WHITE (-6475 4275);
DISPLAY INVISIBLE (-6475 4275);
FORCEPROP 1 LAST PART_NUMBER CS00002JB13
J 2
(-6325 4175);
DISPLAY 0.489362 (-6325 4175);
PAINT SKYBLUE (-6325 4175);
DISPLAY INVISIBLE (-6325 4175);
FORCEADD Q_RES..1
(-6425 4325);
FORCEPROP 1 LAST LOCATION R1281
J 0
(-6300 4325);
DISPLAY 0.489362 (-6300 4325);
PAINT SKYBLUE (-6300 4325);
FORCEPROP 0 LAST $SEC 1
J 0
(-6300 4375);
DISPLAY 0.680851 (-6300 4375);
PAINT MONO (-6300 4375);
DISPLAY INVISIBLE (-6300 4375);
FORCEPROP 0 LAST CDS_SEC 1
J 0
(-6300 4375);
DISPLAY 0.680851 (-6300 4375);
DISPLAY INVISIBLE (-6300 4375);
FORCEPROP 1 LASTPIN (-6525 4325) $PN 1
J 0
(-6513 4337);
DISPLAY 0.489362 (-6513 4337);
PAINT MONO (-6513 4337);
FORCEPROP 1 LASTPIN (-6325 4325) $PN 2
J 0
(-6363 4337);
DISPLAY 0.489362 (-6363 4337);
PAINT MONO (-6363 4337);
FORCEPROP 1 LAST VALUE 33
J 2
(-6550 4325);
DISPLAY 0.489362 (-6550 4325);
PAINT SKYBLUE (-6550 4325);
FORCEPROP 2 LAST CDS_LIB pure_quanta
J 0
(-6425 4325);
DISPLAY INVISIBLE (-6425 4325);
FORCEPROP 2 LAST BOM_COST MEM
J 2
(-6400 4475);
DISPLAY 0.744681 (-6400 4475);
PAINT WHITE (-6400 4475);
DISPLAY INVISIBLE (-6400 4475);
FORCEPROP 1 LAST WATTAGE 1/16W
J 2
(-6500 4250);
DISPLAY 0.489362 (-6500 4250);
PAINT SKYBLUE (-6500 4250);
DISPLAY INVISIBLE (-6500 4250);
FORCEPROP 1 LAST MATERIAL CHIP
J 2
(-6250 4300);
DISPLAY 0.489362 (-6250 4300);
PAINT SKYBLUE (-6250 4300);
DISPLAY INVISIBLE (-6250 4300);
FORCEPROP 1 LAST TOLERANCE 5%
J 0
(-6550 4300);
DISPLAY 0.489362 (-6550 4300);
PAINT SKYBLUE (-6550 4300);
DISPLAY INVISIBLE (-6550 4300);
FORCEPROP 1 LAST PACK_TYPE 0402LF
J 2
(-6250 4250);
DISPLAY 0.489362 (-6250 4250);
PAINT SKYBLUE (-6250 4250);
DISPLAY INVISIBLE (-6250 4250);
FORCEPROP 1 LAST PATH I101
J 0
(-6475 4475);
DISPLAY 0.978723 (-6475 4475);
PAINT WHITE (-6475 4475);
DISPLAY INVISIBLE (-6475 4475);
FORCEPROP 1 LAST PART_NUMBER CS03302JB10
J 2
(-6325 4375);
DISPLAY 0.489362 (-6325 4375);
PAINT SKYBLUE (-6325 4375);
DISPLAY INVISIBLE (-6325 4375);
FORCEADD Q_RES..1
(-6425 4275);
FORCEPROP 1 LAST LOCATION R1280
J 0
(-6300 4275);
DISPLAY 0.489362 (-6300 4275);
PAINT SKYBLUE (-6300 4275);
FORCEPROP 0 LAST $SEC 1
J 0
(-6300 4325);
DISPLAY 0.680851 (-6300 4325);
PAINT MONO (-6300 4325);
DISPLAY INVISIBLE (-6300 4325);
FORCEPROP 0 LAST CDS_SEC 1
J 0
(-6300 4325);
DISPLAY 0.680851 (-6300 4325);
DISPLAY INVISIBLE (-6300 4325);
FORCEPROP 1 LASTPIN (-6525 4275) $PN 1
J 0
(-6513 4287);
DISPLAY 0.489362 (-6513 4287);
PAINT MONO (-6513 4287);
FORCEPROP 1 LASTPIN (-6325 4275) $PN 2
J 0
(-6363 4287);
DISPLAY 0.489362 (-6363 4287);
PAINT MONO (-6363 4287);
FORCEPROP 1 LAST VALUE 33
J 2
(-6550 4275);
DISPLAY 0.489362 (-6550 4275);
PAINT SKYBLUE (-6550 4275);
FORCEPROP 2 LAST CDS_LIB pure_quanta
J 0
(-6425 4275);
DISPLAY INVISIBLE (-6425 4275);
FORCEPROP 2 LAST BOM_COST MEM
J 2
(-6400 4425);
DISPLAY 0.744681 (-6400 4425);
PAINT WHITE (-6400 4425);
DISPLAY INVISIBLE (-6400 4425);
FORCEPROP 1 LAST WATTAGE 1/16W
J 2
(-6500 4200);
DISPLAY 0.489362 (-6500 4200);
PAINT SKYBLUE (-6500 4200);
DISPLAY INVISIBLE (-6500 4200);
FORCEPROP 1 LAST MATERIAL CHIP
J 2
(-6250 4250);
DISPLAY 0.489362 (-6250 4250);
PAINT SKYBLUE (-6250 4250);
DISPLAY INVISIBLE (-6250 4250);
FORCEPROP 1 LAST TOLERANCE 5%
J 0
(-6550 4250);
DISPLAY 0.489362 (-6550 4250);
PAINT SKYBLUE (-6550 4250);
DISPLAY INVISIBLE (-6550 4250);
FORCEPROP 1 LAST PACK_TYPE 0402LF
J 2
(-6250 4200);
DISPLAY 0.489362 (-6250 4200);
PAINT SKYBLUE (-6250 4200);
DISPLAY INVISIBLE (-6250 4200);
FORCEPROP 1 LAST PATH I102
J 0
(-6475 4425);
DISPLAY 0.978723 (-6475 4425);
PAINT WHITE (-6475 4425);
DISPLAY INVISIBLE (-6475 4425);
FORCEPROP 1 LAST PART_NUMBER CS03302JB10
J 2
(-6325 4325);
DISPLAY 0.489362 (-6325 4325);
PAINT SKYBLUE (-6325 4325);
DISPLAY INVISIBLE (-6325 4325);
FORCEADD Q_RES..1
(-6425 4475);
FORCEPROP 1 LAST LOCATION R1279
J 0
(-6300 4475);
DISPLAY 0.489362 (-6300 4475);
PAINT SKYBLUE (-6300 4475);
FORCEPROP 0 LAST $SEC 1
J 0
(-6300 4525);
DISPLAY 0.680851 (-6300 4525);
PAINT MONO (-6300 4525);
DISPLAY INVISIBLE (-6300 4525);
FORCEPROP 0 LAST CDS_SEC 1
J 0
(-6300 4525);
DISPLAY 0.680851 (-6300 4525);
DISPLAY INVISIBLE (-6300 4525);
FORCEPROP 1 LASTPIN (-6525 4475) $PN 1
J 0
(-6513 4487);
DISPLAY 0.489362 (-6513 4487);
PAINT MONO (-6513 4487);
FORCEPROP 1 LASTPIN (-6325 4475) $PN 2
J 0
(-6363 4487);
DISPLAY 0.489362 (-6363 4487);
PAINT MONO (-6363 4487);
FORCEPROP 1 LAST VALUE 33
J 2
(-6550 4475);
DISPLAY 0.489362 (-6550 4475);
PAINT SKYBLUE (-6550 4475);
FORCEPROP 2 LAST CDS_LIB pure_quanta
J 0
(-6425 4475);
DISPLAY INVISIBLE (-6425 4475);
FORCEPROP 2 LAST BOM_COST MEM
J 2
(-6400 4625);
DISPLAY 0.744681 (-6400 4625);
PAINT WHITE (-6400 4625);
DISPLAY INVISIBLE (-6400 4625);
FORCEPROP 1 LAST WATTAGE 1/16W
J 2
(-6500 4400);
DISPLAY 0.489362 (-6500 4400);
PAINT SKYBLUE (-6500 4400);
DISPLAY INVISIBLE (-6500 4400);
FORCEPROP 1 LAST MATERIAL CHIP
J 2
(-6250 4450);
DISPLAY 0.489362 (-6250 4450);
PAINT SKYBLUE (-6250 4450);
DISPLAY INVISIBLE (-6250 4450);
FORCEPROP 1 LAST TOLERANCE 5%
J 0
(-6550 4450);
DISPLAY 0.489362 (-6550 4450);
PAINT SKYBLUE (-6550 4450);
DISPLAY INVISIBLE (-6550 4450);
FORCEPROP 1 LAST PACK_TYPE 0402LF
J 2
(-6250 4400);
DISPLAY 0.489362 (-6250 4400);
PAINT SKYBLUE (-6250 4400);
DISPLAY INVISIBLE (-6250 4400);
FORCEPROP 1 LAST PATH I103
J 0
(-6475 4625);
DISPLAY 0.978723 (-6475 4625);
PAINT WHITE (-6475 4625);
DISPLAY INVISIBLE (-6475 4625);
FORCEPROP 1 LAST PART_NUMBER CS03302JB10
J 2
(-6325 4525);
DISPLAY 0.489362 (-6325 4525);
PAINT SKYBLUE (-6325 4525);
DISPLAY INVISIBLE (-6325 4525);
FORCEADD Q_RES..1
(-6425 4525);
FORCEPROP 1 LAST LOCATION R215
J 0
(-6300 4525);
DISPLAY 0.489362 (-6300 4525);
PAINT SKYBLUE (-6300 4525);
FORCEPROP 0 LAST $SEC 1
J 2
(-6300 4575);
DISPLAY 0.680851 (-6300 4575);
PAINT MONO (-6300 4575);
DISPLAY INVISIBLE (-6300 4575);
FORCEPROP 0 LAST CDS_SEC 1
J 2
(-6300 4575);
DISPLAY 1.021277 (-6300 4575);
DISPLAY INVISIBLE (-6300 4575);
FORCEPROP 1 LASTPIN (-6525 4525) $PN 1
J 0
(-6513 4537);
DISPLAY 0.489362 (-6513 4537);
PAINT MONO (-6513 4537);
FORCEPROP 1 LASTPIN (-6325 4525) $PN 2
J 0
(-6363 4537);
DISPLAY 0.489362 (-6363 4537);
PAINT MONO (-6363 4537);
FORCEPROP 1 LAST VALUE 33
J 2
(-6550 4525);
DISPLAY 0.489362 (-6550 4525);
PAINT SKYBLUE (-6550 4525);
FORCEPROP 2 LAST CDS_LIB pure_quanta
J 2
(-6425 4525);
DISPLAY INVISIBLE (-6425 4525);
FORCEPROP 2 LAST BOM_COST MEM
J 2
(-6400 4675);
DISPLAY 0.744681 (-6400 4675);
PAINT WHITE (-6400 4675);
DISPLAY INVISIBLE (-6400 4675);
FORCEPROP 1 LAST WATTAGE 1/16W
J 2
(-6500 4450);
DISPLAY 0.489362 (-6500 4450);
PAINT SKYBLUE (-6500 4450);
DISPLAY INVISIBLE (-6500 4450);
FORCEPROP 1 LAST MATERIAL CHIP
J 2
(-6250 4500);
DISPLAY 0.489362 (-6250 4500);
PAINT SKYBLUE (-6250 4500);
DISPLAY INVISIBLE (-6250 4500);
FORCEPROP 1 LAST TOLERANCE 5%
J 0
(-6550 4500);
DISPLAY 0.489362 (-6550 4500);
PAINT SKYBLUE (-6550 4500);
DISPLAY INVISIBLE (-6550 4500);
FORCEPROP 1 LAST PACK_TYPE 0402LF
J 2
(-6250 4450);
DISPLAY 0.489362 (-6250 4450);
PAINT SKYBLUE (-6250 4450);
DISPLAY INVISIBLE (-6250 4450);
FORCEPROP 1 LAST PATH I104
J 0
(-6475 4675);
DISPLAY 0.978723 (-6475 4675);
PAINT WHITE (-6475 4675);
DISPLAY INVISIBLE (-6475 4675);
FORCEPROP 1 LAST PART_NUMBER CS03302JB10
J 2
(-6325 4575);
DISPLAY 0.489362 (-6325 4575);
PAINT SKYBLUE (-6325 4575);
DISPLAY INVISIBLE (-6325 4575);
FORCEADD Q_RES..1
(-6425 4625);
FORCEPROP 1 LAST LOCATION R1278
J 0
(-6300 4625);
DISPLAY 0.489362 (-6300 4625);
PAINT SKYBLUE (-6300 4625);
FORCEPROP 0 LAST $SEC 1
J 0
(-6300 4675);
DISPLAY 0.680851 (-6300 4675);
PAINT MONO (-6300 4675);
DISPLAY INVISIBLE (-6300 4675);
FORCEPROP 0 LAST CDS_SEC 1
J 0
(-6300 4675);
DISPLAY 0.680851 (-6300 4675);
DISPLAY INVISIBLE (-6300 4675);
FORCEPROP 1 LASTPIN (-6525 4625) $PN 1
J 0
(-6513 4637);
DISPLAY 0.489362 (-6513 4637);
PAINT MONO (-6513 4637);
FORCEPROP 1 LASTPIN (-6325 4625) $PN 2
J 0
(-6363 4637);
DISPLAY 0.489362 (-6363 4637);
PAINT MONO (-6363 4637);
FORCEPROP 1 LAST VALUE 33
J 2
(-6550 4625);
DISPLAY 0.489362 (-6550 4625);
PAINT SKYBLUE (-6550 4625);
FORCEPROP 2 LAST CDS_LIB pure_quanta
J 0
(-6425 4625);
DISPLAY INVISIBLE (-6425 4625);
FORCEPROP 2 LAST BOM_COST MEM
J 2
(-6400 4775);
DISPLAY 0.744681 (-6400 4775);
PAINT WHITE (-6400 4775);
DISPLAY INVISIBLE (-6400 4775);
FORCEPROP 1 LAST WATTAGE 1/16W
J 2
(-6500 4550);
DISPLAY 0.489362 (-6500 4550);
PAINT SKYBLUE (-6500 4550);
DISPLAY INVISIBLE (-6500 4550);
FORCEPROP 1 LAST MATERIAL CHIP
J 2
(-6250 4600);
DISPLAY 0.489362 (-6250 4600);
PAINT SKYBLUE (-6250 4600);
DISPLAY INVISIBLE (-6250 4600);
FORCEPROP 1 LAST TOLERANCE 5%
J 0
(-6550 4600);
DISPLAY 0.489362 (-6550 4600);
PAINT SKYBLUE (-6550 4600);
DISPLAY INVISIBLE (-6550 4600);
FORCEPROP 1 LAST PACK_TYPE 0402LF
J 2
(-6250 4550);
DISPLAY 0.489362 (-6250 4550);
PAINT SKYBLUE (-6250 4550);
DISPLAY INVISIBLE (-6250 4550);
FORCEPROP 1 LAST PATH I105
J 0
(-6475 4775);
DISPLAY 0.978723 (-6475 4775);
PAINT WHITE (-6475 4775);
DISPLAY INVISIBLE (-6475 4775);
FORCEPROP 1 LAST PART_NUMBER CS03302JB10
J 2
(-6325 4675);
DISPLAY 0.489362 (-6325 4675);
PAINT SKYBLUE (-6325 4675);
DISPLAY INVISIBLE (-6325 4675);
FORCEADD Q_RES..1
(-6425 4675);
FORCEPROP 1 LAST LOCATION R203
J 0
(-6300 4675);
DISPLAY 0.489362 (-6300 4675);
PAINT SKYBLUE (-6300 4675);
FORCEPROP 0 LAST $SEC 1
J 2
(-6300 4725);
DISPLAY 0.680851 (-6300 4725);
PAINT MONO (-6300 4725);
DISPLAY INVISIBLE (-6300 4725);
FORCEPROP 0 LAST CDS_SEC 1
J 2
(-6300 4725);
DISPLAY 1.021277 (-6300 4725);
DISPLAY INVISIBLE (-6300 4725);
FORCEPROP 1 LASTPIN (-6525 4675) $PN 1
J 0
(-6513 4687);
DISPLAY 0.489362 (-6513 4687);
PAINT MONO (-6513 4687);
FORCEPROP 1 LASTPIN (-6325 4675) $PN 2
J 0
(-6363 4687);
DISPLAY 0.489362 (-6363 4687);
PAINT MONO (-6363 4687);
FORCEPROP 1 LAST VALUE 0
J 2
(-6550 4675);
DISPLAY 0.489362 (-6550 4675);
PAINT SKYBLUE (-6550 4675);
FORCEPROP 2 LAST BOM_COST MEM
J 2
(-6400 4825);
DISPLAY 0.744681 (-6400 4825);
PAINT WHITE (-6400 4825);
DISPLAY INVISIBLE (-6400 4825);
FORCEPROP 2 LAST CDS_LIB pure_quanta
J 2
(-6425 4675);
DISPLAY INVISIBLE (-6425 4675);
FORCEPROP 1 LAST WATTAGE 1/16W
J 2
(-6500 4600);
DISPLAY 0.489362 (-6500 4600);
PAINT SKYBLUE (-6500 4600);
DISPLAY INVISIBLE (-6500 4600);
FORCEPROP 1 LAST MATERIAL CHIP
J 2
(-6250 4650);
DISPLAY 0.489362 (-6250 4650);
PAINT SKYBLUE (-6250 4650);
DISPLAY INVISIBLE (-6250 4650);
FORCEPROP 1 LAST TOLERANCE 5%
J 0
(-6550 4650);
DISPLAY 0.489362 (-6550 4650);
PAINT SKYBLUE (-6550 4650);
DISPLAY INVISIBLE (-6550 4650);
FORCEPROP 1 LAST PACK_TYPE 0402LF
J 2
(-6250 4600);
DISPLAY 0.489362 (-6250 4600);
PAINT SKYBLUE (-6250 4600);
DISPLAY INVISIBLE (-6250 4600);
FORCEPROP 1 LAST PATH I106
J 0
(-6475 4825);
DISPLAY 0.978723 (-6475 4825);
PAINT WHITE (-6475 4825);
DISPLAY INVISIBLE (-6475 4825);
FORCEPROP 1 LAST PART_NUMBER CS00002JB13
J 2
(-6325 4725);
DISPLAY 0.489362 (-6325 4725);
PAINT SKYBLUE (-6325 4725);
DISPLAY INVISIBLE (-6325 4725);
FORCEADD Q_RES..1
(-6425 4725);
FORCEPROP 1 LAST LOCATION R371
J 0
(-6300 4725);
DISPLAY 0.489362 (-6300 4725);
PAINT SKYBLUE (-6300 4725);
FORCEPROP 0 LAST $SEC 1
J 0
(-6300 4775);
DISPLAY 0.680851 (-6300 4775);
PAINT MONO (-6300 4775);
DISPLAY INVISIBLE (-6300 4775);
FORCEPROP 0 LAST CDS_SEC 1
J 0
(-6300 4775);
DISPLAY 0.680851 (-6300 4775);
DISPLAY INVISIBLE (-6300 4775);
FORCEPROP 1 LASTPIN (-6525 4725) $PN 1
J 0
(-6513 4737);
DISPLAY 0.489362 (-6513 4737);
PAINT MONO (-6513 4737);
FORCEPROP 1 LASTPIN (-6325 4725) $PN 2
J 0
(-6363 4737);
DISPLAY 0.489362 (-6363 4737);
PAINT MONO (-6363 4737);
FORCEPROP 1 LAST VALUE 33
J 2
(-6550 4725);
DISPLAY 0.489362 (-6550 4725);
PAINT SKYBLUE (-6550 4725);
FORCEPROP 2 LAST CDS_LIB pure_quanta
J 0
(-6425 4725);
DISPLAY INVISIBLE (-6425 4725);
FORCEPROP 2 LAST BOM_COST MEM
J 2
(-6400 4875);
DISPLAY 0.744681 (-6400 4875);
PAINT WHITE (-6400 4875);
DISPLAY INVISIBLE (-6400 4875);
FORCEPROP 1 LAST WATTAGE 1/16W
J 2
(-6500 4650);
DISPLAY 0.489362 (-6500 4650);
PAINT SKYBLUE (-6500 4650);
DISPLAY INVISIBLE (-6500 4650);
FORCEPROP 1 LAST MATERIAL CHIP
J 2
(-6250 4700);
DISPLAY 0.489362 (-6250 4700);
PAINT SKYBLUE (-6250 4700);
DISPLAY INVISIBLE (-6250 4700);
FORCEPROP 1 LAST TOLERANCE 5%
J 0
(-6550 4700);
DISPLAY 0.489362 (-6550 4700);
PAINT SKYBLUE (-6550 4700);
DISPLAY INVISIBLE (-6550 4700);
FORCEPROP 1 LAST PACK_TYPE 0402LF
J 2
(-6250 4650);
DISPLAY 0.489362 (-6250 4650);
PAINT SKYBLUE (-6250 4650);
DISPLAY INVISIBLE (-6250 4650);
FORCEPROP 1 LAST PATH I107
J 0
(-6475 4875);
DISPLAY 0.978723 (-6475 4875);
PAINT WHITE (-6475 4875);
DISPLAY INVISIBLE (-6475 4875);
FORCEPROP 1 LAST PART_NUMBER CS03302JB10
J 2
(-6325 4775);
DISPLAY 0.489362 (-6325 4775);
PAINT SKYBLUE (-6325 4775);
DISPLAY INVISIBLE (-6325 4775);
FORCEADD Q_RES..1
(-6425 4775);
FORCEPROP 1 LAST LOCATION R219
J 0
(-6300 4775);
DISPLAY 0.489362 (-6300 4775);
PAINT SKYBLUE (-6300 4775);
FORCEPROP 0 LAST $SEC 1
J 2
(-6300 4825);
DISPLAY 0.680851 (-6300 4825);
PAINT MONO (-6300 4825);
DISPLAY INVISIBLE (-6300 4825);
FORCEPROP 0 LAST CDS_SEC 1
J 2
(-6300 4825);
DISPLAY 1.021277 (-6300 4825);
DISPLAY INVISIBLE (-6300 4825);
FORCEPROP 1 LASTPIN (-6525 4775) $PN 1
J 0
(-6513 4787);
DISPLAY 0.489362 (-6513 4787);
PAINT MONO (-6513 4787);
FORCEPROP 1 LASTPIN (-6325 4775) $PN 2
J 0
(-6363 4787);
DISPLAY 0.489362 (-6363 4787);
PAINT MONO (-6363 4787);
FORCEPROP 1 LAST VALUE 33
J 2
(-6550 4775);
DISPLAY 0.489362 (-6550 4775);
PAINT SKYBLUE (-6550 4775);
FORCEPROP 2 LAST CDS_LIB pure_quanta
J 2
(-6425 4775);
DISPLAY INVISIBLE (-6425 4775);
FORCEPROP 2 LAST BOM_COST MEM
J 2
(-6400 4925);
DISPLAY 0.744681 (-6400 4925);
PAINT WHITE (-6400 4925);
DISPLAY INVISIBLE (-6400 4925);
FORCEPROP 1 LAST WATTAGE 1/16W
J 2
(-6500 4700);
DISPLAY 0.489362 (-6500 4700);
PAINT SKYBLUE (-6500 4700);
DISPLAY INVISIBLE (-6500 4700);
FORCEPROP 1 LAST MATERIAL CHIP
J 2
(-6250 4750);
DISPLAY 0.489362 (-6250 4750);
PAINT SKYBLUE (-6250 4750);
DISPLAY INVISIBLE (-6250 4750);
FORCEPROP 1 LAST TOLERANCE 5%
J 0
(-6550 4750);
DISPLAY 0.489362 (-6550 4750);
PAINT SKYBLUE (-6550 4750);
DISPLAY INVISIBLE (-6550 4750);
FORCEPROP 1 LAST PACK_TYPE 0402LF
J 2
(-6250 4700);
DISPLAY 0.489362 (-6250 4700);
PAINT SKYBLUE (-6250 4700);
DISPLAY INVISIBLE (-6250 4700);
FORCEPROP 1 LAST PATH I108
J 0
(-6475 4925);
DISPLAY 0.978723 (-6475 4925);
PAINT WHITE (-6475 4925);
DISPLAY INVISIBLE (-6475 4925);
FORCEPROP 1 LAST PART_NUMBER CS03302JB10
J 2
(-6325 4825);
DISPLAY 0.489362 (-6325 4825);
PAINT SKYBLUE (-6325 4825);
DISPLAY INVISIBLE (-6325 4825);
FORCEADD Q_RES..1
(-6425 4925);
FORCEPROP 1 LAST LOCATION R196
J 0
(-6300 4925);
DISPLAY 0.489362 (-6300 4925);
PAINT SKYBLUE (-6300 4925);
FORCEPROP 0 LAST $SEC 1
J 2
(-6300 4975);
DISPLAY 0.680851 (-6300 4975);
PAINT MONO (-6300 4975);
DISPLAY INVISIBLE (-6300 4975);
FORCEPROP 0 LAST CDS_SEC 1
J 2
(-6300 4975);
DISPLAY 1.021277 (-6300 4975);
DISPLAY INVISIBLE (-6300 4975);
FORCEPROP 1 LASTPIN (-6525 4925) $PN 1
J 0
(-6513 4937);
DISPLAY 0.489362 (-6513 4937);
PAINT MONO (-6513 4937);
FORCEPROP 1 LASTPIN (-6325 4925) $PN 2
J 0
(-6363 4937);
DISPLAY 0.489362 (-6363 4937);
PAINT MONO (-6363 4937);
FORCEPROP 1 LAST VALUE 0
J 2
(-6550 4925);
DISPLAY 0.489362 (-6550 4925);
PAINT SKYBLUE (-6550 4925);
FORCEPROP 2 LAST CDS_LIB pure_quanta
J 2
(-6425 4925);
DISPLAY INVISIBLE (-6425 4925);
FORCEPROP 2 LAST BOM_COST MEM
J 2
(-6400 5075);
DISPLAY 0.744681 (-6400 5075);
PAINT WHITE (-6400 5075);
DISPLAY INVISIBLE (-6400 5075);
FORCEPROP 1 LAST WATTAGE 1/16W
J 2
(-6500 4850);
DISPLAY 0.489362 (-6500 4850);
PAINT SKYBLUE (-6500 4850);
DISPLAY INVISIBLE (-6500 4850);
FORCEPROP 1 LAST MATERIAL CHIP
J 2
(-6250 4900);
DISPLAY 0.489362 (-6250 4900);
PAINT SKYBLUE (-6250 4900);
DISPLAY INVISIBLE (-6250 4900);
FORCEPROP 1 LAST TOLERANCE 5%
J 0
(-6550 4900);
DISPLAY 0.489362 (-6550 4900);
PAINT SKYBLUE (-6550 4900);
DISPLAY INVISIBLE (-6550 4900);
FORCEPROP 1 LAST PACK_TYPE 0402LF
J 2
(-6250 4850);
DISPLAY 0.489362 (-6250 4850);
PAINT SKYBLUE (-6250 4850);
DISPLAY INVISIBLE (-6250 4850);
FORCEPROP 1 LAST PATH I109
J 0
(-6475 5075);
DISPLAY 0.978723 (-6475 5075);
PAINT WHITE (-6475 5075);
DISPLAY INVISIBLE (-6475 5075);
FORCEPROP 1 LAST PART_NUMBER CS00002JB13
J 2
(-6325 4975);
DISPLAY 0.489362 (-6325 4975);
PAINT SKYBLUE (-6325 4975);
DISPLAY INVISIBLE (-6325 4975);
FORCEADD OFFPAGE..5
(-7800 1225);
FORCEPROP 2 LAST $XR0 85 
J 0
(-8024 1225);
DISPLAY 0.638298 (-8024 1225);
PAINT MONO (-8024 1225);
FORCEPROP 2 LAST CDS_LIB standard
J 0
(-7800 1225);
DISPLAY INVISIBLE (-7800 1225);
FORCEPROP 1 LAST OFFPAGE TRUE
J 0
(-7475 1100);
DISPLAY 0.872340 (-7475 1100);
PAINT GREEN (-7475 1100);
DISPLAY INVISIBLE (-7475 1100);
FORCEPROP 1 LAST COMMENT_BODY TRUE
J 0
(-7700 1150);
DISPLAY 0.872340 (-7700 1150);
PAINT GREEN (-7700 1150);
DISPLAY INVISIBLE (-7700 1150);
FORCEPROP 2 LAST PATH I11
J 0
(-8000 1275);
DISPLAY 0.680851 (-8000 1275);
DISPLAY INVISIBLE (-8000 1275);
FORCEADD Q_RES..1
(-6425 4975);
FORCEPROP 1 LAST LOCATION R242
J 0
(-6300 4975);
DISPLAY 0.489362 (-6300 4975);
PAINT SKYBLUE (-6300 4975);
FORCEPROP 0 LAST $SEC 1
J 2
(-6300 5025);
DISPLAY 0.680851 (-6300 5025);
PAINT MONO (-6300 5025);
DISPLAY INVISIBLE (-6300 5025);
FORCEPROP 0 LAST CDS_SEC 1
J 2
(-6300 5025);
DISPLAY 1.021277 (-6300 5025);
DISPLAY INVISIBLE (-6300 5025);
FORCEPROP 1 LASTPIN (-6525 4975) $PN 1
J 0
(-6513 4987);
DISPLAY 0.489362 (-6513 4987);
PAINT MONO (-6513 4987);
FORCEPROP 1 LASTPIN (-6325 4975) $PN 2
J 0
(-6363 4987);
DISPLAY 0.489362 (-6363 4987);
PAINT MONO (-6363 4987);
FORCEPROP 1 LAST VALUE 0
J 2
(-6550 4975);
DISPLAY 0.489362 (-6550 4975);
PAINT SKYBLUE (-6550 4975);
FORCEPROP 2 LAST BOM_COST MEM
J 2
(-6400 5125);
DISPLAY 0.744681 (-6400 5125);
PAINT WHITE (-6400 5125);
DISPLAY INVISIBLE (-6400 5125);
FORCEPROP 2 LAST CDS_LIB pure_quanta
J 2
(-6425 4975);
DISPLAY INVISIBLE (-6425 4975);
FORCEPROP 1 LAST WATTAGE 1/16W
J 2
(-6500 4900);
DISPLAY 0.489362 (-6500 4900);
PAINT SKYBLUE (-6500 4900);
DISPLAY INVISIBLE (-6500 4900);
FORCEPROP 1 LAST MATERIAL CHIP
J 2
(-6250 4950);
DISPLAY 0.489362 (-6250 4950);
PAINT SKYBLUE (-6250 4950);
DISPLAY INVISIBLE (-6250 4950);
FORCEPROP 1 LAST TOLERANCE 5%
J 0
(-6550 4950);
DISPLAY 0.489362 (-6550 4950);
PAINT SKYBLUE (-6550 4950);
DISPLAY INVISIBLE (-6550 4950);
FORCEPROP 1 LAST PACK_TYPE 0402LF
J 2
(-6250 4900);
DISPLAY 0.489362 (-6250 4900);
PAINT SKYBLUE (-6250 4900);
DISPLAY INVISIBLE (-6250 4900);
FORCEPROP 1 LAST PATH I110
J 0
(-6475 5125);
DISPLAY 0.978723 (-6475 5125);
PAINT WHITE (-6475 5125);
DISPLAY INVISIBLE (-6475 5125);
FORCEPROP 1 LAST PART_NUMBER CS00002JB13
J 2
(-6325 5025);
DISPLAY 0.489362 (-6325 5025);
PAINT SKYBLUE (-6325 5025);
DISPLAY INVISIBLE (-6325 5025);
FORCEADD Q_RES..1
(-6425 5025);
FORCEPROP 1 LAST LOCATION R159
J 0
(-6300 5025);
DISPLAY 0.489362 (-6300 5025);
PAINT SKYBLUE (-6300 5025);
FORCEPROP 0 LAST $SEC 1
J 2
(-6300 5075);
DISPLAY 0.680851 (-6300 5075);
PAINT MONO (-6300 5075);
DISPLAY INVISIBLE (-6300 5075);
FORCEPROP 0 LAST CDS_SEC 1
J 2
(-6300 5075);
DISPLAY 1.021277 (-6300 5075);
DISPLAY INVISIBLE (-6300 5075);
FORCEPROP 1 LASTPIN (-6525 5025) $PN 1
J 0
(-6513 5037);
DISPLAY 0.489362 (-6513 5037);
PAINT MONO (-6513 5037);
FORCEPROP 1 LASTPIN (-6325 5025) $PN 2
J 0
(-6363 5037);
DISPLAY 0.489362 (-6363 5037);
PAINT MONO (-6363 5037);
FORCEPROP 1 LAST VALUE 33
J 2
(-6550 5025);
DISPLAY 0.489362 (-6550 5025);
PAINT SKYBLUE (-6550 5025);
FORCEPROP 2 LAST CDS_LIB pure_quanta
J 2
(-6425 5025);
DISPLAY INVISIBLE (-6425 5025);
FORCEPROP 2 LAST BOM_COST MEM
J 2
(-6400 5175);
DISPLAY 0.744681 (-6400 5175);
PAINT WHITE (-6400 5175);
DISPLAY INVISIBLE (-6400 5175);
FORCEPROP 1 LAST WATTAGE 1/16W
J 2
(-6500 4950);
DISPLAY 0.489362 (-6500 4950);
PAINT SKYBLUE (-6500 4950);
DISPLAY INVISIBLE (-6500 4950);
FORCEPROP 1 LAST MATERIAL CHIP
J 2
(-6250 5000);
DISPLAY 0.489362 (-6250 5000);
PAINT SKYBLUE (-6250 5000);
DISPLAY INVISIBLE (-6250 5000);
FORCEPROP 1 LAST TOLERANCE 5%
J 0
(-6550 5000);
DISPLAY 0.489362 (-6550 5000);
PAINT SKYBLUE (-6550 5000);
DISPLAY INVISIBLE (-6550 5000);
FORCEPROP 1 LAST PACK_TYPE 0402LF
J 2
(-6250 4950);
DISPLAY 0.489362 (-6250 4950);
PAINT SKYBLUE (-6250 4950);
DISPLAY INVISIBLE (-6250 4950);
FORCEPROP 1 LAST PATH I111
J 0
(-6475 5175);
DISPLAY 0.978723 (-6475 5175);
PAINT WHITE (-6475 5175);
DISPLAY INVISIBLE (-6475 5175);
FORCEPROP 1 LAST PART_NUMBER CS03302JB10
J 2
(-6325 5075);
DISPLAY 0.489362 (-6325 5075);
PAINT SKYBLUE (-6325 5075);
DISPLAY INVISIBLE (-6325 5075);
FORCEADD Q_RES..1
(-6425 5075);
FORCEPROP 1 LAST LOCATION R463
J 0
(-6300 5075);
DISPLAY 0.489362 (-6300 5075);
PAINT SKYBLUE (-6300 5075);
FORCEPROP 0 LAST $SEC 1
J 0
(-6300 5100);
DISPLAY 0.680851 (-6300 5100);
PAINT MONO (-6300 5100);
DISPLAY INVISIBLE (-6300 5100);
FORCEPROP 0 LAST CDS_SEC 1
J 0
(-6300 5100);
DISPLAY 1.021277 (-6300 5100);
DISPLAY INVISIBLE (-6300 5100);
FORCEPROP 1 LASTPIN (-6525 5075) $PN 1
J 0
(-6513 5087);
DISPLAY 0.489362 (-6513 5087);
PAINT MONO (-6513 5087);
FORCEPROP 1 LASTPIN (-6325 5075) $PN 2
J 0
(-6363 5087);
DISPLAY 0.489362 (-6363 5087);
PAINT MONO (-6363 5087);
FORCEPROP 1 LAST VALUE 33
J 2
(-6525 5075);
DISPLAY 0.489362 (-6525 5075);
PAINT SKYBLUE (-6525 5075);
FORCEPROP 2 LAST CDS_LIB pure_quanta
J 0
(-6425 5075);
DISPLAY INVISIBLE (-6425 5075);
FORCEPROP 1 LAST WATTAGE 1/16W
J 2
(-6025 5000);
DISPLAY 0.489362 (-6025 5000);
PAINT SKYBLUE (-6025 5000);
DISPLAY INVISIBLE (-6025 5000);
FORCEPROP 1 LAST MATERIAL CHIP
J 0
(-6000 5000);
DISPLAY 0.489362 (-6000 5000);
PAINT SKYBLUE (-6000 5000);
DISPLAY INVISIBLE (-6000 5000);
FORCEPROP 1 LAST TOLERANCE 5%
J 0
(-6450 5000);
DISPLAY 0.489362 (-6450 5000);
PAINT SKYBLUE (-6450 5000);
DISPLAY INVISIBLE (-6450 5000);
FORCEPROP 1 LAST PACK_TYPE 0402LF
J 0
(-6375 5000);
DISPLAY 0.489362 (-6375 5000);
PAINT SKYBLUE (-6375 5000);
DISPLAY INVISIBLE (-6375 5000);
FORCEPROP 1 LAST PATH I112
J 0
(-6475 5225);
DISPLAY 0.978723 (-6475 5225);
PAINT WHITE (-6475 5225);
DISPLAY INVISIBLE (-6475 5225);
FORCEPROP 1 LAST PART_NUMBER CS03302JB10
J 0
(-6400 5125);
DISPLAY 0.489362 (-6400 5125);
PAINT SKYBLUE (-6400 5125);
DISPLAY INVISIBLE (-6400 5125);
FORCEADD Q_RES..1
(-6425 5125);
FORCEPROP 1 LAST LOCATION R57
J 0
(-6300 5125);
DISPLAY 0.489362 (-6300 5125);
PAINT SKYBLUE (-6300 5125);
FORCEPROP 0 LAST $SEC 1
J 0
(-6275 5175);
DISPLAY 0.680851 (-6275 5175);
PAINT MONO (-6275 5175);
DISPLAY INVISIBLE (-6275 5175);
FORCEPROP 0 LAST CDS_SEC 1
J 0
(-6275 5175);
DISPLAY 1.021277 (-6275 5175);
DISPLAY INVISIBLE (-6275 5175);
FORCEPROP 1 LASTPIN (-6525 5125) $PN 1
J 0
(-6513 5137);
DISPLAY 0.489362 (-6513 5137);
PAINT MONO (-6513 5137);
FORCEPROP 1 LASTPIN (-6325 5125) $PN 2
J 0
(-6363 5137);
DISPLAY 0.489362 (-6363 5137);
PAINT MONO (-6363 5137);
FORCEPROP 1 LAST VALUE 0
J 2
(-6550 5125);
DISPLAY 0.489362 (-6550 5125);
PAINT SKYBLUE (-6550 5125);
FORCEPROP 2 LAST CDS_LIB pure_quanta
J 0
(-6425 5125);
DISPLAY INVISIBLE (-6425 5125);
FORCEPROP 2 LAST BOM_COST MEM
J 2
(-6400 5275);
DISPLAY 0.744681 (-6400 5275);
PAINT WHITE (-6400 5275);
DISPLAY INVISIBLE (-6400 5275);
FORCEPROP 1 LAST WATTAGE 1/16W
J 2
(-6500 5050);
DISPLAY 0.489362 (-6500 5050);
PAINT SKYBLUE (-6500 5050);
DISPLAY INVISIBLE (-6500 5050);
FORCEPROP 1 LAST MATERIAL CHIP
J 2
(-6250 5100);
DISPLAY 0.489362 (-6250 5100);
PAINT SKYBLUE (-6250 5100);
DISPLAY INVISIBLE (-6250 5100);
FORCEPROP 1 LAST TOLERANCE 5%
J 0
(-6550 5100);
DISPLAY 0.489362 (-6550 5100);
PAINT SKYBLUE (-6550 5100);
DISPLAY INVISIBLE (-6550 5100);
FORCEPROP 1 LAST PACK_TYPE 0402LF
J 2
(-6250 5050);
DISPLAY 0.489362 (-6250 5050);
PAINT SKYBLUE (-6250 5050);
DISPLAY INVISIBLE (-6250 5050);
FORCEPROP 1 LAST PATH I113
J 0
(-6475 5275);
DISPLAY 0.978723 (-6475 5275);
PAINT WHITE (-6475 5275);
DISPLAY INVISIBLE (-6475 5275);
FORCEPROP 1 LAST PART_NUMBER CS00002JB13
J 2
(-6325 5175);
DISPLAY 0.489362 (-6325 5175);
PAINT SKYBLUE (-6325 5175);
DISPLAY INVISIBLE (-6325 5175);
FORCEADD Q_RES..1
(-6425 5175);
FORCEPROP 1 LAST LOCATION R241
J 0
(-6300 5175);
DISPLAY 0.489362 (-6300 5175);
PAINT SKYBLUE (-6300 5175);
FORCEPROP 0 LAST $SEC 1
J 2
(-6300 5225);
DISPLAY 0.680851 (-6300 5225);
PAINT MONO (-6300 5225);
DISPLAY INVISIBLE (-6300 5225);
FORCEPROP 0 LAST CDS_SEC 1
J 2
(-6300 5225);
DISPLAY 1.021277 (-6300 5225);
DISPLAY INVISIBLE (-6300 5225);
FORCEPROP 1 LASTPIN (-6525 5175) $PN 1
J 0
(-6513 5187);
DISPLAY 0.489362 (-6513 5187);
PAINT MONO (-6513 5187);
FORCEPROP 1 LASTPIN (-6325 5175) $PN 2
J 0
(-6363 5187);
DISPLAY 0.489362 (-6363 5187);
PAINT MONO (-6363 5187);
FORCEPROP 1 LAST VALUE 0
J 2
(-6550 5175);
DISPLAY 0.489362 (-6550 5175);
PAINT SKYBLUE (-6550 5175);
FORCEPROP 2 LAST BOM_COST MEM
J 2
(-6400 5325);
DISPLAY 0.744681 (-6400 5325);
PAINT WHITE (-6400 5325);
DISPLAY INVISIBLE (-6400 5325);
FORCEPROP 2 LAST CDS_LIB pure_quanta
J 2
(-6425 5175);
DISPLAY INVISIBLE (-6425 5175);
FORCEPROP 1 LAST WATTAGE 1/16W
J 2
(-6500 5100);
DISPLAY 0.489362 (-6500 5100);
PAINT SKYBLUE (-6500 5100);
DISPLAY INVISIBLE (-6500 5100);
FORCEPROP 1 LAST MATERIAL CHIP
J 2
(-6250 5150);
DISPLAY 0.489362 (-6250 5150);
PAINT SKYBLUE (-6250 5150);
DISPLAY INVISIBLE (-6250 5150);
FORCEPROP 1 LAST TOLERANCE 5%
J 0
(-6550 5150);
DISPLAY 0.489362 (-6550 5150);
PAINT SKYBLUE (-6550 5150);
DISPLAY INVISIBLE (-6550 5150);
FORCEPROP 1 LAST PACK_TYPE 0402LF
J 2
(-6250 5100);
DISPLAY 0.489362 (-6250 5100);
PAINT SKYBLUE (-6250 5100);
DISPLAY INVISIBLE (-6250 5100);
FORCEPROP 1 LAST PATH I114
J 0
(-6475 5325);
DISPLAY 0.978723 (-6475 5325);
PAINT WHITE (-6475 5325);
DISPLAY INVISIBLE (-6475 5325);
FORCEPROP 1 LAST PART_NUMBER CS00002JB13
J 2
(-6325 5225);
DISPLAY 0.489362 (-6325 5225);
PAINT SKYBLUE (-6325 5225);
DISPLAY INVISIBLE (-6325 5225);
FORCEADD Q_RES..1
(-6425 5375);
FORCEPROP 1 LAST LOCATION R272
J 0
(-6300 5375);
DISPLAY 0.489362 (-6300 5375);
PAINT SKYBLUE (-6300 5375);
FORCEPROP 0 LAST $SEC 1
J 2
(-6300 5425);
DISPLAY 0.680851 (-6300 5425);
PAINT MONO (-6300 5425);
DISPLAY INVISIBLE (-6300 5425);
FORCEPROP 0 LAST CDS_SEC 1
J 2
(-6300 5425);
DISPLAY 1.021277 (-6300 5425);
DISPLAY INVISIBLE (-6300 5425);
FORCEPROP 1 LASTPIN (-6525 5375) $PN 1
J 0
(-6513 5387);
DISPLAY 0.489362 (-6513 5387);
PAINT MONO (-6513 5387);
FORCEPROP 1 LASTPIN (-6325 5375) $PN 2
J 0
(-6363 5387);
DISPLAY 0.489362 (-6363 5387);
PAINT MONO (-6363 5387);
FORCEPROP 1 LAST VALUE 0
J 2
(-6550 5375);
DISPLAY 0.489362 (-6550 5375);
PAINT SKYBLUE (-6550 5375);
FORCEPROP 1 LAST MATERIAL EMPTY
J 2
(-6600 5375);
DISPLAY 0.489362 (-6600 5375);
PAINT RED (-6600 5375);
FORCEPROP 2 LAST CDS_LIB pure_quanta
J 2
(-6425 5375);
DISPLAY INVISIBLE (-6425 5375);
FORCEPROP 2 LAST BOM_COST MEM
J 2
(-6400 5525);
DISPLAY 0.744681 (-6400 5525);
PAINT WHITE (-6400 5525);
DISPLAY INVISIBLE (-6400 5525);
FORCEPROP 1 LAST WATTAGE 1/16W
J 2
(-6500 5300);
DISPLAY 0.489362 (-6500 5300);
PAINT SKYBLUE (-6500 5300);
DISPLAY INVISIBLE (-6500 5300);
FORCEPROP 1 LAST TOLERANCE 5%
J 0
(-6550 5350);
DISPLAY 0.489362 (-6550 5350);
PAINT SKYBLUE (-6550 5350);
DISPLAY INVISIBLE (-6550 5350);
FORCEPROP 1 LAST PACK_TYPE 0402LF
J 2
(-6250 5300);
DISPLAY 0.489362 (-6250 5300);
PAINT SKYBLUE (-6250 5300);
DISPLAY INVISIBLE (-6250 5300);
FORCEPROP 1 LAST PATH I115
J 0
(-6475 5525);
DISPLAY 0.978723 (-6475 5525);
PAINT WHITE (-6475 5525);
DISPLAY INVISIBLE (-6475 5525);
FORCEPROP 1 LAST PART_NUMBER CS00002JB13
J 2
(-6325 5425);
DISPLAY 0.489362 (-6325 5425);
PAINT SKYBLUE (-6325 5425);
DISPLAY INVISIBLE (-6325 5425);
FORCEADD Q_RES..1
(-6425 5325);
FORCEPROP 1 LAST LOCATION R253
J 0
(-6300 5325);
DISPLAY 0.489362 (-6300 5325);
PAINT SKYBLUE (-6300 5325);
FORCEPROP 0 LAST $SEC 1
J 2
(-6300 5375);
DISPLAY 0.680851 (-6300 5375);
PAINT MONO (-6300 5375);
DISPLAY INVISIBLE (-6300 5375);
FORCEPROP 0 LAST CDS_SEC 1
J 2
(-6300 5375);
DISPLAY 1.021277 (-6300 5375);
DISPLAY INVISIBLE (-6300 5375);
FORCEPROP 1 LASTPIN (-6525 5325) $PN 1
J 0
(-6513 5337);
DISPLAY 0.489362 (-6513 5337);
PAINT MONO (-6513 5337);
FORCEPROP 1 LASTPIN (-6325 5325) $PN 2
J 0
(-6363 5337);
DISPLAY 0.489362 (-6363 5337);
PAINT MONO (-6363 5337);
FORCEPROP 1 LAST VALUE 0
J 2
(-6550 5325);
DISPLAY 0.489362 (-6550 5325);
PAINT SKYBLUE (-6550 5325);
FORCEPROP 2 LAST BOM_COST MEM
J 2
(-6400 5475);
DISPLAY 0.744681 (-6400 5475);
PAINT WHITE (-6400 5475);
DISPLAY INVISIBLE (-6400 5475);
FORCEPROP 2 LAST CDS_LIB pure_quanta
J 2
(-6425 5325);
DISPLAY INVISIBLE (-6425 5325);
FORCEPROP 1 LAST WATTAGE 1/16W
J 2
(-6500 5250);
DISPLAY 0.489362 (-6500 5250);
PAINT SKYBLUE (-6500 5250);
DISPLAY INVISIBLE (-6500 5250);
FORCEPROP 1 LAST MATERIAL CHIP
J 2
(-6250 5300);
DISPLAY 0.489362 (-6250 5300);
PAINT SKYBLUE (-6250 5300);
DISPLAY INVISIBLE (-6250 5300);
FORCEPROP 1 LAST TOLERANCE 5%
J 0
(-6550 5300);
DISPLAY 0.489362 (-6550 5300);
PAINT SKYBLUE (-6550 5300);
DISPLAY INVISIBLE (-6550 5300);
FORCEPROP 1 LAST PACK_TYPE 0402LF
J 2
(-6250 5250);
DISPLAY 0.489362 (-6250 5250);
PAINT SKYBLUE (-6250 5250);
DISPLAY INVISIBLE (-6250 5250);
FORCEPROP 1 LAST PATH I116
J 0
(-6475 5475);
DISPLAY 0.978723 (-6475 5475);
PAINT WHITE (-6475 5475);
DISPLAY INVISIBLE (-6475 5475);
FORCEPROP 1 LAST PART_NUMBER CS00002JB13
J 2
(-6325 5375);
DISPLAY 0.489362 (-6325 5375);
PAINT SKYBLUE (-6325 5375);
DISPLAY INVISIBLE (-6325 5375);
FORCEADD Q_RES..1
(-6425 5425);
FORCEPROP 1 LAST LOCATION R216
J 0
(-6300 5425);
DISPLAY 0.489362 (-6300 5425);
PAINT SKYBLUE (-6300 5425);
FORCEPROP 0 LAST $SEC 1
J 2
(-6300 5475);
DISPLAY 0.680851 (-6300 5475);
PAINT MONO (-6300 5475);
DISPLAY INVISIBLE (-6300 5475);
FORCEPROP 0 LAST CDS_SEC 1
J 2
(-6300 5475);
DISPLAY 1.021277 (-6300 5475);
DISPLAY INVISIBLE (-6300 5475);
FORCEPROP 1 LASTPIN (-6525 5425) $PN 1
J 0
(-6513 5437);
DISPLAY 0.489362 (-6513 5437);
PAINT MONO (-6513 5437);
FORCEPROP 1 LASTPIN (-6325 5425) $PN 2
J 0
(-6363 5437);
DISPLAY 0.489362 (-6363 5437);
PAINT MONO (-6363 5437);
FORCEPROP 1 LAST VALUE 33
J 2
(-6550 5425);
DISPLAY 0.489362 (-6550 5425);
PAINT SKYBLUE (-6550 5425);
FORCEPROP 2 LAST BOM_COST MEM
J 2
(-6400 5575);
DISPLAY 0.744681 (-6400 5575);
PAINT WHITE (-6400 5575);
DISPLAY INVISIBLE (-6400 5575);
FORCEPROP 2 LAST CDS_LIB pure_quanta
J 2
(-6425 5425);
DISPLAY INVISIBLE (-6425 5425);
FORCEPROP 1 LAST WATTAGE 1/16W
J 2
(-6500 5350);
DISPLAY 0.489362 (-6500 5350);
PAINT SKYBLUE (-6500 5350);
DISPLAY INVISIBLE (-6500 5350);
FORCEPROP 1 LAST MATERIAL CHIP
J 2
(-6250 5400);
DISPLAY 0.489362 (-6250 5400);
PAINT SKYBLUE (-6250 5400);
DISPLAY INVISIBLE (-6250 5400);
FORCEPROP 1 LAST TOLERANCE 5%
J 0
(-6550 5400);
DISPLAY 0.489362 (-6550 5400);
PAINT SKYBLUE (-6550 5400);
DISPLAY INVISIBLE (-6550 5400);
FORCEPROP 1 LAST PACK_TYPE 0402LF
J 2
(-6250 5350);
DISPLAY 0.489362 (-6250 5350);
PAINT SKYBLUE (-6250 5350);
DISPLAY INVISIBLE (-6250 5350);
FORCEPROP 1 LAST PATH I117
J 0
(-6475 5575);
DISPLAY 0.978723 (-6475 5575);
PAINT WHITE (-6475 5575);
DISPLAY INVISIBLE (-6475 5575);
FORCEPROP 1 LAST PART_NUMBER CS03302JB10
J 2
(-6325 5475);
DISPLAY 0.489362 (-6325 5475);
PAINT SKYBLUE (-6325 5475);
DISPLAY INVISIBLE (-6325 5475);
FORCEADD Q_RES..1
(-6425 5525);
FORCEPROP 1 LAST LOCATION R217
J 0
(-6300 5525);
DISPLAY 0.489362 (-6300 5525);
PAINT SKYBLUE (-6300 5525);
FORCEPROP 0 LAST $SEC 1
J 2
(-6300 5575);
DISPLAY 0.680851 (-6300 5575);
PAINT MONO (-6300 5575);
DISPLAY INVISIBLE (-6300 5575);
FORCEPROP 0 LAST CDS_SEC 1
J 2
(-6300 5575);
DISPLAY 1.021277 (-6300 5575);
DISPLAY INVISIBLE (-6300 5575);
FORCEPROP 1 LASTPIN (-6525 5525) $PN 1
J 0
(-6513 5537);
DISPLAY 0.489362 (-6513 5537);
PAINT MONO (-6513 5537);
FORCEPROP 1 LASTPIN (-6325 5525) $PN 2
J 0
(-6363 5537);
DISPLAY 0.489362 (-6363 5537);
PAINT MONO (-6363 5537);
FORCEPROP 1 LAST VALUE 33
J 2
(-6550 5525);
DISPLAY 0.489362 (-6550 5525);
PAINT SKYBLUE (-6550 5525);
FORCEPROP 2 LAST BOM_COST MEM
J 2
(-6400 5675);
DISPLAY 0.744681 (-6400 5675);
PAINT WHITE (-6400 5675);
DISPLAY INVISIBLE (-6400 5675);
FORCEPROP 2 LAST CDS_LIB pure_quanta
J 2
(-6425 5525);
DISPLAY INVISIBLE (-6425 5525);
FORCEPROP 1 LAST WATTAGE 1/16W
J 2
(-6500 5450);
DISPLAY 0.489362 (-6500 5450);
PAINT SKYBLUE (-6500 5450);
DISPLAY INVISIBLE (-6500 5450);
FORCEPROP 1 LAST MATERIAL CHIP
J 2
(-6250 5500);
DISPLAY 0.489362 (-6250 5500);
PAINT SKYBLUE (-6250 5500);
DISPLAY INVISIBLE (-6250 5500);
FORCEPROP 1 LAST TOLERANCE 5%
J 0
(-6550 5500);
DISPLAY 0.489362 (-6550 5500);
PAINT SKYBLUE (-6550 5500);
DISPLAY INVISIBLE (-6550 5500);
FORCEPROP 1 LAST PACK_TYPE 0402LF
J 2
(-6250 5450);
DISPLAY 0.489362 (-6250 5450);
PAINT SKYBLUE (-6250 5450);
DISPLAY INVISIBLE (-6250 5450);
FORCEPROP 1 LAST PATH I118
J 0
(-6475 5675);
DISPLAY 0.978723 (-6475 5675);
PAINT WHITE (-6475 5675);
DISPLAY INVISIBLE (-6475 5675);
FORCEPROP 1 LAST PART_NUMBER CS03302JB10
J 2
(-6325 5575);
DISPLAY 0.489362 (-6325 5575);
PAINT SKYBLUE (-6325 5575);
DISPLAY INVISIBLE (-6325 5575);
FORCEADD Q_RES..1
(-6425 5575);
FORCEPROP 1 LAST LOCATION R273
J 0
(-6300 5575);
DISPLAY 0.489362 (-6300 5575);
PAINT SKYBLUE (-6300 5575);
FORCEPROP 0 LAST $SEC 1
J 2
(-6300 5625);
DISPLAY 0.680851 (-6300 5625);
PAINT MONO (-6300 5625);
DISPLAY INVISIBLE (-6300 5625);
FORCEPROP 0 LAST CDS_SEC 1
J 2
(-6300 5625);
DISPLAY 1.021277 (-6300 5625);
DISPLAY INVISIBLE (-6300 5625);
FORCEPROP 1 LASTPIN (-6525 5575) $PN 1
J 0
(-6513 5587);
DISPLAY 0.489362 (-6513 5587);
PAINT MONO (-6513 5587);
FORCEPROP 1 LASTPIN (-6325 5575) $PN 2
J 0
(-6363 5587);
DISPLAY 0.489362 (-6363 5587);
PAINT MONO (-6363 5587);
FORCEPROP 1 LAST VALUE 33
J 2
(-6550 5575);
DISPLAY 0.489362 (-6550 5575);
PAINT SKYBLUE (-6550 5575);
FORCEPROP 2 LAST BOM_COST MEM
J 2
(-6400 5725);
DISPLAY 0.744681 (-6400 5725);
PAINT WHITE (-6400 5725);
DISPLAY INVISIBLE (-6400 5725);
FORCEPROP 2 LAST CDS_LIB pure_quanta
J 2
(-6425 5575);
DISPLAY INVISIBLE (-6425 5575);
FORCEPROP 1 LAST WATTAGE 1/16W
J 2
(-6500 5500);
DISPLAY 0.489362 (-6500 5500);
PAINT SKYBLUE (-6500 5500);
DISPLAY INVISIBLE (-6500 5500);
FORCEPROP 1 LAST MATERIAL CHIP
J 2
(-6250 5550);
DISPLAY 0.489362 (-6250 5550);
PAINT SKYBLUE (-6250 5550);
DISPLAY INVISIBLE (-6250 5550);
FORCEPROP 1 LAST TOLERANCE 5%
J 0
(-6550 5550);
DISPLAY 0.489362 (-6550 5550);
PAINT SKYBLUE (-6550 5550);
DISPLAY INVISIBLE (-6550 5550);
FORCEPROP 1 LAST PACK_TYPE 0402LF
J 2
(-6250 5500);
DISPLAY 0.489362 (-6250 5500);
PAINT SKYBLUE (-6250 5500);
DISPLAY INVISIBLE (-6250 5500);
FORCEPROP 1 LAST PATH I119
J 0
(-6475 5725);
DISPLAY 0.978723 (-6475 5725);
PAINT WHITE (-6475 5725);
DISPLAY INVISIBLE (-6475 5725);
FORCEPROP 1 LAST PART_NUMBER CS03302JB10
J 2
(-6325 5625);
DISPLAY 0.489362 (-6325 5625);
PAINT SKYBLUE (-6325 5625);
DISPLAY INVISIBLE (-6325 5625);
FORCEADD OFFPAGE..5
(-7800 1075);
FORCEPROP 2 LAST $XR0 85 
J 0
(-8024 1075);
DISPLAY 0.638298 (-8024 1075);
PAINT MONO (-8024 1075);
FORCEPROP 2 LAST CDS_LIB standard
J 0
(-7800 1075);
DISPLAY INVISIBLE (-7800 1075);
FORCEPROP 1 LAST OFFPAGE TRUE
J 0
(-7475 950);
DISPLAY 0.872340 (-7475 950);
PAINT GREEN (-7475 950);
DISPLAY INVISIBLE (-7475 950);
FORCEPROP 1 LAST COMMENT_BODY TRUE
J 0
(-7700 1000);
DISPLAY 0.872340 (-7700 1000);
PAINT GREEN (-7700 1000);
DISPLAY INVISIBLE (-7700 1000);
FORCEPROP 2 LAST PATH I12
J 0
(-8000 1125);
DISPLAY 0.680851 (-8000 1125);
DISPLAY INVISIBLE (-8000 1125);
FORCEADD Q_RES..1
(-6425 5675);
FORCEPROP 1 LAST LOCATION R197
J 0
(-6300 5675);
DISPLAY 0.489362 (-6300 5675);
PAINT SKYBLUE (-6300 5675);
FORCEPROP 0 LAST $SEC 1
J 2
(-6300 5725);
DISPLAY 0.680851 (-6300 5725);
PAINT MONO (-6300 5725);
DISPLAY INVISIBLE (-6300 5725);
FORCEPROP 0 LAST CDS_SEC 1
J 2
(-6300 5725);
DISPLAY 1.021277 (-6300 5725);
DISPLAY INVISIBLE (-6300 5725);
FORCEPROP 1 LASTPIN (-6525 5675) $PN 1
J 0
(-6513 5687);
DISPLAY 0.489362 (-6513 5687);
PAINT MONO (-6513 5687);
FORCEPROP 1 LASTPIN (-6325 5675) $PN 2
J 0
(-6363 5687);
DISPLAY 0.489362 (-6363 5687);
PAINT MONO (-6363 5687);
FORCEPROP 1 LAST VALUE 0
J 2
(-6550 5675);
DISPLAY 0.489362 (-6550 5675);
PAINT SKYBLUE (-6550 5675);
FORCEPROP 2 LAST CDS_LIB pure_quanta
J 2
(-6425 5675);
DISPLAY INVISIBLE (-6425 5675);
FORCEPROP 2 LAST BOM_COST MEM
J 2
(-6400 5825);
DISPLAY 0.744681 (-6400 5825);
PAINT WHITE (-6400 5825);
DISPLAY INVISIBLE (-6400 5825);
FORCEPROP 1 LAST WATTAGE 1/16W
J 2
(-6500 5600);
DISPLAY 0.489362 (-6500 5600);
PAINT SKYBLUE (-6500 5600);
DISPLAY INVISIBLE (-6500 5600);
FORCEPROP 1 LAST MATERIAL CHIP
J 2
(-6250 5650);
DISPLAY 0.489362 (-6250 5650);
PAINT SKYBLUE (-6250 5650);
DISPLAY INVISIBLE (-6250 5650);
FORCEPROP 1 LAST TOLERANCE 5%
J 0
(-6550 5650);
DISPLAY 0.489362 (-6550 5650);
PAINT SKYBLUE (-6550 5650);
DISPLAY INVISIBLE (-6550 5650);
FORCEPROP 1 LAST PACK_TYPE 0402LF
J 2
(-6250 5600);
DISPLAY 0.489362 (-6250 5600);
PAINT SKYBLUE (-6250 5600);
DISPLAY INVISIBLE (-6250 5600);
FORCEPROP 1 LAST PATH I120
J 0
(-6475 5825);
DISPLAY 0.978723 (-6475 5825);
PAINT WHITE (-6475 5825);
DISPLAY INVISIBLE (-6475 5825);
FORCEPROP 1 LAST PART_NUMBER CS00002JB13
J 2
(-6325 5725);
DISPLAY 0.489362 (-6325 5725);
PAINT SKYBLUE (-6325 5725);
DISPLAY INVISIBLE (-6325 5725);
FORCEADD Q_RES..1
(-6425 5825);
FORCEPROP 1 LAST LOCATION R255
J 0
(-6300 5825);
DISPLAY 0.489362 (-6300 5825);
PAINT SKYBLUE (-6300 5825);
FORCEPROP 0 LAST $SEC 1
J 2
(-6300 5875);
DISPLAY 0.680851 (-6300 5875);
PAINT MONO (-6300 5875);
DISPLAY INVISIBLE (-6300 5875);
FORCEPROP 0 LAST CDS_SEC 1
J 2
(-6300 5875);
DISPLAY 1.021277 (-6300 5875);
DISPLAY INVISIBLE (-6300 5875);
FORCEPROP 1 LASTPIN (-6525 5825) $PN 1
J 0
(-6513 5837);
DISPLAY 0.489362 (-6513 5837);
PAINT MONO (-6513 5837);
FORCEPROP 1 LASTPIN (-6325 5825) $PN 2
J 0
(-6363 5837);
DISPLAY 0.489362 (-6363 5837);
PAINT MONO (-6363 5837);
FORCEPROP 1 LAST VALUE 0
J 2
(-6550 5825);
DISPLAY 0.489362 (-6550 5825);
PAINT SKYBLUE (-6550 5825);
FORCEPROP 2 LAST CDS_LIB pure_quanta
J 2
(-6425 5825);
DISPLAY INVISIBLE (-6425 5825);
FORCEPROP 1 LAST PACK_TYPE 0402LF
J 2
(-6250 5750);
DISPLAY 0.489362 (-6250 5750);
PAINT SKYBLUE (-6250 5750);
DISPLAY INVISIBLE (-6250 5750);
FORCEPROP 1 LAST TOLERANCE 5%
J 0
(-6550 5800);
DISPLAY 0.489362 (-6550 5800);
PAINT SKYBLUE (-6550 5800);
DISPLAY INVISIBLE (-6550 5800);
FORCEPROP 1 LAST MATERIAL CHIP
J 2
(-6250 5800);
DISPLAY 0.489362 (-6250 5800);
PAINT SKYBLUE (-6250 5800);
DISPLAY INVISIBLE (-6250 5800);
FORCEPROP 1 LAST WATTAGE 1/16W
J 2
(-6500 5750);
DISPLAY 0.489362 (-6500 5750);
PAINT SKYBLUE (-6500 5750);
DISPLAY INVISIBLE (-6500 5750);
FORCEPROP 2 LAST BOM_COST MEM
J 2
(-6400 5975);
DISPLAY 0.744681 (-6400 5975);
PAINT WHITE (-6400 5975);
DISPLAY INVISIBLE (-6400 5975);
FORCEPROP 1 LAST PATH I121
J 0
(-6475 5975);
DISPLAY 0.978723 (-6475 5975);
PAINT WHITE (-6475 5975);
DISPLAY INVISIBLE (-6475 5975);
FORCEPROP 1 LAST PART_NUMBER CS00002JB13
J 2
(-6325 5875);
DISPLAY 0.489362 (-6325 5875);
PAINT SKYBLUE (-6325 5875);
DISPLAY INVISIBLE (-6325 5875);
FORCEADD Q_RES..1
(-6425 6025);
FORCEPROP 1 LAST LOCATION R198
J 0
(-6300 6025);
DISPLAY 0.489362 (-6300 6025);
PAINT SKYBLUE (-6300 6025);
FORCEPROP 0 LAST $SEC 1
J 2
(-6300 6075);
DISPLAY 0.680851 (-6300 6075);
PAINT MONO (-6300 6075);
DISPLAY INVISIBLE (-6300 6075);
FORCEPROP 0 LAST CDS_SEC 1
J 2
(-6300 6075);
DISPLAY 1.021277 (-6300 6075);
DISPLAY INVISIBLE (-6300 6075);
FORCEPROP 1 LASTPIN (-6525 6025) $PN 1
J 0
(-6513 6037);
DISPLAY 0.489362 (-6513 6037);
PAINT MONO (-6513 6037);
FORCEPROP 1 LASTPIN (-6325 6025) $PN 2
J 0
(-6363 6037);
DISPLAY 0.489362 (-6363 6037);
PAINT MONO (-6363 6037);
FORCEPROP 1 LAST VALUE 0
J 2
(-6550 6025);
DISPLAY 0.489362 (-6550 6025);
PAINT SKYBLUE (-6550 6025);
FORCEPROP 2 LAST CDS_LIB pure_quanta
J 2
(-6425 6025);
DISPLAY INVISIBLE (-6425 6025);
FORCEPROP 2 LAST BOM_COST MEM
J 2
(-6400 6175);
DISPLAY 0.744681 (-6400 6175);
PAINT WHITE (-6400 6175);
DISPLAY INVISIBLE (-6400 6175);
FORCEPROP 1 LAST WATTAGE 1/16W
J 2
(-6500 5950);
DISPLAY 0.489362 (-6500 5950);
PAINT SKYBLUE (-6500 5950);
DISPLAY INVISIBLE (-6500 5950);
FORCEPROP 1 LAST MATERIAL CHIP
J 2
(-6250 6000);
DISPLAY 0.489362 (-6250 6000);
PAINT SKYBLUE (-6250 6000);
DISPLAY INVISIBLE (-6250 6000);
FORCEPROP 1 LAST TOLERANCE 5%
J 0
(-6550 6000);
DISPLAY 0.489362 (-6550 6000);
PAINT SKYBLUE (-6550 6000);
DISPLAY INVISIBLE (-6550 6000);
FORCEPROP 1 LAST PACK_TYPE 0402LF
J 2
(-6250 5950);
DISPLAY 0.489362 (-6250 5950);
PAINT SKYBLUE (-6250 5950);
DISPLAY INVISIBLE (-6250 5950);
FORCEPROP 1 LAST PATH I122
J 0
(-6475 6175);
DISPLAY 0.978723 (-6475 6175);
PAINT WHITE (-6475 6175);
DISPLAY INVISIBLE (-6475 6175);
FORCEPROP 1 LAST PART_NUMBER CS00002JB13
J 2
(-6325 6075);
DISPLAY 0.489362 (-6325 6075);
PAINT SKYBLUE (-6325 6075);
DISPLAY INVISIBLE (-6325 6075);
FORCEADD Q_RES..1
(-6425 6075);
FORCEPROP 1 LAST LOCATION R254
J 0
(-6300 6075);
DISPLAY 0.489362 (-6300 6075);
PAINT SKYBLUE (-6300 6075);
FORCEPROP 0 LAST $SEC 1
J 2
(-6300 6125);
DISPLAY 0.680851 (-6300 6125);
PAINT MONO (-6300 6125);
DISPLAY INVISIBLE (-6300 6125);
FORCEPROP 0 LAST CDS_SEC 1
J 2
(-6300 6125);
DISPLAY 1.021277 (-6300 6125);
DISPLAY INVISIBLE (-6300 6125);
FORCEPROP 1 LASTPIN (-6525 6075) $PN 1
J 0
(-6513 6087);
DISPLAY 0.489362 (-6513 6087);
PAINT MONO (-6513 6087);
FORCEPROP 1 LASTPIN (-6325 6075) $PN 2
J 0
(-6363 6087);
DISPLAY 0.489362 (-6363 6087);
PAINT MONO (-6363 6087);
FORCEPROP 1 LAST VALUE 0
J 2
(-6550 6075);
DISPLAY 0.489362 (-6550 6075);
PAINT SKYBLUE (-6550 6075);
FORCEPROP 2 LAST CDS_LIB pure_quanta
J 2
(-6425 6075);
DISPLAY INVISIBLE (-6425 6075);
FORCEPROP 2 LAST BOM_COST MEM
J 2
(-6400 6225);
DISPLAY 0.744681 (-6400 6225);
PAINT WHITE (-6400 6225);
DISPLAY INVISIBLE (-6400 6225);
FORCEPROP 1 LAST WATTAGE 1/16W
J 2
(-6500 6000);
DISPLAY 0.489362 (-6500 6000);
PAINT SKYBLUE (-6500 6000);
DISPLAY INVISIBLE (-6500 6000);
FORCEPROP 1 LAST MATERIAL CHIP
J 2
(-6250 6050);
DISPLAY 0.489362 (-6250 6050);
PAINT SKYBLUE (-6250 6050);
DISPLAY INVISIBLE (-6250 6050);
FORCEPROP 1 LAST TOLERANCE 5%
J 0
(-6550 6050);
DISPLAY 0.489362 (-6550 6050);
PAINT SKYBLUE (-6550 6050);
DISPLAY INVISIBLE (-6550 6050);
FORCEPROP 1 LAST PACK_TYPE 0402LF
J 2
(-6250 6000);
DISPLAY 0.489362 (-6250 6000);
PAINT SKYBLUE (-6250 6000);
DISPLAY INVISIBLE (-6250 6000);
FORCEPROP 1 LAST PATH I123
J 0
(-6475 6225);
DISPLAY 0.978723 (-6475 6225);
PAINT WHITE (-6475 6225);
DISPLAY INVISIBLE (-6475 6225);
FORCEPROP 1 LAST PART_NUMBER CS00002JB13
J 2
(-6325 6125);
DISPLAY 0.489362 (-6325 6125);
PAINT SKYBLUE (-6325 6125);
DISPLAY INVISIBLE (-6325 6125);
FORCEADD OFFPAGE..4
R 2
(-7350 6175);
FORCEPROP 2 LAST $XR0 28 
J 0
(-7571 6175);
DISPLAY 0.638298 (-7571 6175);
PAINT MONO (-7571 6175);
FORCEPROP 2 LAST CDS_LIB standard
J 0
(-7350 6175);
DISPLAY INVISIBLE (-7350 6175);
FORCEPROP 1 LAST OFFPAGE TRUE
J 2
(-7675 6050);
DISPLAY 0.872340 (-7675 6050);
PAINT GREEN (-7675 6050);
DISPLAY INVISIBLE (-7675 6050);
FORCEPROP 1 LAST COMMENT_BODY TRUE
J 2
(-7325 6075);
DISPLAY 0.872340 (-7325 6075);
PAINT GREEN (-7325 6075);
DISPLAY INVISIBLE (-7325 6075);
FORCEPROP 2 LAST PATH I124
J 0
(-7550 6225);
DISPLAY 0.680851 (-7550 6225);
DISPLAY INVISIBLE (-7550 6225);
FORCEADD Q_RES..1
(-2300 1625);
FORCEPROP 1 LAST LOCATION R798
J 0
(-2200 1625);
DISPLAY 0.489362 (-2200 1625);
PAINT SKYBLUE (-2200 1625);
FORCEPROP 0 LAST $SEC 1
J 0
(-2175 1675);
DISPLAY 0.680851 (-2175 1675);
PAINT MONO (-2175 1675);
DISPLAY INVISIBLE (-2175 1675);
FORCEPROP 0 LAST CDS_SEC 1
J 0
(-2175 1675);
DISPLAY 1.021277 (-2175 1675);
DISPLAY INVISIBLE (-2175 1675);
FORCEPROP 1 LASTPIN (-2400 1625) $PN 1
J 0
(-2388 1637);
DISPLAY 0.489362 (-2388 1637);
PAINT MONO (-2388 1637);
FORCEPROP 1 LASTPIN (-2200 1625) $PN 2
J 0
(-2238 1637);
DISPLAY 0.489362 (-2238 1637);
PAINT MONO (-2238 1637);
FORCEPROP 1 LAST VALUE 33
J 2
(-2425 1625);
DISPLAY 0.489362 (-2425 1625);
PAINT SKYBLUE (-2425 1625);
FORCEPROP 2 LAST CDS_LIB pure_quanta
J 0
(-2300 1625);
DISPLAY INVISIBLE (-2300 1625);
FORCEPROP 2 LAST BOM_COST MEM
J 2
(-2275 1775);
DISPLAY 0.744681 (-2275 1775);
PAINT WHITE (-2275 1775);
DISPLAY INVISIBLE (-2275 1775);
FORCEPROP 1 LAST WATTAGE 1/16W
J 2
(-2375 1550);
DISPLAY 0.489362 (-2375 1550);
PAINT SKYBLUE (-2375 1550);
DISPLAY INVISIBLE (-2375 1550);
FORCEPROP 1 LAST MATERIAL CHIP
J 2
(-2125 1600);
DISPLAY 0.489362 (-2125 1600);
PAINT SKYBLUE (-2125 1600);
DISPLAY INVISIBLE (-2125 1600);
FORCEPROP 1 LAST TOLERANCE 5%
J 0
(-2425 1600);
DISPLAY 0.489362 (-2425 1600);
PAINT SKYBLUE (-2425 1600);
DISPLAY INVISIBLE (-2425 1600);
FORCEPROP 1 LAST PACK_TYPE 0402LF
J 2
(-2125 1550);
DISPLAY 0.489362 (-2125 1550);
PAINT SKYBLUE (-2125 1550);
DISPLAY INVISIBLE (-2125 1550);
FORCEPROP 1 LAST PATH I125
J 0
(-2350 1775);
DISPLAY 0.978723 (-2350 1775);
PAINT WHITE (-2350 1775);
DISPLAY INVISIBLE (-2350 1775);
FORCEPROP 1 LAST PART_NUMBER CS03302JB10
J 2
(-2200 1675);
DISPLAY 0.489362 (-2200 1675);
PAINT SKYBLUE (-2200 1675);
DISPLAY INVISIBLE (-2200 1675);
FORCEADD Q_RES..1
(-3225 3825);
FORCEPROP 1 LAST LOCATION R265
J 0
(-3100 3825);
DISPLAY 0.489362 (-3100 3825);
PAINT SKYBLUE (-3100 3825);
FORCEPROP 0 LAST $SEC 1
J 2
(-3100 3875);
DISPLAY 0.680851 (-3100 3875);
PAINT MONO (-3100 3875);
DISPLAY INVISIBLE (-3100 3875);
FORCEPROP 0 LAST CDS_SEC 1
J 2
(-3100 3875);
DISPLAY 1.021277 (-3100 3875);
DISPLAY INVISIBLE (-3100 3875);
FORCEPROP 1 LASTPIN (-3325 3825) $PN 1
J 0
(-3313 3837);
DISPLAY 0.489362 (-3313 3837);
PAINT MONO (-3313 3837);
FORCEPROP 1 LASTPIN (-3125 3825) $PN 2
J 0
(-3163 3837);
DISPLAY 0.489362 (-3163 3837);
PAINT MONO (-3163 3837);
FORCEPROP 1 LAST VALUE 33
J 2
(-3350 3825);
DISPLAY 0.489362 (-3350 3825);
PAINT SKYBLUE (-3350 3825);
FORCEPROP 2 LAST CDS_LIB pure_quanta
J 2
(-3225 3825);
DISPLAY INVISIBLE (-3225 3825);
FORCEPROP 2 LAST BOM_COST MEM
J 2
(-3200 3975);
DISPLAY 0.744681 (-3200 3975);
PAINT WHITE (-3200 3975);
DISPLAY INVISIBLE (-3200 3975);
FORCEPROP 1 LAST WATTAGE 1/16W
J 2
(-3300 3750);
DISPLAY 0.489362 (-3300 3750);
PAINT SKYBLUE (-3300 3750);
DISPLAY INVISIBLE (-3300 3750);
FORCEPROP 1 LAST MATERIAL CHIP
J 2
(-3050 3800);
DISPLAY 0.489362 (-3050 3800);
PAINT SKYBLUE (-3050 3800);
DISPLAY INVISIBLE (-3050 3800);
FORCEPROP 1 LAST TOLERANCE 5%
J 0
(-3350 3800);
DISPLAY 0.489362 (-3350 3800);
PAINT SKYBLUE (-3350 3800);
DISPLAY INVISIBLE (-3350 3800);
FORCEPROP 1 LAST PACK_TYPE 0402LF
J 2
(-3050 3750);
DISPLAY 0.489362 (-3050 3750);
PAINT SKYBLUE (-3050 3750);
DISPLAY INVISIBLE (-3050 3750);
FORCEPROP 1 LAST PATH I126
J 0
(-3275 3975);
DISPLAY 0.978723 (-3275 3975);
PAINT WHITE (-3275 3975);
DISPLAY INVISIBLE (-3275 3975);
FORCEPROP 1 LAST PART_NUMBER CS03302JB10
J 2
(-3125 3875);
DISPLAY 0.489362 (-3125 3875);
PAINT SKYBLUE (-3125 3875);
DISPLAY INVISIBLE (-3125 3875);
FORCEADD Q_RES..1
(-3225 3875);
FORCEPROP 1 LAST LOCATION R1202
J 0
(-3100 3875);
DISPLAY 0.489362 (-3100 3875);
PAINT SKYBLUE (-3100 3875);
FORCEPROP 0 LAST $SEC 1
J 0
(-3100 3925);
DISPLAY 0.680851 (-3100 3925);
PAINT MONO (-3100 3925);
DISPLAY INVISIBLE (-3100 3925);
FORCEPROP 0 LAST CDS_SEC 1
J 0
(-3100 3925);
DISPLAY 0.680851 (-3100 3925);
DISPLAY INVISIBLE (-3100 3925);
FORCEPROP 1 LASTPIN (-3325 3875) $PN 1
J 0
(-3313 3887);
DISPLAY 0.489362 (-3313 3887);
PAINT MONO (-3313 3887);
FORCEPROP 1 LASTPIN (-3125 3875) $PN 2
J 0
(-3163 3887);
DISPLAY 0.489362 (-3163 3887);
PAINT MONO (-3163 3887);
FORCEPROP 1 LAST VALUE 0
J 2
(-3350 3875);
DISPLAY 0.489362 (-3350 3875);
PAINT SKYBLUE (-3350 3875);
FORCEPROP 2 LAST CDS_LIB pure_quanta
J 0
(-3225 3875);
DISPLAY INVISIBLE (-3225 3875);
FORCEPROP 1 LAST PACK_TYPE 0402LF
J 2
(-3050 3800);
DISPLAY 0.489362 (-3050 3800);
PAINT SKYBLUE (-3050 3800);
DISPLAY INVISIBLE (-3050 3800);
FORCEPROP 1 LAST TOLERANCE 5%
J 0
(-3350 3850);
DISPLAY 0.489362 (-3350 3850);
PAINT SKYBLUE (-3350 3850);
DISPLAY INVISIBLE (-3350 3850);
FORCEPROP 1 LAST MATERIAL CHIP
J 2
(-3050 3850);
DISPLAY 0.489362 (-3050 3850);
PAINT SKYBLUE (-3050 3850);
DISPLAY INVISIBLE (-3050 3850);
FORCEPROP 1 LAST WATTAGE 1/16W
J 2
(-3300 3800);
DISPLAY 0.489362 (-3300 3800);
PAINT SKYBLUE (-3300 3800);
DISPLAY INVISIBLE (-3300 3800);
FORCEPROP 2 LAST BOM_COST MEM
J 2
(-3200 4025);
DISPLAY 0.744681 (-3200 4025);
PAINT WHITE (-3200 4025);
DISPLAY INVISIBLE (-3200 4025);
FORCEPROP 1 LAST PATH I127
J 0
(-3275 4025);
DISPLAY 0.978723 (-3275 4025);
PAINT WHITE (-3275 4025);
DISPLAY INVISIBLE (-3275 4025);
FORCEPROP 1 LAST PART_NUMBER CS00002JB13
J 2
(-3125 3925);
DISPLAY 0.489362 (-3125 3925);
PAINT SKYBLUE (-3125 3925);
DISPLAY INVISIBLE (-3125 3925);
FORCEADD Q_RES..1
(-3225 4075);
FORCEPROP 1 LAST LOCATION R252
J 0
(-3100 4075);
DISPLAY 0.489362 (-3100 4075);
PAINT SKYBLUE (-3100 4075);
FORCEPROP 0 LAST $SEC 1
J 0
(-3100 4100);
DISPLAY 0.680851 (-3100 4100);
PAINT MONO (-3100 4100);
DISPLAY INVISIBLE (-3100 4100);
FORCEPROP 0 LAST CDS_SEC 1
J 0
(-3100 4100);
DISPLAY 0.680851 (-3100 4100);
DISPLAY INVISIBLE (-3100 4100);
FORCEPROP 1 LASTPIN (-3325 4075) $PN 1
J 0
(-3313 4087);
DISPLAY 0.787234 (-3313 4087);
PAINT MONO (-3313 4087);
FORCEPROP 1 LASTPIN (-3125 4075) $PN 2
J 0
(-3163 4087);
DISPLAY 0.787234 (-3163 4087);
PAINT MONO (-3163 4087);
FORCEPROP 1 LAST VALUE 0
J 2
(-3350 4075);
DISPLAY 0.489362 (-3350 4075);
PAINT SKYBLUE (-3350 4075);
FORCEPROP 2 LAST CDS_LIB pure_quanta
J 0
(-3225 4075);
DISPLAY INVISIBLE (-3225 4075);
FORCEPROP 2 LAST BOM_COST MEM
J 2
(-3200 4225);
DISPLAY 0.744681 (-3200 4225);
PAINT WHITE (-3200 4225);
DISPLAY INVISIBLE (-3200 4225);
FORCEPROP 1 LAST WATTAGE 1/16W
J 2
(-3300 4000);
DISPLAY 0.489362 (-3300 4000);
PAINT SKYBLUE (-3300 4000);
DISPLAY INVISIBLE (-3300 4000);
FORCEPROP 1 LAST MATERIAL CHIP
J 2
(-3050 4050);
DISPLAY 0.489362 (-3050 4050);
PAINT SKYBLUE (-3050 4050);
DISPLAY INVISIBLE (-3050 4050);
FORCEPROP 1 LAST TOLERANCE 5%
J 0
(-3350 4050);
DISPLAY 0.489362 (-3350 4050);
PAINT SKYBLUE (-3350 4050);
DISPLAY INVISIBLE (-3350 4050);
FORCEPROP 1 LAST PACK_TYPE 0402LF
J 2
(-3050 4000);
DISPLAY 0.489362 (-3050 4000);
PAINT SKYBLUE (-3050 4000);
DISPLAY INVISIBLE (-3050 4000);
FORCEPROP 1 LAST PATH I128
J 0
(-3275 4225);
DISPLAY 0.978723 (-3275 4225);
PAINT WHITE (-3275 4225);
DISPLAY INVISIBLE (-3275 4225);
FORCEPROP 1 LAST PART_NUMBER CS00002JB13
J 2
(-3125 4125);
DISPLAY 0.489362 (-3125 4125);
PAINT SKYBLUE (-3125 4125);
DISPLAY INVISIBLE (-3125 4125);
FORCEADD Q_RES..1
(-3225 4025);
FORCEPROP 1 LAST LOCATION R186
J 0
(-3100 4025);
DISPLAY 0.489362 (-3100 4025);
PAINT SKYBLUE (-3100 4025);
FORCEPROP 0 LAST $SEC 1
J 2
(-3100 4075);
DISPLAY 0.680851 (-3100 4075);
PAINT MONO (-3100 4075);
DISPLAY INVISIBLE (-3100 4075);
FORCEPROP 0 LAST CDS_SEC 1
J 2
(-3100 4075);
DISPLAY 1.021277 (-3100 4075);
DISPLAY INVISIBLE (-3100 4075);
FORCEPROP 1 LASTPIN (-3325 4025) $PN 1
J 0
(-3313 4037);
DISPLAY 0.489362 (-3313 4037);
PAINT MONO (-3313 4037);
FORCEPROP 1 LASTPIN (-3125 4025) $PN 2
J 0
(-3163 4037);
DISPLAY 0.489362 (-3163 4037);
PAINT MONO (-3163 4037);
FORCEPROP 1 LAST VALUE 33
J 2
(-3350 4025);
DISPLAY 0.489362 (-3350 4025);
PAINT SKYBLUE (-3350 4025);
FORCEPROP 1 LAST PACK_TYPE 0402LF
J 2
(-3050 3950);
DISPLAY 0.489362 (-3050 3950);
PAINT SKYBLUE (-3050 3950);
DISPLAY INVISIBLE (-3050 3950);
FORCEPROP 1 LAST TOLERANCE 5%
J 0
(-3350 4000);
DISPLAY 0.489362 (-3350 4000);
PAINT SKYBLUE (-3350 4000);
DISPLAY INVISIBLE (-3350 4000);
FORCEPROP 1 LAST MATERIAL CHIP
J 2
(-3050 4000);
DISPLAY 0.489362 (-3050 4000);
PAINT SKYBLUE (-3050 4000);
DISPLAY INVISIBLE (-3050 4000);
FORCEPROP 1 LAST WATTAGE 1/16W
J 2
(-3300 3950);
DISPLAY 0.489362 (-3300 3950);
PAINT SKYBLUE (-3300 3950);
DISPLAY INVISIBLE (-3300 3950);
FORCEPROP 2 LAST BOM_COST MEM
J 2
(-3200 4175);
DISPLAY 0.744681 (-3200 4175);
PAINT WHITE (-3200 4175);
DISPLAY INVISIBLE (-3200 4175);
FORCEPROP 2 LAST CDS_LIB pure_quanta
J 2
(-3225 4025);
DISPLAY INVISIBLE (-3225 4025);
FORCEPROP 1 LAST PATH I129
J 0
(-3275 4175);
DISPLAY 0.978723 (-3275 4175);
PAINT WHITE (-3275 4175);
DISPLAY INVISIBLE (-3275 4175);
FORCEPROP 1 LAST PART_NUMBER CS03302JB10
J 2
(-3125 4075);
DISPLAY 0.489362 (-3125 4075);
PAINT SKYBLUE (-3125 4075);
DISPLAY INVISIBLE (-3125 4075);
FORCEADD OFFPAGE..1
(-7800 1675);
FORCEPROP 2 LAST $XR3 271 
J 0
(-8412 1675);
DISPLAY 0.638298 (-8412 1675);
PAINT MONO (-8412 1675);
FORCEPROP 2 LAST $XR2 255 
J 0
(-8292 1675);
DISPLAY 0.638298 (-8292 1675);
PAINT MONO (-8292 1675);
FORCEPROP 2 LAST $XR1 148 
J 0
(-8172 1675);
DISPLAY 0.638298 (-8172 1675);
PAINT MONO (-8172 1675);
FORCEPROP 2 LAST $XR0 270 
J 0
(-8052 1675);
DISPLAY 0.638298 (-8052 1675);
PAINT MONO (-8052 1675);
FORCEPROP 2 LAST CDS_LIB standard
J 0
(-7800 1675);
DISPLAY INVISIBLE (-7800 1675);
FORCEPROP 1 LAST OFFPAGE TRUE
J 0
(-7475 1550);
DISPLAY 0.872340 (-7475 1550);
PAINT GREEN (-7475 1550);
DISPLAY INVISIBLE (-7475 1550);
FORCEPROP 1 LAST COMMENT_BODY TRUE
J 0
(-7675 1575);
DISPLAY 0.872340 (-7675 1575);
PAINT GREEN (-7675 1575);
DISPLAY INVISIBLE (-7675 1575);
FORCEPROP 2 LAST PATH I13
J 0
(-8075 1725);
DISPLAY 0.680851 (-8075 1725);
DISPLAY INVISIBLE (-8075 1725);
FORCEADD Q_RES..1
(-2300 2775);
FORCEPROP 1 LAST LOCATION R957
J 0
(-2200 2775);
DISPLAY 0.489362 (-2200 2775);
PAINT SKYBLUE (-2200 2775);
FORCEPROP 0 LAST $SEC 1
J 0
(-2200 2825);
DISPLAY 0.680851 (-2200 2825);
PAINT MONO (-2200 2825);
DISPLAY INVISIBLE (-2200 2825);
FORCEPROP 0 LAST CDS_SEC 1
J 0
(-2200 2825);
DISPLAY 0.680851 (-2200 2825);
DISPLAY INVISIBLE (-2200 2825);
FORCEPROP 1 LASTPIN (-2400 2775) $PN 1
J 0
(-2388 2787);
DISPLAY 0.489362 (-2388 2787);
PAINT MONO (-2388 2787);
FORCEPROP 1 LASTPIN (-2200 2775) $PN 2
J 0
(-2238 2787);
DISPLAY 0.489362 (-2238 2787);
PAINT MONO (-2238 2787);
FORCEPROP 1 LAST VALUE 33
J 2
(-2425 2775);
DISPLAY 0.489362 (-2425 2775);
PAINT SKYBLUE (-2425 2775);
FORCEPROP 2 LAST CDS_LIB pure_quanta
J 0
(-2300 2775);
DISPLAY INVISIBLE (-2300 2775);
FORCEPROP 2 LAST BOM_COST MEM
J 2
(-2275 2925);
DISPLAY 0.744681 (-2275 2925);
PAINT WHITE (-2275 2925);
DISPLAY INVISIBLE (-2275 2925);
FORCEPROP 1 LAST WATTAGE 1/16W
J 2
(-2375 2700);
DISPLAY 0.489362 (-2375 2700);
PAINT SKYBLUE (-2375 2700);
DISPLAY INVISIBLE (-2375 2700);
FORCEPROP 1 LAST MATERIAL CHIP
J 2
(-2125 2750);
DISPLAY 0.489362 (-2125 2750);
PAINT SKYBLUE (-2125 2750);
DISPLAY INVISIBLE (-2125 2750);
FORCEPROP 1 LAST TOLERANCE 5%
J 0
(-2425 2750);
DISPLAY 0.489362 (-2425 2750);
PAINT SKYBLUE (-2425 2750);
DISPLAY INVISIBLE (-2425 2750);
FORCEPROP 1 LAST PACK_TYPE 0402LF
J 2
(-2125 2700);
DISPLAY 0.489362 (-2125 2700);
PAINT SKYBLUE (-2125 2700);
DISPLAY INVISIBLE (-2125 2700);
FORCEPROP 1 LAST PATH I130
J 0
(-2350 2925);
DISPLAY 0.978723 (-2350 2925);
PAINT WHITE (-2350 2925);
DISPLAY INVISIBLE (-2350 2925);
FORCEPROP 1 LAST PART_NUMBER CS03302JB10
J 2
(-2200 2825);
DISPLAY 0.489362 (-2200 2825);
PAINT SKYBLUE (-2200 2825);
DISPLAY INVISIBLE (-2200 2825);
FORCEADD Q_RES..1
(-2300 2725);
FORCEPROP 1 LAST LOCATION R685
J 0
(-2200 2725);
DISPLAY 0.489362 (-2200 2725);
PAINT SKYBLUE (-2200 2725);
FORCEPROP 0 LAST $SEC 1
J 0
(-2175 2775);
DISPLAY 0.680851 (-2175 2775);
PAINT MONO (-2175 2775);
DISPLAY INVISIBLE (-2175 2775);
FORCEPROP 0 LAST CDS_SEC 1
J 0
(-2175 2775);
DISPLAY 1.021277 (-2175 2775);
DISPLAY INVISIBLE (-2175 2775);
FORCEPROP 1 LASTPIN (-2400 2725) $PN 1
J 0
(-2388 2737);
DISPLAY 0.489362 (-2388 2737);
PAINT MONO (-2388 2737);
FORCEPROP 1 LASTPIN (-2200 2725) $PN 2
J 0
(-2238 2737);
DISPLAY 0.489362 (-2238 2737);
PAINT MONO (-2238 2737);
FORCEPROP 1 LAST VALUE 33
J 2
(-2425 2725);
DISPLAY 0.489362 (-2425 2725);
PAINT SKYBLUE (-2425 2725);
FORCEPROP 2 LAST BOM_COST MEM
J 2
(-2275 2875);
DISPLAY 0.744681 (-2275 2875);
PAINT WHITE (-2275 2875);
DISPLAY INVISIBLE (-2275 2875);
FORCEPROP 2 LAST CDS_LIB pure_quanta
J 0
(-2300 2725);
DISPLAY INVISIBLE (-2300 2725);
FORCEPROP 1 LAST WATTAGE 1/16W
J 2
(-2375 2650);
DISPLAY 0.489362 (-2375 2650);
PAINT SKYBLUE (-2375 2650);
DISPLAY INVISIBLE (-2375 2650);
FORCEPROP 1 LAST MATERIAL CHIP
J 2
(-2125 2700);
DISPLAY 0.489362 (-2125 2700);
PAINT SKYBLUE (-2125 2700);
DISPLAY INVISIBLE (-2125 2700);
FORCEPROP 1 LAST TOLERANCE 5%
J 0
(-2425 2700);
DISPLAY 0.489362 (-2425 2700);
PAINT SKYBLUE (-2425 2700);
DISPLAY INVISIBLE (-2425 2700);
FORCEPROP 1 LAST PACK_TYPE 0402LF
J 2
(-2125 2650);
DISPLAY 0.489362 (-2125 2650);
PAINT SKYBLUE (-2125 2650);
DISPLAY INVISIBLE (-2125 2650);
FORCEPROP 1 LAST PATH I131
J 0
(-2350 2875);
DISPLAY 0.978723 (-2350 2875);
PAINT WHITE (-2350 2875);
DISPLAY INVISIBLE (-2350 2875);
FORCEPROP 1 LAST PART_NUMBER CS03302JB10
J 2
(-2200 2775);
DISPLAY 0.489362 (-2200 2775);
PAINT SKYBLUE (-2200 2775);
DISPLAY INVISIBLE (-2200 2775);
FORCEADD OFFPAGE..1
R 2
(-2300 4075);
FORCEPROP 2 LAST $XR1 55 
J 0
(-2024 4075);
DISPLAY 0.638298 (-2024 4075);
PAINT MONO (-2024 4075);
FORCEPROP 2 LAST $XR0 28 
J 0
(-2114 4075);
DISPLAY 0.638298 (-2114 4075);
PAINT MONO (-2114 4075);
FORCEPROP 2 LAST CDS_LIB standard
J 0
(-2300 4075);
DISPLAY INVISIBLE (-2300 4075);
FORCEPROP 1 LAST OFFPAGE TRUE
J 2
(-2625 3950);
DISPLAY 0.872340 (-2625 3950);
PAINT GREEN (-2625 3950);
DISPLAY INVISIBLE (-2625 3950);
FORCEPROP 1 LAST COMMENT_BODY TRUE
J 2
(-2425 3975);
DISPLAY 0.872340 (-2425 3975);
PAINT GREEN (-2425 3975);
DISPLAY INVISIBLE (-2425 3975);
FORCEPROP 2 LAST PATH I132
J 0
(-2000 4125);
DISPLAY 0.680851 (-2000 4125);
DISPLAY INVISIBLE (-2000 4125);
FORCEADD OFFPAGE..2
(-2300 4025);
FORCEPROP 2 LAST $XR0 28 
J 0
(-2111 4025);
DISPLAY 0.638298 (-2111 4025);
PAINT MONO (-2111 4025);
FORCEPROP 2 LAST CDS_LIB standard
J 0
(-2300 4025);
DISPLAY INVISIBLE (-2300 4025);
FORCEPROP 1 LAST OFFPAGE TRUE
J 0
(-1975 3900);
DISPLAY 0.872340 (-1975 3900);
PAINT GREEN (-1975 3900);
DISPLAY INVISIBLE (-1975 3900);
FORCEPROP 1 LAST COMMENT_BODY TRUE
J 0
(-2345 3930);
DISPLAY 0.872340 (-2345 3930);
PAINT GREEN (-2345 3930);
DISPLAY INVISIBLE (-2345 3930);
FORCEPROP 2 LAST PATH I133
J 0
(-2100 4075);
DISPLAY 0.680851 (-2100 4075);
DISPLAY INVISIBLE (-2100 4075);
FORCEADD OFFPAGE..2
(-2300 3825);
FORCEPROP 2 LAST $XR0 55 
J 0
(-2111 3825);
DISPLAY 0.638298 (-2111 3825);
PAINT MONO (-2111 3825);
FORCEPROP 2 LAST CDS_LIB standard
J 0
(-2300 3825);
DISPLAY INVISIBLE (-2300 3825);
FORCEPROP 1 LAST OFFPAGE TRUE
J 0
(-1975 3700);
DISPLAY 0.872340 (-1975 3700);
PAINT GREEN (-1975 3700);
DISPLAY INVISIBLE (-1975 3700);
FORCEPROP 1 LAST COMMENT_BODY TRUE
J 0
(-2345 3730);
DISPLAY 0.872340 (-2345 3730);
PAINT GREEN (-2345 3730);
DISPLAY INVISIBLE (-2345 3730);
FORCEPROP 2 LAST PATH I134
J 0
(-2100 3875);
DISPLAY 0.680851 (-2100 3875);
DISPLAY INVISIBLE (-2100 3875);
FORCEADD OFFPAGE..1
R 2
(-2300 3875);
FORCEPROP 2 LAST $XR0 167 
J 0
(-2084 3875);
DISPLAY 0.638298 (-2084 3875);
PAINT MONO (-2084 3875);
FORCEPROP 2 LAST CDS_LIB standard
J 0
(-2300 3875);
DISPLAY INVISIBLE (-2300 3875);
FORCEPROP 1 LAST OFFPAGE TRUE
J 2
(-2625 3750);
DISPLAY 0.872340 (-2625 3750);
PAINT GREEN (-2625 3750);
DISPLAY INVISIBLE (-2625 3750);
FORCEPROP 1 LAST COMMENT_BODY TRUE
J 2
(-2425 3775);
DISPLAY 0.872340 (-2425 3775);
PAINT GREEN (-2425 3775);
DISPLAY INVISIBLE (-2425 3775);
FORCEPROP 2 LAST PATH I135
J 0
(-2100 3925);
DISPLAY 0.680851 (-2100 3925);
DISPLAY INVISIBLE (-2100 3925);
FORCEADD OFFPAGE..1
R 2
(-2300 4125);
FORCEPROP 2 LAST $XR0 55 
J 0
(-2114 4125);
DISPLAY 0.638298 (-2114 4125);
PAINT MONO (-2114 4125);
FORCEPROP 2 LAST CDS_LIB standard
J 0
(-2300 4125);
DISPLAY INVISIBLE (-2300 4125);
FORCEPROP 1 LAST OFFPAGE TRUE
J 2
(-2625 4000);
DISPLAY 0.872340 (-2625 4000);
PAINT GREEN (-2625 4000);
DISPLAY INVISIBLE (-2625 4000);
FORCEPROP 1 LAST COMMENT_BODY TRUE
J 2
(-2425 4025);
DISPLAY 0.872340 (-2425 4025);
PAINT GREEN (-2425 4025);
DISPLAY INVISIBLE (-2425 4025);
FORCEPROP 2 LAST PATH I136
J 0
(-2100 4175);
DISPLAY 0.680851 (-2100 4175);
DISPLAY INVISIBLE (-2100 4175);
FORCEADD OFFPAGE..2
(-1450 875);
FORCEPROP 2 LAST $XR3 248 
J 0
(-931 875);
DISPLAY 0.638298 (-931 875);
PAINT MONO (-931 875);
FORCEPROP 2 LAST $XR2 141 
J 0
(-1051 875);
DISPLAY 0.638298 (-1051 875);
PAINT MONO (-1051 875);
FORCEPROP 2 LAST $XR1 140 
J 0
(-1171 875);
DISPLAY 0.638298 (-1171 875);
PAINT MONO (-1171 875);
FORCEPROP 2 LAST $XR0 83 
J 0
(-1261 875);
DISPLAY 0.638298 (-1261 875);
PAINT MONO (-1261 875);
FORCEPROP 2 LAST CDS_LIB standard
J 0
(-1450 875);
DISPLAY INVISIBLE (-1450 875);
FORCEPROP 1 LAST OFFPAGE TRUE
J 0
(-1125 750);
DISPLAY 0.872340 (-1125 750);
PAINT GREEN (-1125 750);
DISPLAY INVISIBLE (-1125 750);
FORCEPROP 1 LAST COMMENT_BODY TRUE
J 0
(-1495 780);
DISPLAY 0.872340 (-1495 780);
PAINT GREEN (-1495 780);
DISPLAY INVISIBLE (-1495 780);
FORCEPROP 2 LAST PATH I137
J 0
(-1275 950);
DISPLAY 0.680851 (-1275 950);
DISPLAY INVISIBLE (-1275 950);
FORCEADD OFFPAGE..1
(-7800 1725);
FORCEPROP 2 LAST $XR0 209 
J 0
(-8052 1725);
DISPLAY 0.638298 (-8052 1725);
PAINT MONO (-8052 1725);
FORCEPROP 2 LAST CDS_LIB standard
J 0
(-7800 1725);
DISPLAY INVISIBLE (-7800 1725);
FORCEPROP 1 LAST OFFPAGE TRUE
J 0
(-7475 1600);
DISPLAY 0.872340 (-7475 1600);
PAINT GREEN (-7475 1600);
DISPLAY INVISIBLE (-7475 1600);
FORCEPROP 1 LAST COMMENT_BODY TRUE
J 0
(-7675 1625);
DISPLAY 0.872340 (-7675 1625);
PAINT GREEN (-7675 1625);
DISPLAY INVISIBLE (-7675 1625);
FORCEPROP 2 LAST PATH I14
J 0
(-8075 1775);
DISPLAY 0.680851 (-8075 1775);
DISPLAY INVISIBLE (-8075 1775);
FORCEADD OFFPAGE..2
(-800 1125);
FORCEPROP 2 LAST $XR3 142 
J 0
(-521 1089);
DISPLAY 0.638298 (-521 1089);
PAINT MONO (-521 1089);
FORCEPROP 2 LAST $XR2 141 
J 0
(-401 1125);
DISPLAY 0.638298 (-401 1125);
PAINT MONO (-401 1125);
FORCEPROP 2 LAST $XR1 140 
J 0
(-521 1125);
DISPLAY 0.638298 (-521 1125);
PAINT MONO (-521 1125);
FORCEPROP 2 LAST $XR0 83 
J 0
(-611 1125);
DISPLAY 0.638298 (-611 1125);
PAINT MONO (-611 1125);
FORCEPROP 2 LAST CDS_LIB standard
J 0
(-800 1125);
DISPLAY INVISIBLE (-800 1125);
FORCEPROP 1 LAST OFFPAGE TRUE
J 0
(-475 1000);
DISPLAY 0.872340 (-475 1000);
PAINT GREEN (-475 1000);
DISPLAY INVISIBLE (-475 1000);
FORCEPROP 1 LAST COMMENT_BODY TRUE
J 0
(-845 1030);
DISPLAY 0.872340 (-845 1030);
PAINT GREEN (-845 1030);
DISPLAY INVISIBLE (-845 1030);
FORCEPROP 2 LAST PATH I140
J 0
(-625 1200);
DISPLAY 0.680851 (-625 1200);
DISPLAY INVISIBLE (-625 1200);
FORCEADD OFFPAGE..1
R 2
(-825 1175);
FORCEPROP 2 LAST $XR1 172 
J 0
(-519 1175);
DISPLAY 0.638298 (-519 1175);
PAINT MONO (-519 1175);
FORCEPROP 2 LAST $XR0 83 
J 0
(-609 1175);
DISPLAY 0.638298 (-609 1175);
PAINT MONO (-609 1175);
FORCEPROP 2 LAST CDS_LIB standard
J 0
(-825 1175);
DISPLAY INVISIBLE (-825 1175);
FORCEPROP 1 LAST OFFPAGE TRUE
J 2
(-1150 1050);
DISPLAY 0.872340 (-1150 1050);
PAINT GREEN (-1150 1050);
DISPLAY INVISIBLE (-1150 1050);
FORCEPROP 1 LAST COMMENT_BODY TRUE
J 2
(-950 1075);
DISPLAY 0.872340 (-950 1075);
PAINT GREEN (-950 1075);
DISPLAY INVISIBLE (-950 1075);
FORCEPROP 2 LAST PATH I141
J 0
(-525 1225);
DISPLAY 0.680851 (-525 1225);
DISPLAY INVISIBLE (-525 1225);
FORCEADD OFFPAGE..2
(-800 1225);
FORCEPROP 2 LAST $XR0 138 
J 0
(-611 1225);
DISPLAY 0.638298 (-611 1225);
PAINT MONO (-611 1225);
FORCEPROP 2 LAST CDS_LIB standard
J 0
(-800 1225);
DISPLAY INVISIBLE (-800 1225);
FORCEPROP 1 LAST OFFPAGE TRUE
J 0
(-475 1100);
DISPLAY 0.872340 (-475 1100);
PAINT GREEN (-475 1100);
DISPLAY INVISIBLE (-475 1100);
FORCEPROP 1 LAST COMMENT_BODY TRUE
J 0
(-845 1130);
DISPLAY 0.872340 (-845 1130);
PAINT GREEN (-845 1130);
DISPLAY INVISIBLE (-845 1130);
FORCEPROP 2 LAST PATH I142
J 0
(-625 1300);
DISPLAY 0.680851 (-625 1300);
DISPLAY INVISIBLE (-625 1300);
FORCEADD OFFPAGE..2
(-775 1325);
FORCEPROP 2 LAST $XR0 142 
J 0
(-586 1325);
DISPLAY 0.638298 (-586 1325);
PAINT MONO (-586 1325);
FORCEPROP 2 LAST CDS_LIB standard
J 0
(-775 1325);
DISPLAY INVISIBLE (-775 1325);
FORCEPROP 1 LAST OFFPAGE TRUE
J 0
(-450 1200);
DISPLAY 0.872340 (-450 1200);
PAINT GREEN (-450 1200);
DISPLAY INVISIBLE (-450 1200);
FORCEPROP 1 LAST COMMENT_BODY TRUE
J 0
(-820 1230);
DISPLAY 0.872340 (-820 1230);
PAINT GREEN (-820 1230);
DISPLAY INVISIBLE (-820 1230);
FORCEPROP 2 LAST PATH I143
J 0
(-575 1375);
DISPLAY 0.680851 (-575 1375);
DISPLAY INVISIBLE (-575 1375);
FORCEADD OFFPAGE..2
(-775 1425);
FORCEPROP 2 LAST $XR0 136 
J 0
(-586 1425);
DISPLAY 0.638298 (-586 1425);
PAINT MONO (-586 1425);
FORCEPROP 2 LAST CDS_LIB standard
J 0
(-775 1425);
DISPLAY INVISIBLE (-775 1425);
FORCEPROP 1 LAST OFFPAGE TRUE
J 0
(-450 1300);
DISPLAY 0.872340 (-450 1300);
PAINT GREEN (-450 1300);
DISPLAY INVISIBLE (-450 1300);
FORCEPROP 1 LAST COMMENT_BODY TRUE
J 0
(-820 1330);
DISPLAY 0.872340 (-820 1330);
PAINT GREEN (-820 1330);
DISPLAY INVISIBLE (-820 1330);
FORCEPROP 2 LAST PATH I144
J 0
(-575 1475);
DISPLAY 0.680851 (-575 1475);
DISPLAY INVISIBLE (-575 1475);
FORCEADD OFFPAGE..2
(-775 1625);
FORCEPROP 2 LAST $XR1 144 
J 0
(-496 1625);
DISPLAY 0.638298 (-496 1625);
PAINT MONO (-496 1625);
FORCEPROP 2 LAST $XR0 83 
J 0
(-586 1625);
DISPLAY 0.638298 (-586 1625);
PAINT MONO (-586 1625);
FORCEPROP 2 LAST CDS_LIB standard
J 0
(-775 1625);
DISPLAY INVISIBLE (-775 1625);
FORCEPROP 1 LAST OFFPAGE TRUE
J 0
(-450 1500);
DISPLAY 0.872340 (-450 1500);
PAINT GREEN (-450 1500);
DISPLAY INVISIBLE (-450 1500);
FORCEPROP 1 LAST COMMENT_BODY TRUE
J 0
(-820 1530);
DISPLAY 0.872340 (-820 1530);
PAINT GREEN (-820 1530);
DISPLAY INVISIBLE (-820 1530);
FORCEPROP 2 LAST PATH I147
J 0
(-475 1675);
DISPLAY 0.680851 (-475 1675);
DISPLAY INVISIBLE (-475 1675);
FORCEADD OFFPAGE..2
(-775 1675);
FORCEPROP 2 LAST $XR0 188 
J 0
(-586 1675);
DISPLAY 0.638298 (-586 1675);
PAINT MONO (-586 1675);
FORCEPROP 2 LAST CDS_LIB standard
J 0
(-775 1675);
DISPLAY INVISIBLE (-775 1675);
FORCEPROP 1 LAST OFFPAGE TRUE
J 0
(-450 1550);
DISPLAY 0.872340 (-450 1550);
PAINT GREEN (-450 1550);
DISPLAY INVISIBLE (-450 1550);
FORCEPROP 1 LAST COMMENT_BODY TRUE
J 0
(-820 1580);
DISPLAY 0.872340 (-820 1580);
PAINT GREEN (-820 1580);
DISPLAY INVISIBLE (-820 1580);
FORCEPROP 2 LAST PATH I148
J 0
(-575 1725);
DISPLAY 0.680851 (-575 1725);
DISPLAY INVISIBLE (-575 1725);
FORCEADD OFFPAGE..1
(-7800 1825);
FORCEPROP 2 LAST $XR2 270 
J 0
(-8262 1825);
DISPLAY 0.638298 (-8262 1825);
PAINT MONO (-8262 1825);
FORCEPROP 2 LAST $XR1 85 
J 0
(-8142 1825);
DISPLAY 0.638298 (-8142 1825);
PAINT MONO (-8142 1825);
FORCEPROP 2 LAST $XR0 190 
J 0
(-8052 1825);
DISPLAY 0.638298 (-8052 1825);
PAINT MONO (-8052 1825);
FORCEPROP 2 LAST CDS_LIB standard
J 0
(-7800 1825);
DISPLAY INVISIBLE (-7800 1825);
FORCEPROP 1 LAST OFFPAGE TRUE
J 0
(-7475 1700);
DISPLAY 0.872340 (-7475 1700);
PAINT GREEN (-7475 1700);
DISPLAY INVISIBLE (-7475 1700);
FORCEPROP 1 LAST COMMENT_BODY TRUE
J 0
(-7675 1725);
DISPLAY 0.872340 (-7675 1725);
PAINT GREEN (-7675 1725);
DISPLAY INVISIBLE (-7675 1725);
FORCEPROP 2 LAST PATH I15
J 0
(-8075 1875);
DISPLAY 0.680851 (-8075 1875);
DISPLAY INVISIBLE (-8075 1875);
FORCEADD OFFPAGE..2
(-775 2775);
FORCEPROP 2 LAST $XR0 150 
J 0
(-586 2775);
DISPLAY 0.638298 (-586 2775);
PAINT MONO (-586 2775);
FORCEPROP 2 LAST CDS_LIB standard
J 0
(-775 2775);
DISPLAY INVISIBLE (-775 2775);
FORCEPROP 1 LAST OFFPAGE TRUE
J 0
(-450 2650);
DISPLAY 0.872340 (-450 2650);
PAINT GREEN (-450 2650);
DISPLAY INVISIBLE (-450 2650);
FORCEPROP 1 LAST COMMENT_BODY TRUE
J 0
(-820 2680);
DISPLAY 0.872340 (-820 2680);
PAINT GREEN (-820 2680);
DISPLAY INVISIBLE (-820 2680);
FORCEPROP 2 LAST PATH I151
J 0
(-575 2825);
DISPLAY 0.680851 (-575 2825);
DISPLAY INVISIBLE (-575 2825);
FORCEADD OFFPAGE..2
(-775 2725);
FORCEPROP 2 LAST $XR1 145 
J 0
(-496 2725);
DISPLAY 0.638298 (-496 2725);
PAINT MONO (-496 2725);
FORCEPROP 2 LAST $XR0 83 
J 0
(-586 2725);
DISPLAY 0.638298 (-586 2725);
PAINT MONO (-586 2725);
FORCEPROP 2 LAST CDS_LIB standard
J 0
(-775 2725);
DISPLAY INVISIBLE (-775 2725);
FORCEPROP 1 LAST OFFPAGE TRUE
J 0
(-450 2600);
DISPLAY 0.872340 (-450 2600);
PAINT GREEN (-450 2600);
DISPLAY INVISIBLE (-450 2600);
FORCEPROP 1 LAST COMMENT_BODY TRUE
J 0
(-820 2630);
DISPLAY 0.872340 (-820 2630);
PAINT GREEN (-820 2630);
DISPLAY INVISIBLE (-820 2630);
FORCEPROP 2 LAST PATH I152
J 0
(-475 2775);
DISPLAY 0.680851 (-475 2775);
DISPLAY INVISIBLE (-475 2775);
FORCEADD Q_RES..1
(-3225 4175);
FORCEPROP 1 LAST LOCATION R158
J 0
(-3100 4175);
DISPLAY 0.489362 (-3100 4175);
PAINT SKYBLUE (-3100 4175);
FORCEPROP 0 LAST $SEC 1
J 2
(-3100 4225);
DISPLAY 0.680851 (-3100 4225);
PAINT MONO (-3100 4225);
DISPLAY INVISIBLE (-3100 4225);
FORCEPROP 0 LAST CDS_SEC 1
J 2
(-3100 4225);
DISPLAY 1.021277 (-3100 4225);
DISPLAY INVISIBLE (-3100 4225);
FORCEPROP 1 LASTPIN (-3325 4175) $PN 1
J 0
(-3313 4187);
DISPLAY 0.489362 (-3313 4187);
PAINT MONO (-3313 4187);
FORCEPROP 1 LASTPIN (-3125 4175) $PN 2
J 0
(-3163 4187);
DISPLAY 0.489362 (-3163 4187);
PAINT MONO (-3163 4187);
FORCEPROP 1 LAST VALUE 33
J 2
(-3350 4175);
DISPLAY 0.489362 (-3350 4175);
PAINT SKYBLUE (-3350 4175);
FORCEPROP 1 LAST PACK_TYPE 0402LF
J 2
(-3050 4100);
DISPLAY 0.489362 (-3050 4100);
PAINT SKYBLUE (-3050 4100);
DISPLAY INVISIBLE (-3050 4100);
FORCEPROP 1 LAST TOLERANCE 5%
J 0
(-3350 4150);
DISPLAY 0.489362 (-3350 4150);
PAINT SKYBLUE (-3350 4150);
DISPLAY INVISIBLE (-3350 4150);
FORCEPROP 1 LAST MATERIAL CHIP
J 2
(-3050 4150);
DISPLAY 0.489362 (-3050 4150);
PAINT SKYBLUE (-3050 4150);
DISPLAY INVISIBLE (-3050 4150);
FORCEPROP 1 LAST WATTAGE 1/16W
J 2
(-3300 4100);
DISPLAY 0.489362 (-3300 4100);
PAINT SKYBLUE (-3300 4100);
DISPLAY INVISIBLE (-3300 4100);
FORCEPROP 2 LAST BOM_COST MEM
J 2
(-3200 4325);
DISPLAY 0.744681 (-3200 4325);
PAINT WHITE (-3200 4325);
DISPLAY INVISIBLE (-3200 4325);
FORCEPROP 2 LAST CDS_LIB pure_quanta
J 2
(-3225 4175);
DISPLAY INVISIBLE (-3225 4175);
FORCEPROP 1 LAST PATH I154
J 0
(-3275 4325);
DISPLAY 0.978723 (-3275 4325);
PAINT WHITE (-3275 4325);
DISPLAY INVISIBLE (-3275 4325);
FORCEPROP 1 LAST PART_NUMBER CS03302JB10
J 2
(-3125 4225);
DISPLAY 0.489362 (-3125 4225);
PAINT SKYBLUE (-3125 4225);
DISPLAY INVISIBLE (-3125 4225);
FORCEADD Q_RES..1
(-3225 4225);
FORCEPROP 1 LAST LOCATION R395
J 0
(-3100 4225);
DISPLAY 0.489362 (-3100 4225);
PAINT SKYBLUE (-3100 4225);
FORCEPROP 0 LAST $SEC 1
J 0
(-3100 4275);
DISPLAY 0.680851 (-3100 4275);
PAINT MONO (-3100 4275);
DISPLAY INVISIBLE (-3100 4275);
FORCEPROP 0 LAST CDS_SEC 1
J 0
(-3100 4275);
DISPLAY 0.680851 (-3100 4275);
DISPLAY INVISIBLE (-3100 4275);
FORCEPROP 1 LASTPIN (-3325 4225) $PN 1
J 0
(-3313 4237);
DISPLAY 0.489362 (-3313 4237);
PAINT MONO (-3313 4237);
FORCEPROP 1 LASTPIN (-3125 4225) $PN 2
J 0
(-3163 4237);
DISPLAY 0.489362 (-3163 4237);
PAINT MONO (-3163 4237);
FORCEPROP 1 LAST VALUE 0
J 2
(-3350 4225);
DISPLAY 0.489362 (-3350 4225);
PAINT SKYBLUE (-3350 4225);
FORCEPROP 1 LAST PACK_TYPE 0402LF
J 2
(-3050 4150);
DISPLAY 0.489362 (-3050 4150);
PAINT SKYBLUE (-3050 4150);
DISPLAY INVISIBLE (-3050 4150);
FORCEPROP 1 LAST TOLERANCE 5%
J 0
(-3350 4200);
DISPLAY 0.489362 (-3350 4200);
PAINT SKYBLUE (-3350 4200);
DISPLAY INVISIBLE (-3350 4200);
FORCEPROP 1 LAST MATERIAL CHIP
J 2
(-3050 4200);
DISPLAY 0.489362 (-3050 4200);
PAINT SKYBLUE (-3050 4200);
DISPLAY INVISIBLE (-3050 4200);
FORCEPROP 1 LAST WATTAGE 1/16W
J 2
(-3300 4150);
DISPLAY 0.489362 (-3300 4150);
PAINT SKYBLUE (-3300 4150);
DISPLAY INVISIBLE (-3300 4150);
FORCEPROP 2 LAST BOM_COST MEM
J 2
(-3200 4375);
DISPLAY 0.744681 (-3200 4375);
PAINT WHITE (-3200 4375);
DISPLAY INVISIBLE (-3200 4375);
FORCEPROP 2 LAST CDS_LIB pure_quanta
J 0
(-3225 4225);
DISPLAY INVISIBLE (-3225 4225);
FORCEPROP 1 LAST PATH I155
J 0
(-3275 4375);
DISPLAY 0.978723 (-3275 4375);
PAINT WHITE (-3275 4375);
DISPLAY INVISIBLE (-3275 4375);
FORCEPROP 1 LAST PART_NUMBER CS00002JB13
J 2
(-3125 4275);
DISPLAY 0.489362 (-3125 4275);
PAINT SKYBLUE (-3125 4275);
DISPLAY INVISIBLE (-3125 4275);
FORCEADD Q_RES..1
(-3225 4325);
FORCEPROP 1 LAST LOCATION R1564
J 0
(-3100 4325);
DISPLAY 0.489362 (-3100 4325);
PAINT SKYBLUE (-3100 4325);
FORCEPROP 0 LAST $SEC 1
J 0
(-3100 4350);
DISPLAY 0.680851 (-3100 4350);
PAINT MONO (-3100 4350);
DISPLAY INVISIBLE (-3100 4350);
FORCEPROP 0 LAST CDS_SEC 1
J 0
(-3100 4350);
DISPLAY 0.680851 (-3100 4350);
DISPLAY INVISIBLE (-3100 4350);
FORCEPROP 1 LASTPIN (-3325 4325) $PN 1
J 0
(-3313 4337);
DISPLAY 0.787234 (-3313 4337);
PAINT MONO (-3313 4337);
FORCEPROP 1 LASTPIN (-3125 4325) $PN 2
J 0
(-3163 4337);
DISPLAY 0.787234 (-3163 4337);
PAINT MONO (-3163 4337);
FORCEPROP 1 LAST VALUE 33
J 2
(-3350 4325);
DISPLAY 0.489362 (-3350 4325);
PAINT SKYBLUE (-3350 4325);
FORCEPROP 1 LAST PACK_TYPE 0402LF
J 2
(-3050 4250);
DISPLAY 0.489362 (-3050 4250);
PAINT SKYBLUE (-3050 4250);
DISPLAY INVISIBLE (-3050 4250);
FORCEPROP 1 LAST TOLERANCE 5%
J 0
(-3350 4300);
DISPLAY 0.489362 (-3350 4300);
PAINT SKYBLUE (-3350 4300);
DISPLAY INVISIBLE (-3350 4300);
FORCEPROP 1 LAST MATERIAL CHIP
J 2
(-3050 4300);
DISPLAY 0.489362 (-3050 4300);
PAINT SKYBLUE (-3050 4300);
DISPLAY INVISIBLE (-3050 4300);
FORCEPROP 1 LAST WATTAGE 1/16W
J 2
(-3300 4250);
DISPLAY 0.489362 (-3300 4250);
PAINT SKYBLUE (-3300 4250);
DISPLAY INVISIBLE (-3300 4250);
FORCEPROP 2 LAST BOM_COST MEM
J 2
(-3200 4475);
DISPLAY 0.744681 (-3200 4475);
PAINT WHITE (-3200 4475);
DISPLAY INVISIBLE (-3200 4475);
FORCEPROP 2 LAST CDS_LIB pure_quanta
J 0
(-3225 4325);
DISPLAY INVISIBLE (-3225 4325);
FORCEPROP 1 LAST PATH I156
J 0
(-3275 4475);
DISPLAY 0.978723 (-3275 4475);
PAINT WHITE (-3275 4475);
DISPLAY INVISIBLE (-3275 4475);
FORCEPROP 1 LAST PART_NUMBER CS03302JB10
J 2
(-3125 4375);
DISPLAY 0.489362 (-3125 4375);
PAINT SKYBLUE (-3125 4375);
DISPLAY INVISIBLE (-3125 4375);
FORCEADD Q_RES..1
(-3225 4275);
FORCEPROP 1 LAST LOCATION R1616
J 0
(-3100 4275);
DISPLAY 0.489362 (-3100 4275);
PAINT SKYBLUE (-3100 4275);
FORCEPROP 0 LAST $SEC 1
J 0
(-3100 4300);
DISPLAY 0.680851 (-3100 4300);
PAINT MONO (-3100 4300);
DISPLAY INVISIBLE (-3100 4300);
FORCEPROP 0 LAST CDS_SEC 1
J 0
(-3100 4300);
DISPLAY 0.680851 (-3100 4300);
DISPLAY INVISIBLE (-3100 4300);
FORCEPROP 1 LASTPIN (-3325 4275) $PN 1
J 0
(-3313 4287);
DISPLAY 0.787234 (-3313 4287);
PAINT MONO (-3313 4287);
FORCEPROP 1 LASTPIN (-3125 4275) $PN 2
J 0
(-3163 4287);
DISPLAY 0.787234 (-3163 4287);
PAINT MONO (-3163 4287);
FORCEPROP 1 LAST VALUE 33
J 2
(-3350 4275);
DISPLAY 0.489362 (-3350 4275);
PAINT SKYBLUE (-3350 4275);
FORCEPROP 1 LAST PACK_TYPE 0402LF
J 2
(-3050 4200);
DISPLAY 0.489362 (-3050 4200);
PAINT SKYBLUE (-3050 4200);
DISPLAY INVISIBLE (-3050 4200);
FORCEPROP 1 LAST TOLERANCE 5%
J 0
(-3350 4250);
DISPLAY 0.489362 (-3350 4250);
PAINT SKYBLUE (-3350 4250);
DISPLAY INVISIBLE (-3350 4250);
FORCEPROP 1 LAST MATERIAL CHIP
J 2
(-3050 4250);
DISPLAY 0.489362 (-3050 4250);
PAINT SKYBLUE (-3050 4250);
DISPLAY INVISIBLE (-3050 4250);
FORCEPROP 1 LAST WATTAGE 1/16W
J 2
(-3300 4200);
DISPLAY 0.489362 (-3300 4200);
PAINT SKYBLUE (-3300 4200);
DISPLAY INVISIBLE (-3300 4200);
FORCEPROP 2 LAST BOM_COST MEM
J 2
(-3200 4425);
DISPLAY 0.744681 (-3200 4425);
PAINT WHITE (-3200 4425);
DISPLAY INVISIBLE (-3200 4425);
FORCEPROP 2 LAST CDS_LIB pure_quanta
J 0
(-3225 4275);
DISPLAY INVISIBLE (-3225 4275);
FORCEPROP 1 LAST PATH I157
J 0
(-3275 4425);
DISPLAY 0.978723 (-3275 4425);
PAINT WHITE (-3275 4425);
DISPLAY INVISIBLE (-3275 4425);
FORCEPROP 1 LAST PART_NUMBER CS03302JB10
J 2
(-3125 4325);
DISPLAY 0.489362 (-3125 4325);
PAINT SKYBLUE (-3125 4325);
DISPLAY INVISIBLE (-3125 4325);
FORCEADD Q_RES..1
(-3225 4375);
FORCEPROP 1 LAST LOCATION R1359
J 0
(-3100 4375);
DISPLAY 0.489362 (-3100 4375);
PAINT SKYBLUE (-3100 4375);
FORCEPROP 0 LAST $SEC 1
J 0
(-3100 4425);
DISPLAY 0.680851 (-3100 4425);
PAINT MONO (-3100 4425);
DISPLAY INVISIBLE (-3100 4425);
FORCEPROP 0 LAST CDS_SEC 1
J 0
(-3100 4425);
DISPLAY 0.680851 (-3100 4425);
DISPLAY INVISIBLE (-3100 4425);
FORCEPROP 1 LASTPIN (-3325 4375) $PN 1
J 0
(-3313 4387);
DISPLAY 0.489362 (-3313 4387);
PAINT MONO (-3313 4387);
FORCEPROP 1 LASTPIN (-3125 4375) $PN 2
J 0
(-3163 4387);
DISPLAY 0.489362 (-3163 4387);
PAINT MONO (-3163 4387);
FORCEPROP 1 LAST VALUE 0
J 2
(-3350 4375);
DISPLAY 0.489362 (-3350 4375);
PAINT SKYBLUE (-3350 4375);
FORCEPROP 2 LAST BOM_COST MEM
J 2
(-3200 4525);
DISPLAY 0.744681 (-3200 4525);
PAINT WHITE (-3200 4525);
DISPLAY INVISIBLE (-3200 4525);
FORCEPROP 2 LAST CDS_LIB pure_quanta
J 0
(-3225 4375);
DISPLAY INVISIBLE (-3225 4375);
FORCEPROP 1 LAST WATTAGE 1/16W
J 2
(-3300 4300);
DISPLAY 0.489362 (-3300 4300);
PAINT SKYBLUE (-3300 4300);
DISPLAY INVISIBLE (-3300 4300);
FORCEPROP 1 LAST MATERIAL CHIP
J 2
(-3050 4350);
DISPLAY 0.489362 (-3050 4350);
PAINT SKYBLUE (-3050 4350);
DISPLAY INVISIBLE (-3050 4350);
FORCEPROP 1 LAST TOLERANCE 5%
J 0
(-3350 4350);
DISPLAY 0.489362 (-3350 4350);
PAINT SKYBLUE (-3350 4350);
DISPLAY INVISIBLE (-3350 4350);
FORCEPROP 1 LAST PACK_TYPE 0402LF
J 2
(-3050 4300);
DISPLAY 0.489362 (-3050 4300);
PAINT SKYBLUE (-3050 4300);
DISPLAY INVISIBLE (-3050 4300);
FORCEPROP 1 LAST PATH I158
J 0
(-3275 4525);
DISPLAY 0.978723 (-3275 4525);
PAINT WHITE (-3275 4525);
DISPLAY INVISIBLE (-3275 4525);
FORCEPROP 1 LAST PART_NUMBER CS00002JB13
J 2
(-3125 4425);
DISPLAY 0.489362 (-3125 4425);
PAINT SKYBLUE (-3125 4425);
DISPLAY INVISIBLE (-3125 4425);
FORCEADD Q_RES..1
(-3225 4475);
FORCEPROP 1 LAST LOCATION R372
J 0
(-3100 4475);
DISPLAY 0.489362 (-3100 4475);
PAINT SKYBLUE (-3100 4475);
FORCEPROP 0 LAST $SEC 1
J 0
(-3100 4525);
DISPLAY 0.680851 (-3100 4525);
PAINT MONO (-3100 4525);
DISPLAY INVISIBLE (-3100 4525);
FORCEPROP 0 LAST CDS_SEC 1
J 0
(-3100 4525);
DISPLAY 0.680851 (-3100 4525);
DISPLAY INVISIBLE (-3100 4525);
FORCEPROP 1 LASTPIN (-3325 4475) $PN 1
J 0
(-3313 4487);
DISPLAY 0.489362 (-3313 4487);
PAINT MONO (-3313 4487);
FORCEPROP 1 LASTPIN (-3125 4475) $PN 2
J 0
(-3163 4487);
DISPLAY 0.489362 (-3163 4487);
PAINT MONO (-3163 4487);
FORCEPROP 1 LAST VALUE 33
J 2
(-3350 4475);
DISPLAY 0.489362 (-3350 4475);
PAINT SKYBLUE (-3350 4475);
FORCEPROP 1 LAST PACK_TYPE 0402LF
J 2
(-3050 4400);
DISPLAY 0.489362 (-3050 4400);
PAINT SKYBLUE (-3050 4400);
DISPLAY INVISIBLE (-3050 4400);
FORCEPROP 1 LAST TOLERANCE 5%
J 0
(-3350 4450);
DISPLAY 0.489362 (-3350 4450);
PAINT SKYBLUE (-3350 4450);
DISPLAY INVISIBLE (-3350 4450);
FORCEPROP 1 LAST MATERIAL CHIP
J 2
(-3050 4450);
DISPLAY 0.489362 (-3050 4450);
PAINT SKYBLUE (-3050 4450);
DISPLAY INVISIBLE (-3050 4450);
FORCEPROP 1 LAST WATTAGE 1/16W
J 2
(-3300 4400);
DISPLAY 0.489362 (-3300 4400);
PAINT SKYBLUE (-3300 4400);
DISPLAY INVISIBLE (-3300 4400);
FORCEPROP 2 LAST BOM_COST MEM
J 2
(-3200 4625);
DISPLAY 0.744681 (-3200 4625);
PAINT WHITE (-3200 4625);
DISPLAY INVISIBLE (-3200 4625);
FORCEPROP 2 LAST CDS_LIB pure_quanta
J 0
(-3225 4475);
DISPLAY INVISIBLE (-3225 4475);
FORCEPROP 1 LAST PATH I159
J 0
(-3275 4625);
DISPLAY 0.978723 (-3275 4625);
PAINT WHITE (-3275 4625);
DISPLAY INVISIBLE (-3275 4625);
FORCEPROP 1 LAST PART_NUMBER CS03302JB10
J 2
(-3125 4525);
DISPLAY 0.489362 (-3125 4525);
PAINT SKYBLUE (-3125 4525);
DISPLAY INVISIBLE (-3125 4525);
FORCEADD OFFPAGE..5
(-7800 1875);
FORCEPROP 2 LAST $XR0 192 
J 0
(-8055 1875);
DISPLAY 0.638298 (-8055 1875);
PAINT MONO (-8055 1875);
FORCEPROP 2 LAST CDS_LIB standard
J 0
(-7800 1875);
DISPLAY INVISIBLE (-7800 1875);
FORCEPROP 1 LAST OFFPAGE TRUE
J 0
(-7475 1750);
DISPLAY 0.872340 (-7475 1750);
PAINT GREEN (-7475 1750);
DISPLAY INVISIBLE (-7475 1750);
FORCEPROP 1 LAST COMMENT_BODY TRUE
J 0
(-7700 1800);
DISPLAY 0.872340 (-7700 1800);
PAINT GREEN (-7700 1800);
DISPLAY INVISIBLE (-7700 1800);
FORCEPROP 2 LAST PATH I16
J 0
(-8075 1925);
DISPLAY 0.680851 (-8075 1925);
DISPLAY INVISIBLE (-8075 1925);
FORCEADD Q_RES..1
(-3225 4575);
FORCEPROP 1 LAST LOCATION R174
J 0
(-3100 4575);
DISPLAY 0.489362 (-3100 4575);
PAINT SKYBLUE (-3100 4575);
FORCEPROP 0 LAST $SEC 1
J 0
(-3100 4625);
DISPLAY 0.680851 (-3100 4625);
PAINT MONO (-3100 4625);
DISPLAY INVISIBLE (-3100 4625);
FORCEPROP 0 LAST CDS_SEC 1
J 0
(-3100 4625);
DISPLAY 0.680851 (-3100 4625);
DISPLAY INVISIBLE (-3100 4625);
FORCEPROP 1 LASTPIN (-3325 4575) $PN 1
J 0
(-3313 4587);
DISPLAY 0.489362 (-3313 4587);
PAINT MONO (-3313 4587);
FORCEPROP 1 LASTPIN (-3125 4575) $PN 2
J 0
(-3163 4587);
DISPLAY 0.489362 (-3163 4587);
PAINT MONO (-3163 4587);
FORCEPROP 1 LAST VALUE 33
J 2
(-3350 4575);
DISPLAY 0.489362 (-3350 4575);
PAINT SKYBLUE (-3350 4575);
FORCEPROP 2 LAST CDS_LIB pure_quanta
J 0
(-3225 4575);
DISPLAY INVISIBLE (-3225 4575);
FORCEPROP 2 LAST BOM_COST MEM
J 2
(-3200 4725);
DISPLAY 0.744681 (-3200 4725);
PAINT WHITE (-3200 4725);
DISPLAY INVISIBLE (-3200 4725);
FORCEPROP 1 LAST WATTAGE 1/16W
J 2
(-3300 4500);
DISPLAY 0.489362 (-3300 4500);
PAINT SKYBLUE (-3300 4500);
DISPLAY INVISIBLE (-3300 4500);
FORCEPROP 1 LAST MATERIAL CHIP
J 2
(-3050 4550);
DISPLAY 0.489362 (-3050 4550);
PAINT SKYBLUE (-3050 4550);
DISPLAY INVISIBLE (-3050 4550);
FORCEPROP 1 LAST TOLERANCE 5%
J 0
(-3350 4550);
DISPLAY 0.489362 (-3350 4550);
PAINT SKYBLUE (-3350 4550);
DISPLAY INVISIBLE (-3350 4550);
FORCEPROP 1 LAST PACK_TYPE 0402LF
J 2
(-3050 4500);
DISPLAY 0.489362 (-3050 4500);
PAINT SKYBLUE (-3050 4500);
DISPLAY INVISIBLE (-3050 4500);
FORCEPROP 1 LAST PATH I160
J 0
(-3275 4725);
DISPLAY 0.978723 (-3275 4725);
PAINT WHITE (-3275 4725);
DISPLAY INVISIBLE (-3275 4725);
FORCEPROP 1 LAST PART_NUMBER CS03302JB10
J 2
(-3125 4625);
DISPLAY 0.489362 (-3125 4625);
PAINT SKYBLUE (-3125 4625);
DISPLAY INVISIBLE (-3125 4625);
FORCEADD Q_RES..1
(-3225 4625);
FORCEPROP 1 LAST LOCATION R161
J 0
(-3100 4625);
DISPLAY 0.489362 (-3100 4625);
PAINT SKYBLUE (-3100 4625);
FORCEPROP 0 LAST $SEC 1
J 2
(-3100 4675);
DISPLAY 0.680851 (-3100 4675);
PAINT MONO (-3100 4675);
DISPLAY INVISIBLE (-3100 4675);
FORCEPROP 0 LAST CDS_SEC 1
J 2
(-3100 4675);
DISPLAY 1.021277 (-3100 4675);
DISPLAY INVISIBLE (-3100 4675);
FORCEPROP 1 LASTPIN (-3325 4625) $PN 1
J 0
(-3313 4637);
DISPLAY 0.489362 (-3313 4637);
PAINT MONO (-3313 4637);
FORCEPROP 1 LASTPIN (-3125 4625) $PN 2
J 0
(-3163 4637);
DISPLAY 0.489362 (-3163 4637);
PAINT MONO (-3163 4637);
FORCEPROP 1 LAST VALUE 33
J 2
(-3350 4625);
DISPLAY 0.489362 (-3350 4625);
PAINT SKYBLUE (-3350 4625);
FORCEPROP 2 LAST CDS_LIB pure_quanta
J 2
(-3225 4625);
DISPLAY INVISIBLE (-3225 4625);
FORCEPROP 2 LAST BOM_COST MEM
J 2
(-3200 4775);
DISPLAY 0.744681 (-3200 4775);
PAINT WHITE (-3200 4775);
DISPLAY INVISIBLE (-3200 4775);
FORCEPROP 1 LAST WATTAGE 1/16W
J 2
(-3300 4550);
DISPLAY 0.489362 (-3300 4550);
PAINT SKYBLUE (-3300 4550);
DISPLAY INVISIBLE (-3300 4550);
FORCEPROP 1 LAST MATERIAL CHIP
J 2
(-3050 4600);
DISPLAY 0.489362 (-3050 4600);
PAINT SKYBLUE (-3050 4600);
DISPLAY INVISIBLE (-3050 4600);
FORCEPROP 1 LAST TOLERANCE 5%
J 0
(-3350 4600);
DISPLAY 0.489362 (-3350 4600);
PAINT SKYBLUE (-3350 4600);
DISPLAY INVISIBLE (-3350 4600);
FORCEPROP 1 LAST PACK_TYPE 0402LF
J 2
(-3050 4550);
DISPLAY 0.489362 (-3050 4550);
PAINT SKYBLUE (-3050 4550);
DISPLAY INVISIBLE (-3050 4550);
FORCEPROP 1 LAST PATH I161
J 0
(-3275 4775);
DISPLAY 0.978723 (-3275 4775);
PAINT WHITE (-3275 4775);
DISPLAY INVISIBLE (-3275 4775);
FORCEPROP 1 LAST PART_NUMBER CS03302JB10
J 2
(-3125 4675);
DISPLAY 0.489362 (-3125 4675);
PAINT SKYBLUE (-3125 4675);
DISPLAY INVISIBLE (-3125 4675);
FORCEADD Q_RES..1
(-3225 4725);
FORCEPROP 1 LAST LOCATION R251
J 0
(-3100 4725);
DISPLAY 0.489362 (-3100 4725);
PAINT SKYBLUE (-3100 4725);
FORCEPROP 0 LAST $SEC 1
J 2
(-3100 4775);
DISPLAY 0.680851 (-3100 4775);
PAINT MONO (-3100 4775);
DISPLAY INVISIBLE (-3100 4775);
FORCEPROP 0 LAST CDS_SEC 1
J 2
(-3100 4775);
DISPLAY 1.021277 (-3100 4775);
DISPLAY INVISIBLE (-3100 4775);
FORCEPROP 1 LASTPIN (-3325 4725) $PN 1
J 0
(-3313 4737);
DISPLAY 0.489362 (-3313 4737);
PAINT MONO (-3313 4737);
FORCEPROP 1 LASTPIN (-3125 4725) $PN 2
J 0
(-3163 4737);
DISPLAY 0.489362 (-3163 4737);
PAINT MONO (-3163 4737);
FORCEPROP 1 LAST VALUE 0
J 2
(-3350 4725);
DISPLAY 0.489362 (-3350 4725);
PAINT SKYBLUE (-3350 4725);
FORCEPROP 2 LAST CDS_LIB pure_quanta
J 2
(-3225 4725);
DISPLAY INVISIBLE (-3225 4725);
FORCEPROP 2 LAST BOM_COST MEM
J 2
(-3200 4875);
DISPLAY 0.744681 (-3200 4875);
PAINT WHITE (-3200 4875);
DISPLAY INVISIBLE (-3200 4875);
FORCEPROP 1 LAST WATTAGE 1/16W
J 2
(-3300 4650);
DISPLAY 0.489362 (-3300 4650);
PAINT SKYBLUE (-3300 4650);
DISPLAY INVISIBLE (-3300 4650);
FORCEPROP 1 LAST MATERIAL CHIP
J 2
(-3050 4700);
DISPLAY 0.489362 (-3050 4700);
PAINT SKYBLUE (-3050 4700);
DISPLAY INVISIBLE (-3050 4700);
FORCEPROP 1 LAST TOLERANCE 5%
J 0
(-3350 4700);
DISPLAY 0.489362 (-3350 4700);
PAINT SKYBLUE (-3350 4700);
DISPLAY INVISIBLE (-3350 4700);
FORCEPROP 1 LAST PACK_TYPE 0402LF
J 2
(-3050 4650);
DISPLAY 0.489362 (-3050 4650);
PAINT SKYBLUE (-3050 4650);
DISPLAY INVISIBLE (-3050 4650);
FORCEPROP 1 LAST PATH I162
J 0
(-3275 4875);
DISPLAY 0.978723 (-3275 4875);
PAINT WHITE (-3275 4875);
DISPLAY INVISIBLE (-3275 4875);
FORCEPROP 1 LAST PART_NUMBER CS00002JB13
J 2
(-3125 4775);
DISPLAY 0.489362 (-3125 4775);
PAINT SKYBLUE (-3125 4775);
DISPLAY INVISIBLE (-3125 4775);
FORCEADD Q_RES..1
(-3225 4675);
FORCEPROP 1 LAST LOCATION R173
J 0
(-3100 4675);
DISPLAY 0.489362 (-3100 4675);
PAINT SKYBLUE (-3100 4675);
FORCEPROP 0 LAST $SEC 1
J 2
(-3100 4725);
DISPLAY 0.680851 (-3100 4725);
PAINT MONO (-3100 4725);
DISPLAY INVISIBLE (-3100 4725);
FORCEPROP 0 LAST CDS_SEC 1
J 2
(-3100 4725);
DISPLAY 1.021277 (-3100 4725);
DISPLAY INVISIBLE (-3100 4725);
FORCEPROP 1 LASTPIN (-3325 4675) $PN 1
J 0
(-3313 4687);
DISPLAY 0.489362 (-3313 4687);
PAINT MONO (-3313 4687);
FORCEPROP 1 LASTPIN (-3125 4675) $PN 2
J 0
(-3163 4687);
DISPLAY 0.489362 (-3163 4687);
PAINT MONO (-3163 4687);
FORCEPROP 1 LAST VALUE 33
J 2
(-3350 4675);
DISPLAY 0.489362 (-3350 4675);
PAINT SKYBLUE (-3350 4675);
FORCEPROP 2 LAST BOM_COST MEM
J 2
(-3200 4825);
DISPLAY 0.744681 (-3200 4825);
PAINT WHITE (-3200 4825);
DISPLAY INVISIBLE (-3200 4825);
FORCEPROP 2 LAST CDS_LIB pure_quanta
J 2
(-3225 4675);
DISPLAY INVISIBLE (-3225 4675);
FORCEPROP 1 LAST WATTAGE 1/16W
J 2
(-3300 4600);
DISPLAY 0.489362 (-3300 4600);
PAINT SKYBLUE (-3300 4600);
DISPLAY INVISIBLE (-3300 4600);
FORCEPROP 1 LAST MATERIAL CHIP
J 2
(-3050 4650);
DISPLAY 0.489362 (-3050 4650);
PAINT SKYBLUE (-3050 4650);
DISPLAY INVISIBLE (-3050 4650);
FORCEPROP 1 LAST TOLERANCE 5%
J 0
(-3350 4650);
DISPLAY 0.489362 (-3350 4650);
PAINT SKYBLUE (-3350 4650);
DISPLAY INVISIBLE (-3350 4650);
FORCEPROP 1 LAST PACK_TYPE 0402LF
J 2
(-3050 4600);
DISPLAY 0.489362 (-3050 4600);
PAINT SKYBLUE (-3050 4600);
DISPLAY INVISIBLE (-3050 4600);
FORCEPROP 1 LAST PATH I163
J 0
(-3275 4825);
DISPLAY 0.978723 (-3275 4825);
PAINT WHITE (-3275 4825);
DISPLAY INVISIBLE (-3275 4825);
FORCEPROP 1 LAST PART_NUMBER CS03302JB10
J 2
(-3125 4725);
DISPLAY 0.489362 (-3125 4725);
PAINT SKYBLUE (-3125 4725);
DISPLAY INVISIBLE (-3125 4725);
FORCEADD Q_RES..1
(-3225 4825);
FORCEPROP 1 LAST LOCATION R588
J 0
(-3100 4825);
DISPLAY 0.489362 (-3100 4825);
PAINT SKYBLUE (-3100 4825);
FORCEPROP 0 LAST $SEC 1
J 0
(-3275 4925);
DISPLAY 0.680851 (-3275 4925);
PAINT MONO (-3275 4925);
DISPLAY INVISIBLE (-3275 4925);
FORCEPROP 0 LAST CDS_SEC 1
J 0
(-3275 4925);
DISPLAY 1.021277 (-3275 4925);
DISPLAY INVISIBLE (-3275 4925);
FORCEPROP 1 LASTPIN (-3325 4825) $PN 1
J 0
(-3313 4837);
DISPLAY 0.489362 (-3313 4837);
PAINT MONO (-3313 4837);
FORCEPROP 1 LASTPIN (-3125 4825) $PN 2
J 0
(-3163 4837);
DISPLAY 0.489362 (-3163 4837);
PAINT MONO (-3163 4837);
FORCEPROP 1 LAST VALUE 33
J 2
(-3350 4825);
DISPLAY 0.489362 (-3350 4825);
PAINT SKYBLUE (-3350 4825);
FORCEPROP 2 LAST CDS_LIB pure_quanta
J 0
(-3225 4825);
DISPLAY INVISIBLE (-3225 4825);
FORCEPROP 2 LAST BOM_COST MEM
J 2
(-3200 4975);
DISPLAY 0.744681 (-3200 4975);
PAINT WHITE (-3200 4975);
DISPLAY INVISIBLE (-3200 4975);
FORCEPROP 1 LAST WATTAGE 1/16W
J 2
(-3300 4750);
DISPLAY 0.489362 (-3300 4750);
PAINT SKYBLUE (-3300 4750);
DISPLAY INVISIBLE (-3300 4750);
FORCEPROP 1 LAST MATERIAL CHIP
J 2
(-3050 4800);
DISPLAY 0.489362 (-3050 4800);
PAINT SKYBLUE (-3050 4800);
DISPLAY INVISIBLE (-3050 4800);
FORCEPROP 1 LAST TOLERANCE 5%
J 0
(-3350 4800);
DISPLAY 0.489362 (-3350 4800);
PAINT SKYBLUE (-3350 4800);
DISPLAY INVISIBLE (-3350 4800);
FORCEPROP 1 LAST PACK_TYPE 0402LF
J 2
(-3050 4750);
DISPLAY 0.489362 (-3050 4750);
PAINT SKYBLUE (-3050 4750);
DISPLAY INVISIBLE (-3050 4750);
FORCEPROP 1 LAST PATH I164
J 0
(-3275 4975);
DISPLAY 0.978723 (-3275 4975);
PAINT WHITE (-3275 4975);
DISPLAY INVISIBLE (-3275 4975);
FORCEPROP 1 LAST PART_NUMBER CS03302JB10
J 2
(-3125 4875);
DISPLAY 0.489362 (-3125 4875);
PAINT SKYBLUE (-3125 4875);
DISPLAY INVISIBLE (-3125 4875);
FORCEADD Q_RES..1
(-3225 4925);
FORCEPROP 1 LAST LOCATION R277
J 0
(-3100 4925);
DISPLAY 0.489362 (-3100 4925);
PAINT SKYBLUE (-3100 4925);
FORCEPROP 0 LAST $SEC 1
J 2
(-3100 4975);
DISPLAY 0.680851 (-3100 4975);
PAINT MONO (-3100 4975);
DISPLAY INVISIBLE (-3100 4975);
FORCEPROP 0 LAST CDS_SEC 1
J 2
(-3100 4975);
DISPLAY 1.021277 (-3100 4975);
DISPLAY INVISIBLE (-3100 4975);
FORCEPROP 1 LASTPIN (-3325 4925) $PN 1
J 0
(-3313 4937);
DISPLAY 0.489362 (-3313 4937);
PAINT MONO (-3313 4937);
FORCEPROP 1 LASTPIN (-3125 4925) $PN 2
J 0
(-3163 4937);
DISPLAY 0.489362 (-3163 4937);
PAINT MONO (-3163 4937);
FORCEPROP 1 LAST VALUE 33
J 2
(-3350 4925);
DISPLAY 0.489362 (-3350 4925);
PAINT SKYBLUE (-3350 4925);
FORCEPROP 2 LAST BOM_COST MEM
J 2
(-3200 5075);
DISPLAY 0.744681 (-3200 5075);
PAINT WHITE (-3200 5075);
DISPLAY INVISIBLE (-3200 5075);
FORCEPROP 2 LAST CDS_LIB pure_quanta
J 2
(-3225 4925);
DISPLAY INVISIBLE (-3225 4925);
FORCEPROP 1 LAST WATTAGE 1/16W
J 2
(-3300 4850);
DISPLAY 0.489362 (-3300 4850);
PAINT SKYBLUE (-3300 4850);
DISPLAY INVISIBLE (-3300 4850);
FORCEPROP 1 LAST MATERIAL CHIP
J 2
(-3050 4900);
DISPLAY 0.489362 (-3050 4900);
PAINT SKYBLUE (-3050 4900);
DISPLAY INVISIBLE (-3050 4900);
FORCEPROP 1 LAST TOLERANCE 5%
J 0
(-3350 4900);
DISPLAY 0.489362 (-3350 4900);
PAINT SKYBLUE (-3350 4900);
DISPLAY INVISIBLE (-3350 4900);
FORCEPROP 1 LAST PACK_TYPE 0402LF
J 2
(-3050 4850);
DISPLAY 0.489362 (-3050 4850);
PAINT SKYBLUE (-3050 4850);
DISPLAY INVISIBLE (-3050 4850);
FORCEPROP 1 LAST PATH I165
J 0
(-3275 5075);
DISPLAY 0.978723 (-3275 5075);
PAINT WHITE (-3275 5075);
DISPLAY INVISIBLE (-3275 5075);
FORCEPROP 1 LAST PART_NUMBER CS03302JB10
J 2
(-3125 4975);
DISPLAY 0.489362 (-3125 4975);
PAINT SKYBLUE (-3125 4975);
DISPLAY INVISIBLE (-3125 4975);
FORCEADD Q_RES..1
(-3225 5025);
FORCEPROP 1 LAST LOCATION R937
J 0
(-3100 5025);
DISPLAY 0.489362 (-3100 5025);
PAINT SKYBLUE (-3100 5025);
FORCEPROP 0 LAST $SEC 1
J 0
(-3275 5125);
DISPLAY 0.680851 (-3275 5125);
PAINT MONO (-3275 5125);
DISPLAY INVISIBLE (-3275 5125);
FORCEPROP 0 LAST CDS_SEC 1
J 0
(-3275 5125);
DISPLAY 0.680851 (-3275 5125);
DISPLAY INVISIBLE (-3275 5125);
FORCEPROP 1 LASTPIN (-3325 5025) $PN 1
J 0
(-3313 5037);
DISPLAY 0.489362 (-3313 5037);
PAINT MONO (-3313 5037);
FORCEPROP 1 LASTPIN (-3125 5025) $PN 2
J 0
(-3163 5037);
DISPLAY 0.489362 (-3163 5037);
PAINT MONO (-3163 5037);
FORCEPROP 1 LAST VALUE 0
J 2
(-3350 5025);
DISPLAY 0.489362 (-3350 5025);
PAINT SKYBLUE (-3350 5025);
FORCEPROP 2 LAST CDS_LIB pure_quanta
J 0
(-3225 5025);
DISPLAY INVISIBLE (-3225 5025);
FORCEPROP 2 LAST BOM_COST MEM
J 2
(-3200 5175);
DISPLAY 0.744681 (-3200 5175);
PAINT WHITE (-3200 5175);
DISPLAY INVISIBLE (-3200 5175);
FORCEPROP 1 LAST WATTAGE 1/16W
J 2
(-3300 4950);
DISPLAY 0.489362 (-3300 4950);
PAINT SKYBLUE (-3300 4950);
DISPLAY INVISIBLE (-3300 4950);
FORCEPROP 1 LAST MATERIAL CHIP
J 2
(-3050 5000);
DISPLAY 0.489362 (-3050 5000);
PAINT SKYBLUE (-3050 5000);
DISPLAY INVISIBLE (-3050 5000);
FORCEPROP 1 LAST TOLERANCE 5%
J 0
(-3350 5000);
DISPLAY 0.489362 (-3350 5000);
PAINT SKYBLUE (-3350 5000);
DISPLAY INVISIBLE (-3350 5000);
FORCEPROP 1 LAST PACK_TYPE 0402LF
J 2
(-3050 4950);
DISPLAY 0.489362 (-3050 4950);
PAINT SKYBLUE (-3050 4950);
DISPLAY INVISIBLE (-3050 4950);
FORCEPROP 1 LAST PATH I166
J 0
(-3275 5175);
DISPLAY 0.978723 (-3275 5175);
PAINT WHITE (-3275 5175);
DISPLAY INVISIBLE (-3275 5175);
FORCEPROP 1 LAST PART_NUMBER CS00002JB13
J 2
(-3125 5075);
DISPLAY 0.489362 (-3125 5075);
PAINT SKYBLUE (-3125 5075);
DISPLAY INVISIBLE (-3125 5075);
FORCEADD Q_RES..1
(-3225 5075);
FORCEPROP 1 LAST LOCATION R856
J 0
(-3100 5075);
DISPLAY 0.489362 (-3100 5075);
PAINT SKYBLUE (-3100 5075);
FORCEPROP 0 LAST $SEC 1
J 0
(-3100 5125);
DISPLAY 0.680851 (-3100 5125);
PAINT MONO (-3100 5125);
DISPLAY INVISIBLE (-3100 5125);
FORCEPROP 0 LAST CDS_SEC 1
J 0
(-3100 5125);
DISPLAY 0.680851 (-3100 5125);
DISPLAY INVISIBLE (-3100 5125);
FORCEPROP 1 LASTPIN (-3325 5075) $PN 1
J 0
(-3313 5087);
DISPLAY 0.489362 (-3313 5087);
PAINT MONO (-3313 5087);
FORCEPROP 1 LASTPIN (-3125 5075) $PN 2
J 0
(-3163 5087);
DISPLAY 0.489362 (-3163 5087);
PAINT MONO (-3163 5087);
FORCEPROP 1 LAST VALUE 0
J 2
(-3350 5075);
DISPLAY 0.489362 (-3350 5075);
PAINT SKYBLUE (-3350 5075);
FORCEPROP 2 LAST CDS_LIB pure_quanta
J 0
(-3225 5075);
DISPLAY INVISIBLE (-3225 5075);
FORCEPROP 2 LAST BOM_COST MEM
J 2
(-3200 5225);
DISPLAY 0.744681 (-3200 5225);
PAINT WHITE (-3200 5225);
DISPLAY INVISIBLE (-3200 5225);
FORCEPROP 1 LAST WATTAGE 1/16W
J 2
(-3300 5000);
DISPLAY 0.489362 (-3300 5000);
PAINT SKYBLUE (-3300 5000);
DISPLAY INVISIBLE (-3300 5000);
FORCEPROP 1 LAST MATERIAL CHIP
J 2
(-3050 5050);
DISPLAY 0.489362 (-3050 5050);
PAINT SKYBLUE (-3050 5050);
DISPLAY INVISIBLE (-3050 5050);
FORCEPROP 1 LAST TOLERANCE 5%
J 0
(-3350 5050);
DISPLAY 0.489362 (-3350 5050);
PAINT SKYBLUE (-3350 5050);
DISPLAY INVISIBLE (-3350 5050);
FORCEPROP 1 LAST PACK_TYPE 0402LF
J 2
(-3050 5000);
DISPLAY 0.489362 (-3050 5000);
PAINT SKYBLUE (-3050 5000);
DISPLAY INVISIBLE (-3050 5000);
FORCEPROP 1 LAST PATH I167
J 0
(-3275 5225);
DISPLAY 0.978723 (-3275 5225);
PAINT WHITE (-3275 5225);
DISPLAY INVISIBLE (-3275 5225);
FORCEPROP 1 LAST PART_NUMBER CS00002JB13
J 2
(-3125 5125);
DISPLAY 0.489362 (-3125 5125);
PAINT SKYBLUE (-3125 5125);
DISPLAY INVISIBLE (-3125 5125);
FORCEADD Q_RES..1
(-3225 5125);
FORCEPROP 1 LAST LOCATION R708
J 0
(-3100 5125);
DISPLAY 0.489362 (-3100 5125);
PAINT SKYBLUE (-3100 5125);
FORCEPROP 0 LAST $SEC 1
J 0
(-3100 5175);
DISPLAY 0.680851 (-3100 5175);
PAINT MONO (-3100 5175);
DISPLAY INVISIBLE (-3100 5175);
FORCEPROP 0 LAST CDS_SEC 1
J 0
(-3100 5175);
DISPLAY 0.680851 (-3100 5175);
DISPLAY INVISIBLE (-3100 5175);
FORCEPROP 1 LASTPIN (-3325 5125) $PN 1
J 0
(-3313 5137);
DISPLAY 0.489362 (-3313 5137);
PAINT MONO (-3313 5137);
FORCEPROP 1 LASTPIN (-3125 5125) $PN 2
J 0
(-3163 5137);
DISPLAY 0.489362 (-3163 5137);
PAINT MONO (-3163 5137);
FORCEPROP 1 LAST VALUE 33
J 2
(-3350 5125);
DISPLAY 0.489362 (-3350 5125);
PAINT SKYBLUE (-3350 5125);
FORCEPROP 2 LAST CDS_LIB pure_quanta
J 0
(-3225 5125);
DISPLAY INVISIBLE (-3225 5125);
FORCEPROP 2 LAST BOM_COST MEM
J 2
(-3200 5275);
DISPLAY 0.744681 (-3200 5275);
PAINT WHITE (-3200 5275);
DISPLAY INVISIBLE (-3200 5275);
FORCEPROP 1 LAST WATTAGE 1/16W
J 2
(-3300 5050);
DISPLAY 0.489362 (-3300 5050);
PAINT SKYBLUE (-3300 5050);
DISPLAY INVISIBLE (-3300 5050);
FORCEPROP 1 LAST MATERIAL CHIP
J 2
(-3050 5100);
DISPLAY 0.489362 (-3050 5100);
PAINT SKYBLUE (-3050 5100);
DISPLAY INVISIBLE (-3050 5100);
FORCEPROP 1 LAST TOLERANCE 5%
J 0
(-3350 5100);
DISPLAY 0.489362 (-3350 5100);
PAINT SKYBLUE (-3350 5100);
DISPLAY INVISIBLE (-3350 5100);
FORCEPROP 1 LAST PACK_TYPE 0402LF
J 2
(-3050 5050);
DISPLAY 0.489362 (-3050 5050);
PAINT SKYBLUE (-3050 5050);
DISPLAY INVISIBLE (-3050 5050);
FORCEPROP 1 LAST PATH I168
J 0
(-3275 5275);
DISPLAY 0.978723 (-3275 5275);
PAINT WHITE (-3275 5275);
DISPLAY INVISIBLE (-3275 5275);
FORCEPROP 1 LAST PART_NUMBER CS03302JB10
J 2
(-3125 5175);
DISPLAY 0.489362 (-3125 5175);
PAINT SKYBLUE (-3125 5175);
DISPLAY INVISIBLE (-3125 5175);
FORCEADD Q_RES..1
(-3225 5225);
FORCEPROP 1 LAST LOCATION R1551
J 0
(-3100 5225);
DISPLAY 0.489362 (-3100 5225);
PAINT SKYBLUE (-3100 5225);
FORCEPROP 0 LAST $SEC 1
J 0
(-3100 5250);
DISPLAY 0.680851 (-3100 5250);
PAINT MONO (-3100 5250);
DISPLAY INVISIBLE (-3100 5250);
FORCEPROP 0 LAST CDS_SEC 1
J 0
(-3100 5250);
DISPLAY 0.680851 (-3100 5250);
DISPLAY INVISIBLE (-3100 5250);
FORCEPROP 1 LASTPIN (-3325 5225) $PN 1
J 0
(-3313 5237);
DISPLAY 0.510638 (-3313 5237);
PAINT MONO (-3313 5237);
FORCEPROP 1 LASTPIN (-3125 5225) $PN 2
J 0
(-3163 5237);
DISPLAY 0.510638 (-3163 5237);
PAINT MONO (-3163 5237);
FORCEPROP 1 LAST VALUE 33
J 2
(-3350 5225);
DISPLAY 0.489362 (-3350 5225);
PAINT SKYBLUE (-3350 5225);
FORCEPROP 1 LAST PACK_TYPE 0402LF
J 2
(-3050 5150);
DISPLAY 0.489362 (-3050 5150);
PAINT SKYBLUE (-3050 5150);
DISPLAY INVISIBLE (-3050 5150);
FORCEPROP 1 LAST TOLERANCE 5%
J 0
(-3350 5200);
DISPLAY 0.489362 (-3350 5200);
PAINT SKYBLUE (-3350 5200);
DISPLAY INVISIBLE (-3350 5200);
FORCEPROP 1 LAST MATERIAL CHIP
J 2
(-3050 5200);
DISPLAY 0.489362 (-3050 5200);
PAINT SKYBLUE (-3050 5200);
DISPLAY INVISIBLE (-3050 5200);
FORCEPROP 1 LAST WATTAGE 1/16W
J 2
(-3300 5150);
DISPLAY 0.489362 (-3300 5150);
PAINT SKYBLUE (-3300 5150);
DISPLAY INVISIBLE (-3300 5150);
FORCEPROP 2 LAST BOM_COST MEM
J 2
(-3200 5375);
DISPLAY 0.744681 (-3200 5375);
PAINT WHITE (-3200 5375);
DISPLAY INVISIBLE (-3200 5375);
FORCEPROP 2 LAST CDS_LIB pure_quanta
J 0
(-3225 5225);
DISPLAY INVISIBLE (-3225 5225);
FORCEPROP 1 LAST PATH I169
J 0
(-3275 5375);
DISPLAY 0.978723 (-3275 5375);
PAINT WHITE (-3275 5375);
DISPLAY INVISIBLE (-3275 5375);
FORCEPROP 1 LAST PART_NUMBER CS03302JB10
J 2
(-3125 5275);
DISPLAY 0.489362 (-3125 5275);
PAINT SKYBLUE (-3125 5275);
DISPLAY INVISIBLE (-3125 5275);
FORCEADD OFFPAGE..1
(-7800 2025);
FORCEPROP 2 LAST $XR0 167 
J 0
(-8052 2025);
DISPLAY 0.638298 (-8052 2025);
PAINT MONO (-8052 2025);
FORCEPROP 2 LAST CDS_LIB standard
J 0
(-7800 2025);
DISPLAY INVISIBLE (-7800 2025);
FORCEPROP 1 LAST OFFPAGE TRUE
J 0
(-7475 1900);
DISPLAY 0.872340 (-7475 1900);
DISPLAY INVISIBLE (-7475 1900);
FORCEPROP 1 LAST COMMENT_BODY TRUE
J 0
(-7675 1925);
DISPLAY 0.872340 (-7675 1925);
PAINT GREEN (-7675 1925);
DISPLAY INVISIBLE (-7675 1925);
FORCEPROP 2 LAST PATH I17
J 0
(-7750 2100);
DISPLAY 0.680851 (-7750 2100);
DISPLAY INVISIBLE (-7750 2100);
FORCEADD Q_RES..1
(-3225 5175);
FORCEPROP 1 LAST LOCATION R1552
J 0
(-3100 5175);
DISPLAY 0.489362 (-3100 5175);
PAINT SKYBLUE (-3100 5175);
FORCEPROP 0 LAST $SEC 1
J 0
(-3100 5200);
DISPLAY 0.680851 (-3100 5200);
PAINT MONO (-3100 5200);
DISPLAY INVISIBLE (-3100 5200);
FORCEPROP 0 LAST CDS_SEC 1
J 0
(-3100 5200);
DISPLAY 0.680851 (-3100 5200);
DISPLAY INVISIBLE (-3100 5200);
FORCEPROP 1 LASTPIN (-3325 5175) $PN 1
J 0
(-3313 5187);
DISPLAY 0.510638 (-3313 5187);
PAINT MONO (-3313 5187);
FORCEPROP 1 LASTPIN (-3125 5175) $PN 2
J 0
(-3163 5187);
DISPLAY 0.510638 (-3163 5187);
PAINT MONO (-3163 5187);
FORCEPROP 1 LAST VALUE 33
J 2
(-3350 5175);
DISPLAY 0.489362 (-3350 5175);
PAINT SKYBLUE (-3350 5175);
FORCEPROP 1 LAST PACK_TYPE 0402LF
J 2
(-3050 5100);
DISPLAY 0.489362 (-3050 5100);
PAINT SKYBLUE (-3050 5100);
DISPLAY INVISIBLE (-3050 5100);
FORCEPROP 1 LAST TOLERANCE 5%
J 0
(-3350 5150);
DISPLAY 0.489362 (-3350 5150);
PAINT SKYBLUE (-3350 5150);
DISPLAY INVISIBLE (-3350 5150);
FORCEPROP 1 LAST MATERIAL CHIP
J 2
(-3050 5150);
DISPLAY 0.489362 (-3050 5150);
PAINT SKYBLUE (-3050 5150);
DISPLAY INVISIBLE (-3050 5150);
FORCEPROP 1 LAST WATTAGE 1/16W
J 2
(-3300 5100);
DISPLAY 0.489362 (-3300 5100);
PAINT SKYBLUE (-3300 5100);
DISPLAY INVISIBLE (-3300 5100);
FORCEPROP 2 LAST BOM_COST MEM
J 2
(-3200 5325);
DISPLAY 0.744681 (-3200 5325);
PAINT WHITE (-3200 5325);
DISPLAY INVISIBLE (-3200 5325);
FORCEPROP 2 LAST CDS_LIB pure_quanta
J 0
(-3225 5175);
DISPLAY INVISIBLE (-3225 5175);
FORCEPROP 1 LAST PATH I170
J 0
(-3275 5325);
DISPLAY 0.978723 (-3275 5325);
PAINT WHITE (-3275 5325);
DISPLAY INVISIBLE (-3275 5325);
FORCEPROP 1 LAST PART_NUMBER CS03302JB10
J 2
(-3125 5225);
DISPLAY 0.489362 (-3125 5225);
PAINT SKYBLUE (-3125 5225);
DISPLAY INVISIBLE (-3125 5225);
FORCEADD Q_RES..1
(-3225 5275);
FORCEPROP 1 LAST LOCATION R1550
J 0
(-3100 5275);
DISPLAY 0.510638 (-3100 5275);
PAINT SKYBLUE (-3100 5275);
FORCEPROP 0 LAST $SEC 1
J 0
(-3100 5300);
DISPLAY 0.680851 (-3100 5300);
PAINT MONO (-3100 5300);
DISPLAY INVISIBLE (-3100 5300);
FORCEPROP 0 LAST CDS_SEC 1
J 0
(-3100 5300);
DISPLAY 0.680851 (-3100 5300);
DISPLAY INVISIBLE (-3100 5300);
FORCEPROP 1 LASTPIN (-3325 5275) $PN 1
J 0
(-3313 5287);
DISPLAY 0.510638 (-3313 5287);
PAINT MONO (-3313 5287);
FORCEPROP 1 LASTPIN (-3125 5275) $PN 2
J 0
(-3163 5287);
DISPLAY 0.510638 (-3163 5287);
PAINT MONO (-3163 5287);
FORCEPROP 1 LAST VALUE 33
J 2
(-3350 5275);
DISPLAY 0.489362 (-3350 5275);
PAINT SKYBLUE (-3350 5275);
FORCEPROP 1 LAST PACK_TYPE 0402LF
J 2
(-3050 5200);
DISPLAY 0.489362 (-3050 5200);
PAINT SKYBLUE (-3050 5200);
DISPLAY INVISIBLE (-3050 5200);
FORCEPROP 1 LAST TOLERANCE 5%
J 0
(-3350 5250);
DISPLAY 0.489362 (-3350 5250);
PAINT SKYBLUE (-3350 5250);
DISPLAY INVISIBLE (-3350 5250);
FORCEPROP 1 LAST MATERIAL CHIP
J 2
(-3050 5250);
DISPLAY 0.489362 (-3050 5250);
PAINT SKYBLUE (-3050 5250);
DISPLAY INVISIBLE (-3050 5250);
FORCEPROP 1 LAST WATTAGE 1/16W
J 2
(-3300 5200);
DISPLAY 0.489362 (-3300 5200);
PAINT SKYBLUE (-3300 5200);
DISPLAY INVISIBLE (-3300 5200);
FORCEPROP 2 LAST BOM_COST MEM
J 2
(-3200 5425);
DISPLAY 0.744681 (-3200 5425);
PAINT WHITE (-3200 5425);
DISPLAY INVISIBLE (-3200 5425);
FORCEPROP 2 LAST CDS_LIB pure_quanta
J 0
(-3225 5275);
DISPLAY INVISIBLE (-3225 5275);
FORCEPROP 1 LAST PATH I171
J 0
(-3275 5425);
DISPLAY 0.978723 (-3275 5425);
PAINT WHITE (-3275 5425);
DISPLAY INVISIBLE (-3275 5425);
FORCEPROP 1 LAST PART_NUMBER CS03302JB10
J 2
(-3125 5325);
DISPLAY 0.489362 (-3125 5325);
PAINT SKYBLUE (-3125 5325);
DISPLAY INVISIBLE (-3125 5325);
FORCEADD Q_RES..1
(-3225 5375);
FORCEPROP 1 LAST LOCATION R1558
J 0
(-3100 5375);
DISPLAY 0.510638 (-3100 5375);
PAINT SKYBLUE (-3100 5375);
FORCEPROP 0 LAST $SEC 1
J 0
(-3150 5400);
DISPLAY 0.680851 (-3150 5400);
PAINT MONO (-3150 5400);
DISPLAY INVISIBLE (-3150 5400);
FORCEPROP 0 LAST CDS_SEC 1
J 0
(-3150 5400);
DISPLAY 0.680851 (-3150 5400);
DISPLAY INVISIBLE (-3150 5400);
FORCEPROP 1 LASTPIN (-3325 5375) $PN 1
J 0
(-3313 5387);
DISPLAY 0.787234 (-3313 5387);
PAINT MONO (-3313 5387);
FORCEPROP 1 LASTPIN (-3125 5375) $PN 2
J 0
(-3163 5387);
DISPLAY 0.787234 (-3163 5387);
PAINT MONO (-3163 5387);
FORCEPROP 1 LAST VALUE 33
J 2
(-3325 5375);
DISPLAY 0.489362 (-3325 5375);
PAINT SKYBLUE (-3325 5375);
FORCEPROP 2 LAST CDS_LIB pure_quanta
J 0
(-3225 5375);
DISPLAY INVISIBLE (-3225 5375);
FORCEPROP 1 LAST PACK_TYPE 0402LF
J 0
(-3175 5300);
DISPLAY 0.489362 (-3175 5300);
PAINT SKYBLUE (-3175 5300);
DISPLAY INVISIBLE (-3175 5300);
FORCEPROP 1 LAST TOLERANCE 5%
J 0
(-3250 5300);
DISPLAY 0.489362 (-3250 5300);
PAINT SKYBLUE (-3250 5300);
DISPLAY INVISIBLE (-3250 5300);
FORCEPROP 1 LAST MATERIAL CHIP
J 0
(-2800 5300);
DISPLAY 0.489362 (-2800 5300);
PAINT SKYBLUE (-2800 5300);
DISPLAY INVISIBLE (-2800 5300);
FORCEPROP 1 LAST WATTAGE 1/16W
J 2
(-2825 5300);
DISPLAY 0.489362 (-2825 5300);
PAINT SKYBLUE (-2825 5300);
DISPLAY INVISIBLE (-2825 5300);
FORCEPROP 1 LAST PATH I172
J 0
(-3275 5525);
DISPLAY 0.978723 (-3275 5525);
PAINT WHITE (-3275 5525);
DISPLAY INVISIBLE (-3275 5525);
FORCEPROP 1 LAST PART_NUMBER CS03302JB10
J 0
(-3200 5425);
DISPLAY 0.489362 (-3200 5425);
PAINT SKYBLUE (-3200 5425);
DISPLAY INVISIBLE (-3200 5425);
FORCEADD Q_RES..1
(-3225 5325);
FORCEPROP 1 LAST LOCATION R1549
J 0
(-3100 5325);
DISPLAY 0.489362 (-3100 5325);
PAINT SKYBLUE (-3100 5325);
FORCEPROP 0 LAST $SEC 1
J 0
(-3100 5350);
DISPLAY 0.680851 (-3100 5350);
PAINT MONO (-3100 5350);
DISPLAY INVISIBLE (-3100 5350);
FORCEPROP 0 LAST CDS_SEC 1
J 0
(-3100 5350);
DISPLAY 0.680851 (-3100 5350);
DISPLAY INVISIBLE (-3100 5350);
FORCEPROP 1 LASTPIN (-3325 5325) $PN 1
J 0
(-3313 5337);
DISPLAY 0.404255 (-3313 5337);
PAINT MONO (-3313 5337);
FORCEPROP 1 LASTPIN (-3125 5325) $PN 2
J 0
(-3163 5337);
DISPLAY 0.510638 (-3163 5337);
PAINT MONO (-3163 5337);
FORCEPROP 1 LAST VALUE 33
J 2
(-3350 5325);
DISPLAY 0.489362 (-3350 5325);
PAINT SKYBLUE (-3350 5325);
FORCEPROP 2 LAST CDS_LIB pure_quanta
J 0
(-3225 5325);
DISPLAY INVISIBLE (-3225 5325);
FORCEPROP 2 LAST BOM_COST MEM
J 2
(-3200 5475);
DISPLAY 0.744681 (-3200 5475);
PAINT WHITE (-3200 5475);
DISPLAY INVISIBLE (-3200 5475);
FORCEPROP 1 LAST WATTAGE 1/16W
J 2
(-3300 5250);
DISPLAY 0.489362 (-3300 5250);
PAINT SKYBLUE (-3300 5250);
DISPLAY INVISIBLE (-3300 5250);
FORCEPROP 1 LAST MATERIAL CHIP
J 2
(-3050 5300);
DISPLAY 0.489362 (-3050 5300);
PAINT SKYBLUE (-3050 5300);
DISPLAY INVISIBLE (-3050 5300);
FORCEPROP 1 LAST TOLERANCE 5%
J 0
(-3350 5300);
DISPLAY 0.489362 (-3350 5300);
PAINT SKYBLUE (-3350 5300);
DISPLAY INVISIBLE (-3350 5300);
FORCEPROP 1 LAST PACK_TYPE 0402LF
J 2
(-3050 5250);
DISPLAY 0.489362 (-3050 5250);
PAINT SKYBLUE (-3050 5250);
DISPLAY INVISIBLE (-3050 5250);
FORCEPROP 1 LAST PATH I173
J 0
(-3275 5475);
DISPLAY 0.978723 (-3275 5475);
PAINT WHITE (-3275 5475);
DISPLAY INVISIBLE (-3275 5475);
FORCEPROP 1 LAST PART_NUMBER CS03302JB10
J 2
(-3125 5375);
DISPLAY 0.489362 (-3125 5375);
PAINT SKYBLUE (-3125 5375);
DISPLAY INVISIBLE (-3125 5375);
FORCEADD Q_RES..1
(-3225 5475);
FORCEPROP 1 LAST LOCATION R1553
J 0
(-3100 5475);
DISPLAY 0.489362 (-3100 5475);
PAINT SKYBLUE (-3100 5475);
FORCEPROP 0 LAST $SEC 1
J 0
(-3100 5500);
DISPLAY 0.680851 (-3100 5500);
PAINT MONO (-3100 5500);
DISPLAY INVISIBLE (-3100 5500);
FORCEPROP 0 LAST CDS_SEC 1
J 0
(-3100 5500);
DISPLAY 0.680851 (-3100 5500);
DISPLAY INVISIBLE (-3100 5500);
FORCEPROP 1 LASTPIN (-3325 5475) $PN 1
J 0
(-3313 5487);
DISPLAY 0.510638 (-3313 5487);
PAINT MONO (-3313 5487);
FORCEPROP 1 LASTPIN (-3125 5475) $PN 2
J 0
(-3163 5487);
DISPLAY 0.510638 (-3163 5487);
PAINT MONO (-3163 5487);
FORCEPROP 1 LAST VALUE 33
J 2
(-3325 5475);
DISPLAY 0.489362 (-3325 5475);
PAINT SKYBLUE (-3325 5475);
FORCEPROP 1 LAST WATTAGE 1/16W
J 2
(-2825 5400);
DISPLAY 0.489362 (-2825 5400);
PAINT SKYBLUE (-2825 5400);
DISPLAY INVISIBLE (-2825 5400);
FORCEPROP 1 LAST MATERIAL CHIP
J 0
(-2800 5400);
DISPLAY 0.489362 (-2800 5400);
PAINT SKYBLUE (-2800 5400);
DISPLAY INVISIBLE (-2800 5400);
FORCEPROP 1 LAST TOLERANCE 5%
J 0
(-3250 5400);
DISPLAY 0.489362 (-3250 5400);
PAINT SKYBLUE (-3250 5400);
DISPLAY INVISIBLE (-3250 5400);
FORCEPROP 1 LAST PACK_TYPE 0402LF
J 0
(-3175 5400);
DISPLAY 0.489362 (-3175 5400);
PAINT SKYBLUE (-3175 5400);
DISPLAY INVISIBLE (-3175 5400);
FORCEPROP 2 LAST CDS_LIB pure_quanta
J 0
(-3225 5475);
DISPLAY INVISIBLE (-3225 5475);
FORCEPROP 1 LAST PATH I174
J 0
(-3275 5625);
DISPLAY 0.978723 (-3275 5625);
PAINT WHITE (-3275 5625);
DISPLAY INVISIBLE (-3275 5625);
FORCEPROP 1 LAST PART_NUMBER CS03302JB10
J 0
(-3200 5525);
DISPLAY 0.489362 (-3200 5525);
PAINT SKYBLUE (-3200 5525);
DISPLAY INVISIBLE (-3200 5525);
FORCEADD Q_RES..1
(-3225 5425);
FORCEPROP 1 LAST LOCATION R1557
J 0
(-3100 5425);
DISPLAY 0.510638 (-3100 5425);
PAINT SKYBLUE (-3100 5425);
FORCEPROP 0 LAST $SEC 1
J 0
(-3150 5450);
DISPLAY 0.680851 (-3150 5450);
PAINT MONO (-3150 5450);
DISPLAY INVISIBLE (-3150 5450);
FORCEPROP 0 LAST CDS_SEC 1
J 0
(-3150 5450);
DISPLAY 0.680851 (-3150 5450);
DISPLAY INVISIBLE (-3150 5450);
FORCEPROP 1 LASTPIN (-3325 5425) $PN 1
J 0
(-3313 5437);
DISPLAY 0.787234 (-3313 5437);
PAINT MONO (-3313 5437);
FORCEPROP 1 LASTPIN (-3125 5425) $PN 2
J 0
(-3163 5437);
DISPLAY 0.787234 (-3163 5437);
PAINT MONO (-3163 5437);
FORCEPROP 1 LAST VALUE 33
J 2
(-3325 5425);
DISPLAY 0.489362 (-3325 5425);
PAINT SKYBLUE (-3325 5425);
FORCEPROP 1 LAST WATTAGE 1/16W
J 2
(-2825 5350);
DISPLAY 0.489362 (-2825 5350);
PAINT SKYBLUE (-2825 5350);
DISPLAY INVISIBLE (-2825 5350);
FORCEPROP 1 LAST MATERIAL CHIP
J 0
(-2800 5350);
DISPLAY 0.489362 (-2800 5350);
PAINT SKYBLUE (-2800 5350);
DISPLAY INVISIBLE (-2800 5350);
FORCEPROP 1 LAST TOLERANCE 5%
J 0
(-3250 5350);
DISPLAY 0.489362 (-3250 5350);
PAINT SKYBLUE (-3250 5350);
DISPLAY INVISIBLE (-3250 5350);
FORCEPROP 1 LAST PACK_TYPE 0402LF
J 0
(-3175 5350);
DISPLAY 0.489362 (-3175 5350);
PAINT SKYBLUE (-3175 5350);
DISPLAY INVISIBLE (-3175 5350);
FORCEPROP 2 LAST CDS_LIB pure_quanta
J 0
(-3225 5425);
DISPLAY INVISIBLE (-3225 5425);
FORCEPROP 1 LAST PATH I175
J 0
(-3275 5575);
DISPLAY 0.978723 (-3275 5575);
PAINT WHITE (-3275 5575);
DISPLAY INVISIBLE (-3275 5575);
FORCEPROP 1 LAST PART_NUMBER CS03302JB10
J 0
(-3200 5475);
DISPLAY 0.489362 (-3200 5475);
PAINT SKYBLUE (-3200 5475);
DISPLAY INVISIBLE (-3200 5475);
FORCEADD Q_RES..1
(-3225 5525);
FORCEPROP 1 LAST LOCATION R1556
J 0
(-3100 5525);
DISPLAY 0.510638 (-3100 5525);
PAINT SKYBLUE (-3100 5525);
FORCEPROP 0 LAST $SEC 1
J 0
(-3150 5550);
DISPLAY 0.680851 (-3150 5550);
PAINT MONO (-3150 5550);
DISPLAY INVISIBLE (-3150 5550);
FORCEPROP 0 LAST CDS_SEC 1
J 0
(-3150 5550);
DISPLAY 0.680851 (-3150 5550);
DISPLAY INVISIBLE (-3150 5550);
FORCEPROP 1 LASTPIN (-3325 5525) $PN 1
J 0
(-3313 5537);
DISPLAY 0.787234 (-3313 5537);
PAINT MONO (-3313 5537);
FORCEPROP 1 LASTPIN (-3125 5525) $PN 2
J 0
(-3163 5537);
DISPLAY 0.787234 (-3163 5537);
PAINT MONO (-3163 5537);
FORCEPROP 1 LAST VALUE 33
J 2
(-3325 5525);
DISPLAY 0.489362 (-3325 5525);
PAINT SKYBLUE (-3325 5525);
FORCEPROP 2 LAST CDS_LIB pure_quanta
J 0
(-3225 5525);
DISPLAY INVISIBLE (-3225 5525);
FORCEPROP 1 LAST PACK_TYPE 0402LF
J 0
(-3175 5450);
DISPLAY 0.489362 (-3175 5450);
PAINT SKYBLUE (-3175 5450);
DISPLAY INVISIBLE (-3175 5450);
FORCEPROP 1 LAST TOLERANCE 5%
J 0
(-3250 5450);
DISPLAY 0.489362 (-3250 5450);
PAINT SKYBLUE (-3250 5450);
DISPLAY INVISIBLE (-3250 5450);
FORCEPROP 1 LAST MATERIAL CHIP
J 0
(-2800 5450);
DISPLAY 0.489362 (-2800 5450);
PAINT SKYBLUE (-2800 5450);
DISPLAY INVISIBLE (-2800 5450);
FORCEPROP 1 LAST WATTAGE 1/16W
J 2
(-2825 5450);
DISPLAY 0.489362 (-2825 5450);
PAINT SKYBLUE (-2825 5450);
DISPLAY INVISIBLE (-2825 5450);
FORCEPROP 1 LAST PATH I176
J 0
(-3275 5675);
DISPLAY 0.978723 (-3275 5675);
PAINT WHITE (-3275 5675);
DISPLAY INVISIBLE (-3275 5675);
FORCEPROP 1 LAST PART_NUMBER CS03302JB10
J 0
(-3200 5575);
DISPLAY 0.489362 (-3200 5575);
PAINT SKYBLUE (-3200 5575);
DISPLAY INVISIBLE (-3200 5575);
FORCEADD Q_RES..1
(-3225 5725);
FORCEPROP 1 LAST LOCATION R258
J 0
(-3100 5725);
DISPLAY 0.489362 (-3100 5725);
PAINT SKYBLUE (-3100 5725);
FORCEPROP 0 LAST $SEC 1
J 2
(-3100 5775);
DISPLAY 0.680851 (-3100 5775);
PAINT MONO (-3100 5775);
DISPLAY INVISIBLE (-3100 5775);
FORCEPROP 0 LAST CDS_SEC 1
J 2
(-3100 5775);
DISPLAY 1.021277 (-3100 5775);
DISPLAY INVISIBLE (-3100 5775);
FORCEPROP 1 LASTPIN (-3325 5725) $PN 1
J 0
(-3313 5737);
DISPLAY 0.489362 (-3313 5737);
PAINT MONO (-3313 5737);
FORCEPROP 1 LASTPIN (-3125 5725) $PN 2
J 0
(-3163 5737);
DISPLAY 0.489362 (-3163 5737);
PAINT MONO (-3163 5737);
FORCEPROP 1 LAST VALUE 0
J 2
(-3350 5725);
DISPLAY 0.489362 (-3350 5725);
PAINT SKYBLUE (-3350 5725);
FORCEPROP 2 LAST CDS_LIB pure_quanta
J 2
(-3225 5725);
DISPLAY INVISIBLE (-3225 5725);
FORCEPROP 1 LAST PACK_TYPE 0402LF
J 2
(-3050 5650);
DISPLAY 0.489362 (-3050 5650);
PAINT SKYBLUE (-3050 5650);
DISPLAY INVISIBLE (-3050 5650);
FORCEPROP 1 LAST TOLERANCE 5%
J 0
(-3350 5700);
DISPLAY 0.489362 (-3350 5700);
PAINT SKYBLUE (-3350 5700);
DISPLAY INVISIBLE (-3350 5700);
FORCEPROP 1 LAST MATERIAL CHIP
J 2
(-3050 5700);
DISPLAY 0.489362 (-3050 5700);
PAINT SKYBLUE (-3050 5700);
DISPLAY INVISIBLE (-3050 5700);
FORCEPROP 1 LAST WATTAGE 1/16W
J 2
(-3300 5650);
DISPLAY 0.489362 (-3300 5650);
PAINT SKYBLUE (-3300 5650);
DISPLAY INVISIBLE (-3300 5650);
FORCEPROP 2 LAST BOM_COST MEM
J 2
(-3200 5875);
DISPLAY 0.744681 (-3200 5875);
PAINT WHITE (-3200 5875);
DISPLAY INVISIBLE (-3200 5875);
FORCEPROP 1 LAST PATH I177
J 0
(-3275 5875);
DISPLAY 0.978723 (-3275 5875);
PAINT WHITE (-3275 5875);
DISPLAY INVISIBLE (-3275 5875);
FORCEPROP 1 LAST PART_NUMBER CS00002JB13
J 2
(-3125 5775);
DISPLAY 0.489362 (-3125 5775);
PAINT SKYBLUE (-3125 5775);
DISPLAY INVISIBLE (-3125 5775);
FORCEADD Q_RES..1
(-3225 5775);
FORCEPROP 1 LAST LOCATION R1203
J 0
(-3100 5775);
DISPLAY 0.489362 (-3100 5775);
PAINT SKYBLUE (-3100 5775);
FORCEPROP 0 LAST $SEC 1
J 0
(-3100 5825);
DISPLAY 0.680851 (-3100 5825);
PAINT MONO (-3100 5825);
DISPLAY INVISIBLE (-3100 5825);
FORCEPROP 0 LAST CDS_SEC 1
J 0
(-3100 5825);
DISPLAY 0.680851 (-3100 5825);
DISPLAY INVISIBLE (-3100 5825);
FORCEPROP 1 LASTPIN (-3325 5775) $PN 1
J 0
(-3313 5787);
DISPLAY 0.489362 (-3313 5787);
PAINT MONO (-3313 5787);
FORCEPROP 1 LASTPIN (-3125 5775) $PN 2
J 0
(-3163 5787);
DISPLAY 0.489362 (-3163 5787);
PAINT MONO (-3163 5787);
FORCEPROP 1 LAST VALUE 33
J 2
(-3350 5775);
DISPLAY 0.489362 (-3350 5775);
PAINT SKYBLUE (-3350 5775);
FORCEPROP 1 LAST PACK_TYPE 0402LF
J 2
(-3050 5700);
DISPLAY 0.489362 (-3050 5700);
PAINT SKYBLUE (-3050 5700);
DISPLAY INVISIBLE (-3050 5700);
FORCEPROP 1 LAST TOLERANCE 5%
J 0
(-3350 5750);
DISPLAY 0.489362 (-3350 5750);
PAINT SKYBLUE (-3350 5750);
DISPLAY INVISIBLE (-3350 5750);
FORCEPROP 1 LAST MATERIAL CHIP
J 2
(-3050 5750);
DISPLAY 0.489362 (-3050 5750);
PAINT SKYBLUE (-3050 5750);
DISPLAY INVISIBLE (-3050 5750);
FORCEPROP 1 LAST WATTAGE 1/16W
J 2
(-3300 5700);
DISPLAY 0.489362 (-3300 5700);
PAINT SKYBLUE (-3300 5700);
DISPLAY INVISIBLE (-3300 5700);
FORCEPROP 2 LAST BOM_COST MEM
J 2
(-3200 5925);
DISPLAY 0.744681 (-3200 5925);
PAINT WHITE (-3200 5925);
DISPLAY INVISIBLE (-3200 5925);
FORCEPROP 2 LAST CDS_LIB pure_quanta
J 0
(-3225 5775);
DISPLAY INVISIBLE (-3225 5775);
FORCEPROP 1 LAST PATH I178
J 0
(-3275 5925);
DISPLAY 0.978723 (-3275 5925);
PAINT WHITE (-3275 5925);
DISPLAY INVISIBLE (-3275 5925);
FORCEPROP 1 LAST PART_NUMBER CS03302JB10
J 2
(-3125 5825);
DISPLAY 0.489362 (-3125 5825);
PAINT SKYBLUE (-3125 5825);
DISPLAY INVISIBLE (-3125 5825);
FORCEADD Q_RES..1
(-3225 5925);
FORCEPROP 1 LAST LOCATION R193
J 0
(-3100 5925);
DISPLAY 0.489362 (-3100 5925);
PAINT SKYBLUE (-3100 5925);
FORCEPROP 0 LAST $SEC 1
J 2
(-3100 5975);
DISPLAY 0.680851 (-3100 5975);
PAINT MONO (-3100 5975);
DISPLAY INVISIBLE (-3100 5975);
FORCEPROP 0 LAST CDS_SEC 1
J 2
(-3100 5975);
DISPLAY 1.021277 (-3100 5975);
DISPLAY INVISIBLE (-3100 5975);
FORCEPROP 1 LASTPIN (-3325 5925) $PN 1
J 0
(-3313 5937);
DISPLAY 0.489362 (-3313 5937);
PAINT MONO (-3313 5937);
FORCEPROP 1 LASTPIN (-3125 5925) $PN 2
J 0
(-3163 5937);
DISPLAY 0.489362 (-3163 5937);
PAINT MONO (-3163 5937);
FORCEPROP 1 LAST VALUE 0
J 2
(-3350 5925);
DISPLAY 0.489362 (-3350 5925);
PAINT SKYBLUE (-3350 5925);
FORCEPROP 2 LAST BOM_COST MEM
J 2
(-3200 6075);
DISPLAY 0.744681 (-3200 6075);
PAINT WHITE (-3200 6075);
DISPLAY INVISIBLE (-3200 6075);
FORCEPROP 1 LAST WATTAGE 1/16W
J 2
(-3300 5850);
DISPLAY 0.489362 (-3300 5850);
PAINT SKYBLUE (-3300 5850);
DISPLAY INVISIBLE (-3300 5850);
FORCEPROP 1 LAST MATERIAL CHIP
J 2
(-3050 5900);
DISPLAY 0.489362 (-3050 5900);
PAINT SKYBLUE (-3050 5900);
DISPLAY INVISIBLE (-3050 5900);
FORCEPROP 1 LAST TOLERANCE 5%
J 0
(-3350 5900);
DISPLAY 0.489362 (-3350 5900);
PAINT SKYBLUE (-3350 5900);
DISPLAY INVISIBLE (-3350 5900);
FORCEPROP 1 LAST PACK_TYPE 0402LF
J 2
(-3050 5850);
DISPLAY 0.489362 (-3050 5850);
PAINT SKYBLUE (-3050 5850);
DISPLAY INVISIBLE (-3050 5850);
FORCEPROP 2 LAST CDS_LIB pure_quanta
J 2
(-3225 5925);
DISPLAY INVISIBLE (-3225 5925);
FORCEPROP 1 LAST PATH I179
J 0
(-3275 6075);
DISPLAY 0.978723 (-3275 6075);
PAINT WHITE (-3275 6075);
DISPLAY INVISIBLE (-3275 6075);
FORCEPROP 1 LAST PART_NUMBER CS00002JB13
J 2
(-3125 5975);
DISPLAY 0.489362 (-3125 5975);
PAINT SKYBLUE (-3125 5975);
DISPLAY INVISIBLE (-3125 5975);
FORCEADD OFFPAGE..5
(-7800 1775);
FORCEPROP 2 LAST $XR0 209 
J 0
(-8055 1775);
DISPLAY 0.638298 (-8055 1775);
PAINT MONO (-8055 1775);
FORCEPROP 2 LAST CDS_LIB standard
J 0
(-7800 1775);
DISPLAY INVISIBLE (-7800 1775);
FORCEPROP 1 LAST OFFPAGE TRUE
J 0
(-7475 1650);
DISPLAY 0.872340 (-7475 1650);
PAINT GREEN (-7475 1650);
DISPLAY INVISIBLE (-7475 1650);
FORCEPROP 1 LAST COMMENT_BODY TRUE
J 0
(-7700 1700);
DISPLAY 0.872340 (-7700 1700);
PAINT GREEN (-7700 1700);
DISPLAY INVISIBLE (-7700 1700);
FORCEPROP 2 LAST PATH I18
J 0
(-8050 1825);
DISPLAY 0.680851 (-8050 1825);
DISPLAY INVISIBLE (-8050 1825);
FORCEADD Q_RES..1
(-3225 6125);
FORCEPROP 1 LAST LOCATION R250
J 0
(-3100 6125);
DISPLAY 0.489362 (-3100 6125);
PAINT SKYBLUE (-3100 6125);
FORCEPROP 0 LAST $SEC 1
J 2
(-3100 6175);
DISPLAY 0.680851 (-3100 6175);
PAINT MONO (-3100 6175);
DISPLAY INVISIBLE (-3100 6175);
FORCEPROP 0 LAST CDS_SEC 1
J 2
(-3100 6175);
DISPLAY 1.021277 (-3100 6175);
DISPLAY INVISIBLE (-3100 6175);
FORCEPROP 1 LASTPIN (-3325 6125) $PN 1
J 0
(-3313 6137);
DISPLAY 0.489362 (-3313 6137);
PAINT MONO (-3313 6137);
FORCEPROP 1 LASTPIN (-3125 6125) $PN 2
J 0
(-3163 6137);
DISPLAY 0.489362 (-3163 6137);
PAINT MONO (-3163 6137);
FORCEPROP 1 LAST VALUE 0
J 2
(-3350 6125);
DISPLAY 0.489362 (-3350 6125);
PAINT SKYBLUE (-3350 6125);
FORCEPROP 2 LAST CDS_LIB pure_quanta
J 2
(-3225 6125);
DISPLAY INVISIBLE (-3225 6125);
FORCEPROP 2 LAST BOM_COST MEM
J 2
(-3200 6275);
DISPLAY 0.744681 (-3200 6275);
PAINT WHITE (-3200 6275);
DISPLAY INVISIBLE (-3200 6275);
FORCEPROP 1 LAST WATTAGE 1/16W
J 2
(-3300 6050);
DISPLAY 0.489362 (-3300 6050);
PAINT SKYBLUE (-3300 6050);
DISPLAY INVISIBLE (-3300 6050);
FORCEPROP 1 LAST MATERIAL CHIP
J 2
(-3050 6100);
DISPLAY 0.489362 (-3050 6100);
PAINT SKYBLUE (-3050 6100);
DISPLAY INVISIBLE (-3050 6100);
FORCEPROP 1 LAST TOLERANCE 5%
J 0
(-3350 6100);
DISPLAY 0.489362 (-3350 6100);
PAINT SKYBLUE (-3350 6100);
DISPLAY INVISIBLE (-3350 6100);
FORCEPROP 1 LAST PACK_TYPE 0402LF
J 2
(-3050 6050);
DISPLAY 0.489362 (-3050 6050);
PAINT SKYBLUE (-3050 6050);
DISPLAY INVISIBLE (-3050 6050);
FORCEPROP 1 LAST PATH I180
J 0
(-3275 6275);
DISPLAY 0.978723 (-3275 6275);
PAINT WHITE (-3275 6275);
DISPLAY INVISIBLE (-3275 6275);
FORCEPROP 1 LAST PART_NUMBER CS00002JB13
J 2
(-3125 6175);
DISPLAY 0.489362 (-3125 6175);
PAINT SKYBLUE (-3125 6175);
DISPLAY INVISIBLE (-3125 6175);
FORCEADD OFFPAGE..2
(-2300 4175);
FORCEPROP 2 LAST $XR0 174 
J 0
(-2111 4175);
DISPLAY 0.638298 (-2111 4175);
PAINT MONO (-2111 4175);
FORCEPROP 2 LAST CDS_LIB standard
J 0
(-2300 4175);
DISPLAY INVISIBLE (-2300 4175);
FORCEPROP 1 LAST OFFPAGE TRUE
J 0
(-1975 4050);
DISPLAY 0.872340 (-1975 4050);
PAINT GREEN (-1975 4050);
DISPLAY INVISIBLE (-1975 4050);
FORCEPROP 1 LAST COMMENT_BODY TRUE
J 0
(-2345 4080);
DISPLAY 0.872340 (-2345 4080);
PAINT GREEN (-2345 4080);
DISPLAY INVISIBLE (-2345 4080);
FORCEPROP 2 LAST PATH I181
J 0
(-2100 4225);
DISPLAY 0.680851 (-2100 4225);
DISPLAY INVISIBLE (-2100 4225);
FORCEADD OFFPAGE..1
R 2
(-2300 4225);
FORCEPROP 2 LAST $XR0 167 
J 0
(-2114 4225);
DISPLAY 0.638298 (-2114 4225);
PAINT MONO (-2114 4225);
FORCEPROP 2 LAST CDS_LIB standard
J 0
(-2300 4225);
DISPLAY INVISIBLE (-2300 4225);
FORCEPROP 1 LAST OFFPAGE TRUE
J 2
(-2625 4100);
DISPLAY 0.872340 (-2625 4100);
PAINT GREEN (-2625 4100);
DISPLAY INVISIBLE (-2625 4100);
FORCEPROP 1 LAST COMMENT_BODY TRUE
J 2
(-2425 4125);
DISPLAY 0.872340 (-2425 4125);
PAINT GREEN (-2425 4125);
DISPLAY INVISIBLE (-2425 4125);
FORCEPROP 2 LAST PATH I182
J 0
(-2100 4275);
DISPLAY 0.680851 (-2100 4275);
DISPLAY INVISIBLE (-2100 4275);
FORCEADD OFFPAGE..2
(-2300 4275);
FORCEPROP 2 LAST $XR0 77 
J 0
(-2111 4275);
DISPLAY 0.638298 (-2111 4275);
PAINT MONO (-2111 4275);
FORCEPROP 2 LAST CDS_LIB standard
J 0
(-2300 4275);
DISPLAY INVISIBLE (-2300 4275);
FORCEPROP 1 LAST OFFPAGE TRUE
J 0
(-1975 4150);
DISPLAY 0.872340 (-1975 4150);
PAINT GREEN (-1975 4150);
DISPLAY INVISIBLE (-1975 4150);
FORCEPROP 1 LAST COMMENT_BODY TRUE
J 0
(-2345 4180);
DISPLAY 0.872340 (-2345 4180);
PAINT GREEN (-2345 4180);
DISPLAY INVISIBLE (-2345 4180);
FORCEPROP 2 LAST PATH I183
J 0
(-2100 4325);
DISPLAY 0.680851 (-2100 4325);
DISPLAY INVISIBLE (-2100 4325);
FORCEADD OFFPAGE..2
(-2300 4325);
FORCEPROP 2 LAST $XR0 77 
J 0
(-2111 4325);
DISPLAY 0.638298 (-2111 4325);
PAINT MONO (-2111 4325);
FORCEPROP 2 LAST CDS_LIB standard
J 0
(-2300 4325);
DISPLAY INVISIBLE (-2300 4325);
FORCEPROP 1 LAST OFFPAGE TRUE
J 0
(-1975 4200);
DISPLAY 0.872340 (-1975 4200);
PAINT GREEN (-1975 4200);
DISPLAY INVISIBLE (-1975 4200);
FORCEPROP 1 LAST COMMENT_BODY TRUE
J 0
(-2345 4230);
DISPLAY 0.872340 (-2345 4230);
PAINT GREEN (-2345 4230);
DISPLAY INVISIBLE (-2345 4230);
FORCEPROP 2 LAST PATH I184
J 0
(-2100 4375);
DISPLAY 0.680851 (-2100 4375);
DISPLAY INVISIBLE (-2100 4375);
FORCEADD OFFPAGE..1
R 2
(-2300 4375);
FORCEPROP 2 LAST $XR0 167 
J 0
(-2114 4375);
DISPLAY 0.638298 (-2114 4375);
PAINT MONO (-2114 4375);
FORCEPROP 2 LAST CDS_LIB standard
J 0
(-2300 4375);
DISPLAY INVISIBLE (-2300 4375);
FORCEPROP 1 LAST OFFPAGE TRUE
J 2
(-2625 4250);
DISPLAY 0.872340 (-2625 4250);
PAINT GREEN (-2625 4250);
DISPLAY INVISIBLE (-2625 4250);
FORCEPROP 1 LAST COMMENT_BODY TRUE
J 2
(-2425 4275);
DISPLAY 0.872340 (-2425 4275);
PAINT GREEN (-2425 4275);
DISPLAY INVISIBLE (-2425 4275);
FORCEPROP 2 LAST PATH I185
J 0
(-2100 4425);
DISPLAY 0.680851 (-2100 4425);
DISPLAY INVISIBLE (-2100 4425);
FORCEADD OFFPAGE..2
(-2300 4475);
FORCEPROP 2 LAST $XR0 166 
J 0
(-2111 4475);
DISPLAY 0.638298 (-2111 4475);
PAINT MONO (-2111 4475);
FORCEPROP 2 LAST CDS_LIB standard
J 0
(-2300 4475);
DISPLAY INVISIBLE (-2300 4475);
FORCEPROP 1 LAST OFFPAGE TRUE
J 0
(-1975 4350);
DISPLAY 0.872340 (-1975 4350);
PAINT GREEN (-1975 4350);
DISPLAY INVISIBLE (-1975 4350);
FORCEPROP 1 LAST COMMENT_BODY TRUE
J 0
(-2345 4380);
DISPLAY 0.872340 (-2345 4380);
PAINT GREEN (-2345 4380);
DISPLAY INVISIBLE (-2345 4380);
FORCEPROP 2 LAST PATH I186
J 0
(-2100 4525);
DISPLAY 0.680851 (-2100 4525);
DISPLAY INVISIBLE (-2100 4525);
FORCEADD OFFPAGE..2
(-2300 4575);
FORCEPROP 2 LAST $XR0 84 
J 0
(-2111 4575);
DISPLAY 0.638298 (-2111 4575);
PAINT MONO (-2111 4575);
FORCEPROP 2 LAST CDS_LIB standard
J 0
(-2300 4575);
DISPLAY INVISIBLE (-2300 4575);
FORCEPROP 1 LAST OFFPAGE TRUE
J 0
(-1975 4450);
DISPLAY 0.872340 (-1975 4450);
PAINT GREEN (-1975 4450);
DISPLAY INVISIBLE (-1975 4450);
FORCEPROP 1 LAST COMMENT_BODY TRUE
J 0
(-2345 4480);
DISPLAY 0.872340 (-2345 4480);
PAINT GREEN (-2345 4480);
DISPLAY INVISIBLE (-2345 4480);
FORCEPROP 2 LAST PATH I187
J 0
(-2100 4625);
DISPLAY 0.680851 (-2100 4625);
DISPLAY INVISIBLE (-2100 4625);
FORCEADD OFFPAGE..2
(-2300 4625);
FORCEPROP 2 LAST $XR0 173 
J 0
(-2111 4625);
DISPLAY 0.638298 (-2111 4625);
PAINT MONO (-2111 4625);
FORCEPROP 2 LAST CDS_LIB standard
J 0
(-2300 4625);
DISPLAY INVISIBLE (-2300 4625);
FORCEPROP 1 LAST OFFPAGE TRUE
J 0
(-1975 4500);
DISPLAY 0.872340 (-1975 4500);
PAINT GREEN (-1975 4500);
DISPLAY INVISIBLE (-1975 4500);
FORCEPROP 1 LAST COMMENT_BODY TRUE
J 0
(-2345 4530);
DISPLAY 0.872340 (-2345 4530);
PAINT GREEN (-2345 4530);
DISPLAY INVISIBLE (-2345 4530);
FORCEPROP 2 LAST PATH I188
J 0
(-2100 4675);
DISPLAY 0.680851 (-2100 4675);
DISPLAY INVISIBLE (-2100 4675);
FORCEADD OFFPAGE..2
(-2300 4675);
FORCEPROP 2 LAST $XR0 174 
J 0
(-2111 4675);
DISPLAY 0.638298 (-2111 4675);
PAINT MONO (-2111 4675);
FORCEPROP 2 LAST CDS_LIB standard
J 2
(-2300 4675);
DISPLAY INVISIBLE (-2300 4675);
FORCEPROP 1 LAST OFFPAGE TRUE
J 0
(-1975 4550);
DISPLAY 0.872340 (-1975 4550);
PAINT GREEN (-1975 4550);
DISPLAY INVISIBLE (-1975 4550);
FORCEPROP 1 LAST COMMENT_BODY TRUE
J 0
(-2345 4580);
DISPLAY 0.872340 (-2345 4580);
PAINT GREEN (-2345 4580);
DISPLAY INVISIBLE (-2345 4580);
FORCEPROP 2 LAST PATH I189
J 0
(-2100 4725);
DISPLAY 0.680851 (-2100 4725);
DISPLAY INVISIBLE (-2100 4725);
FORCEADD OFFPAGE..5
(-7800 1625);
FORCEPROP 2 LAST $XR0 28 
J 0
(-8024 1625);
DISPLAY 0.638298 (-8024 1625);
PAINT MONO (-8024 1625);
FORCEPROP 2 LAST CDS_LIB standard
J 0
(-7800 1625);
DISPLAY INVISIBLE (-7800 1625);
FORCEPROP 1 LAST OFFPAGE TRUE
J 0
(-7475 1500);
DISPLAY 0.872340 (-7475 1500);
PAINT GREEN (-7475 1500);
DISPLAY INVISIBLE (-7475 1500);
FORCEPROP 1 LAST COMMENT_BODY TRUE
J 0
(-7700 1550);
DISPLAY 0.872340 (-7700 1550);
PAINT GREEN (-7700 1550);
DISPLAY INVISIBLE (-7700 1550);
FORCEPROP 2 LAST PATH I19
J 0
(-8000 1675);
DISPLAY 0.680851 (-8000 1675);
DISPLAY INVISIBLE (-8000 1675);
FORCEADD OFFPAGE..1
R 2
(-2300 4725);
FORCEPROP 2 LAST $XR0 28 
J 0
(-2114 4725);
DISPLAY 0.638298 (-2114 4725);
PAINT MONO (-2114 4725);
FORCEPROP 2 LAST CDS_LIB standard
J 0
(-2300 4725);
DISPLAY INVISIBLE (-2300 4725);
FORCEPROP 1 LAST OFFPAGE TRUE
J 2
(-2625 4600);
DISPLAY 0.872340 (-2625 4600);
PAINT GREEN (-2625 4600);
DISPLAY INVISIBLE (-2625 4600);
FORCEPROP 1 LAST COMMENT_BODY TRUE
J 2
(-2425 4625);
DISPLAY 0.872340 (-2425 4625);
PAINT GREEN (-2425 4625);
DISPLAY INVISIBLE (-2425 4625);
FORCEPROP 2 LAST PATH I190
J 0
(-2100 4775);
DISPLAY 0.680851 (-2100 4775);
DISPLAY INVISIBLE (-2100 4775);
FORCEADD OFFPAGE..2
(-2300 4825);
FORCEPROP 2 LAST $XR1 29 
J 0
(-1991 4825);
DISPLAY 0.638298 (-1991 4825);
PAINT MONO (-1991 4825);
FORCEPROP 2 LAST $XR0 83 
J 0
(-2081 4825);
DISPLAY 0.638298 (-2081 4825);
PAINT MONO (-2081 4825);
FORCEPROP 2 LAST CDS_LIB standard
J 0
(-2300 4825);
DISPLAY INVISIBLE (-2300 4825);
FORCEPROP 1 LAST OFFPAGE TRUE
J 0
(-1975 4700);
DISPLAY 0.872340 (-1975 4700);
PAINT GREEN (-1975 4700);
DISPLAY INVISIBLE (-1975 4700);
FORCEPROP 1 LAST COMMENT_BODY TRUE
J 0
(-2345 4730);
DISPLAY 0.872340 (-2345 4730);
PAINT GREEN (-2345 4730);
DISPLAY INVISIBLE (-2345 4730);
FORCEPROP 2 LAST PATH I191
J 0
(-2000 4875);
DISPLAY 0.680851 (-2000 4875);
DISPLAY INVISIBLE (-2000 4875);
FORCEADD OFFPAGE..2
(-2300 4925);
FORCEPROP 2 LAST $XR0 55 
J 0
(-2111 4925);
DISPLAY 0.638298 (-2111 4925);
PAINT MONO (-2111 4925);
FORCEPROP 2 LAST CDS_LIB standard
J 0
(-2300 4925);
DISPLAY INVISIBLE (-2300 4925);
FORCEPROP 1 LAST OFFPAGE TRUE
J 0
(-1975 4800);
DISPLAY 0.872340 (-1975 4800);
PAINT GREEN (-1975 4800);
DISPLAY INVISIBLE (-1975 4800);
FORCEPROP 1 LAST COMMENT_BODY TRUE
J 0
(-2345 4830);
DISPLAY 0.872340 (-2345 4830);
PAINT GREEN (-2345 4830);
DISPLAY INVISIBLE (-2345 4830);
FORCEPROP 2 LAST PATH I192
J 0
(-2100 4975);
DISPLAY 0.680851 (-2100 4975);
DISPLAY INVISIBLE (-2100 4975);
FORCEADD OFFPAGE..1
R 2
(-2300 5025);
FORCEPROP 2 LAST $XR0 34 
J 0
(-2114 5025);
DISPLAY 0.638298 (-2114 5025);
PAINT MONO (-2114 5025);
FORCEPROP 2 LAST CDS_LIB standard
J 0
(-2300 5025);
DISPLAY INVISIBLE (-2300 5025);
FORCEPROP 1 LAST OFFPAGE TRUE
J 2
(-2625 4900);
DISPLAY 0.872340 (-2625 4900);
PAINT GREEN (-2625 4900);
DISPLAY INVISIBLE (-2625 4900);
FORCEPROP 1 LAST COMMENT_BODY TRUE
J 2
(-2425 4925);
DISPLAY 0.872340 (-2425 4925);
PAINT GREEN (-2425 4925);
DISPLAY INVISIBLE (-2425 4925);
FORCEPROP 2 LAST PATH I193
J 0
(-2100 5075);
DISPLAY 0.680851 (-2100 5075);
DISPLAY INVISIBLE (-2100 5075);
FORCEADD OFFPAGE..4
(-2300 4975);
FORCEPROP 2 LAST $XR1 27 
J 0
(-1994 4975);
DISPLAY 0.638298 (-1994 4975);
PAINT MONO (-1994 4975);
FORCEPROP 2 LAST $XR0 167 
J 0
(-2114 4975);
DISPLAY 0.638298 (-2114 4975);
PAINT MONO (-2114 4975);
FORCEPROP 2 LAST CDS_LIB standard
J 0
(-2300 4975);
DISPLAY INVISIBLE (-2300 4975);
FORCEPROP 1 LAST OFFPAGE TRUE
J 0
(-1975 4850);
DISPLAY 0.872340 (-1975 4850);
PAINT GREEN (-1975 4850);
DISPLAY INVISIBLE (-1975 4850);
FORCEPROP 1 LAST COMMENT_BODY TRUE
J 0
(-2325 4875);
DISPLAY 0.872340 (-2325 4875);
PAINT GREEN (-2325 4875);
DISPLAY INVISIBLE (-2325 4875);
FORCEPROP 2 LAST PATH I194
J 0
(-1975 5025);
DISPLAY 0.680851 (-1975 5025);
DISPLAY INVISIBLE (-1975 5025);
FORCEADD OFFPAGE..2
(-2300 5075);
FORCEPROP 2 LAST $XR0 172 
J 0
(-2111 5075);
DISPLAY 0.638298 (-2111 5075);
PAINT MONO (-2111 5075);
FORCEPROP 2 LAST CDS_LIB standard
J 0
(-2300 5075);
DISPLAY INVISIBLE (-2300 5075);
FORCEPROP 1 LAST OFFPAGE TRUE
J 0
(-1975 4950);
DISPLAY 0.872340 (-1975 4950);
PAINT GREEN (-1975 4950);
DISPLAY INVISIBLE (-1975 4950);
FORCEPROP 1 LAST COMMENT_BODY TRUE
J 0
(-2345 4980);
DISPLAY 0.872340 (-2345 4980);
PAINT GREEN (-2345 4980);
DISPLAY INVISIBLE (-2345 4980);
FORCEPROP 2 LAST PATH I195
J 0
(-2100 5125);
DISPLAY 0.680851 (-2100 5125);
DISPLAY INVISIBLE (-2100 5125);
FORCEADD OFFPAGE..2
(-2300 5125);
FORCEPROP 2 LAST $XR0 172 
J 0
(-2081 5125);
DISPLAY 0.638298 (-2081 5125);
PAINT MONO (-2081 5125);
FORCEPROP 2 LAST CDS_LIB standard
J 0
(-2300 5125);
DISPLAY INVISIBLE (-2300 5125);
FORCEPROP 1 LAST OFFPAGE TRUE
J 0
(-1975 5000);
DISPLAY 0.872340 (-1975 5000);
PAINT GREEN (-1975 5000);
DISPLAY INVISIBLE (-1975 5000);
FORCEPROP 1 LAST COMMENT_BODY TRUE
J 0
(-2345 5030);
DISPLAY 0.872340 (-2345 5030);
PAINT GREEN (-2345 5030);
DISPLAY INVISIBLE (-2345 5030);
FORCEPROP 2 LAST PATH I196
J 0
(-2100 5175);
DISPLAY 0.680851 (-2100 5175);
DISPLAY INVISIBLE (-2100 5175);
FORCEADD OFFPAGE..6
R 2
(-2300 5175);
FORCEPROP 2 LAST $XR1 150 
J 0
(-1996 5175);
DISPLAY 0.638298 (-1996 5175);
PAINT MONO (-1996 5175);
FORCEPROP 2 LAST $XR0 29 
J 0
(-2086 5175);
DISPLAY 0.638298 (-2086 5175);
PAINT MONO (-2086 5175);
FORCEPROP 2 LAST CDS_LIB standard
J 0
(-2300 5175);
DISPLAY INVISIBLE (-2300 5175);
FORCEPROP 1 LAST OFFPAGE TRUE
J 2
(-2625 5050);
DISPLAY 0.872340 (-2625 5050);
PAINT GREEN (-2625 5050);
DISPLAY INVISIBLE (-2625 5050);
FORCEPROP 1 LAST COMMENT_BODY TRUE
J 2
(-2400 5100);
DISPLAY 0.872340 (-2400 5100);
PAINT GREEN (-2400 5100);
DISPLAY INVISIBLE (-2400 5100);
FORCEPROP 2 LAST PATH I197
J 0
(-1975 5225);
DISPLAY 0.680851 (-1975 5225);
DISPLAY INVISIBLE (-1975 5225);
FORCEADD OFFPAGE..6
R 2
(-2300 5225);
FORCEPROP 2 LAST $XR1 150 
J 0
(-1996 5225);
DISPLAY 0.638298 (-1996 5225);
PAINT MONO (-1996 5225);
FORCEPROP 2 LAST $XR0 29 
J 0
(-2086 5225);
DISPLAY 0.638298 (-2086 5225);
PAINT MONO (-2086 5225);
FORCEPROP 2 LAST CDS_LIB standard
J 0
(-2300 5225);
DISPLAY INVISIBLE (-2300 5225);
FORCEPROP 1 LAST OFFPAGE TRUE
J 2
(-2625 5100);
DISPLAY 0.872340 (-2625 5100);
PAINT GREEN (-2625 5100);
DISPLAY INVISIBLE (-2625 5100);
FORCEPROP 1 LAST COMMENT_BODY TRUE
J 2
(-2400 5150);
DISPLAY 0.872340 (-2400 5150);
PAINT GREEN (-2400 5150);
DISPLAY INVISIBLE (-2400 5150);
FORCEPROP 2 LAST PATH I198
J 0
(-1975 5275);
DISPLAY 0.680851 (-1975 5275);
DISPLAY INVISIBLE (-1975 5275);
FORCEADD OFFPAGE..6
R 2
(-2300 5275);
FORCEPROP 2 LAST $XR1 150 
J 0
(-1996 5275);
DISPLAY 0.638298 (-1996 5275);
PAINT MONO (-1996 5275);
FORCEPROP 2 LAST $XR0 29 
J 0
(-2086 5275);
DISPLAY 0.638298 (-2086 5275);
PAINT MONO (-2086 5275);
FORCEPROP 2 LAST CDS_LIB standard
J 0
(-2300 5275);
DISPLAY INVISIBLE (-2300 5275);
FORCEPROP 1 LAST OFFPAGE TRUE
J 2
(-2625 5150);
DISPLAY 0.872340 (-2625 5150);
PAINT GREEN (-2625 5150);
DISPLAY INVISIBLE (-2625 5150);
FORCEPROP 1 LAST COMMENT_BODY TRUE
J 2
(-2400 5200);
DISPLAY 0.872340 (-2400 5200);
PAINT GREEN (-2400 5200);
DISPLAY INVISIBLE (-2400 5200);
FORCEPROP 2 LAST PATH I199
J 0
(-1975 5325);
DISPLAY 0.680851 (-1975 5325);
DISPLAY INVISIBLE (-1975 5325);
FORCEADD OFFPAGE..5
(-7800 925);
FORCEPROP 2 LAST $XR2 147 
J 0
(-8264 925);
DISPLAY 0.638298 (-8264 925);
PAINT MONO (-8264 925);
FORCEPROP 2 LAST $XR1 146 
J 0
(-8144 925);
DISPLAY 0.638298 (-8144 925);
PAINT MONO (-8144 925);
FORCEPROP 2 LAST $XR0 83 
J 0
(-8024 925);
DISPLAY 0.638298 (-8024 925);
PAINT MONO (-8024 925);
FORCEPROP 2 LAST CDS_LIB standard
J 0
(-7800 925);
DISPLAY INVISIBLE (-7800 925);
FORCEPROP 1 LAST OFFPAGE TRUE
J 0
(-7475 800);
DISPLAY 0.872340 (-7475 800);
PAINT GREEN (-7475 800);
DISPLAY INVISIBLE (-7475 800);
FORCEPROP 1 LAST COMMENT_BODY TRUE
J 0
(-7700 850);
DISPLAY 0.872340 (-7700 850);
PAINT GREEN (-7700 850);
DISPLAY INVISIBLE (-7700 850);
FORCEPROP 2 LAST PATH I2
J 0
(-8000 975);
DISPLAY 0.680851 (-8000 975);
DISPLAY INVISIBLE (-8000 975);
FORCEADD OFFPAGE..5
(-7800 1575);
FORCEPROP 2 LAST $XR0 217 
J 0
(-8055 1575);
DISPLAY 0.638298 (-8055 1575);
PAINT MONO (-8055 1575);
FORCEPROP 2 LAST CDS_LIB standard
J 0
(-7800 1575);
DISPLAY INVISIBLE (-7800 1575);
FORCEPROP 1 LAST OFFPAGE TRUE
J 0
(-7475 1450);
DISPLAY 0.872340 (-7475 1450);
PAINT GREEN (-7475 1450);
DISPLAY INVISIBLE (-7475 1450);
FORCEPROP 1 LAST COMMENT_BODY TRUE
J 0
(-7700 1500);
DISPLAY 0.872340 (-7700 1500);
PAINT GREEN (-7700 1500);
DISPLAY INVISIBLE (-7700 1500);
FORCEPROP 2 LAST PATH I20
J 0
(-8050 1625);
DISPLAY 0.680851 (-8050 1625);
DISPLAY INVISIBLE (-8050 1625);
FORCEADD OFFPAGE..6
R 2
(-2300 5325);
FORCEPROP 2 LAST $XR1 150 
J 0
(-1996 5325);
DISPLAY 0.638298 (-1996 5325);
PAINT MONO (-1996 5325);
FORCEPROP 2 LAST $XR0 29 
J 0
(-2086 5325);
DISPLAY 0.638298 (-2086 5325);
PAINT MONO (-2086 5325);
FORCEPROP 2 LAST CDS_LIB standard
J 0
(-2300 5325);
DISPLAY INVISIBLE (-2300 5325);
FORCEPROP 1 LAST OFFPAGE TRUE
J 2
(-2625 5200);
DISPLAY 0.872340 (-2625 5200);
PAINT GREEN (-2625 5200);
DISPLAY INVISIBLE (-2625 5200);
FORCEPROP 1 LAST COMMENT_BODY TRUE
J 2
(-2400 5250);
DISPLAY 0.872340 (-2400 5250);
PAINT GREEN (-2400 5250);
DISPLAY INVISIBLE (-2400 5250);
FORCEPROP 2 LAST PATH I200
J 0
(-1975 5375);
DISPLAY 0.680851 (-1975 5375);
DISPLAY INVISIBLE (-1975 5375);
FORCEADD OFFPAGE..1
R 2
(-2300 5375);
FORCEPROP 2 LAST $XR1 150 
J 0
(-2024 5375);
DISPLAY 0.638298 (-2024 5375);
PAINT MONO (-2024 5375);
FORCEPROP 2 LAST $XR0 29 
J 0
(-2114 5375);
DISPLAY 0.638298 (-2114 5375);
PAINT MONO (-2114 5375);
FORCEPROP 2 LAST CDS_LIB standard
J 0
(-2300 5375);
DISPLAY INVISIBLE (-2300 5375);
FORCEPROP 1 LAST OFFPAGE TRUE
J 2
(-2625 5250);
DISPLAY 0.872340 (-2625 5250);
PAINT GREEN (-2625 5250);
DISPLAY INVISIBLE (-2625 5250);
FORCEPROP 1 LAST COMMENT_BODY TRUE
J 2
(-2425 5275);
DISPLAY 0.872340 (-2425 5275);
PAINT GREEN (-2425 5275);
DISPLAY INVISIBLE (-2425 5275);
FORCEPROP 2 LAST PATH I201
J 0
(-2000 5425);
DISPLAY 0.680851 (-2000 5425);
DISPLAY INVISIBLE (-2000 5425);
FORCEADD OFFPAGE..1
R 2
(-2300 5425);
FORCEPROP 2 LAST $XR0 153 
J 0
(-2114 5425);
DISPLAY 0.638298 (-2114 5425);
PAINT MONO (-2114 5425);
FORCEPROP 2 LAST CDS_LIB standard
J 0
(-2300 5425);
DISPLAY INVISIBLE (-2300 5425);
FORCEPROP 1 LAST OFFPAGE TRUE
J 2
(-2625 5300);
DISPLAY 0.872340 (-2625 5300);
PAINT GREEN (-2625 5300);
DISPLAY INVISIBLE (-2625 5300);
FORCEPROP 1 LAST COMMENT_BODY TRUE
J 2
(-2425 5325);
DISPLAY 0.872340 (-2425 5325);
PAINT GREEN (-2425 5325);
DISPLAY INVISIBLE (-2425 5325);
FORCEPROP 2 LAST PATH I202
J 0
(-2000 5475);
DISPLAY 0.680851 (-2000 5475);
DISPLAY INVISIBLE (-2000 5475);
FORCEADD OFFPAGE..1
R 2
(-2300 5525);
FORCEPROP 2 LAST $XR2 150 
J 0
(-1904 5525);
DISPLAY 0.638298 (-1904 5525);
PAINT MONO (-1904 5525);
FORCEPROP 2 LAST $XR1 76 
J 0
(-1994 5525);
DISPLAY 0.638298 (-1994 5525);
PAINT MONO (-1994 5525);
FORCEPROP 2 LAST $XR0 29 
J 0
(-2084 5525);
DISPLAY 0.638298 (-2084 5525);
PAINT MONO (-2084 5525);
FORCEPROP 2 LAST CDS_LIB standard
J 0
(-2300 5525);
DISPLAY INVISIBLE (-2300 5525);
FORCEPROP 1 LAST OFFPAGE TRUE
J 2
(-2625 5400);
DISPLAY 0.872340 (-2625 5400);
PAINT GREEN (-2625 5400);
DISPLAY INVISIBLE (-2625 5400);
FORCEPROP 1 LAST COMMENT_BODY TRUE
J 2
(-2425 5425);
DISPLAY 0.872340 (-2425 5425);
PAINT GREEN (-2425 5425);
DISPLAY INVISIBLE (-2425 5425);
FORCEPROP 2 LAST PATH I203
J 0
(-1925 5575);
DISPLAY 0.680851 (-1925 5575);
DISPLAY INVISIBLE (-1925 5575);
FORCEADD OFFPAGE..1
R 2
(-2300 5475);
FORCEPROP 2 LAST $XR1 150 
J 0
(-2024 5475);
DISPLAY 0.638298 (-2024 5475);
PAINT MONO (-2024 5475);
FORCEPROP 2 LAST $XR0 29 
J 0
(-2114 5475);
DISPLAY 0.638298 (-2114 5475);
PAINT MONO (-2114 5475);
FORCEPROP 2 LAST CDS_LIB standard
J 0
(-2300 5475);
DISPLAY INVISIBLE (-2300 5475);
FORCEPROP 1 LAST OFFPAGE TRUE
J 2
(-2625 5350);
DISPLAY 0.872340 (-2625 5350);
PAINT GREEN (-2625 5350);
DISPLAY INVISIBLE (-2625 5350);
FORCEPROP 1 LAST COMMENT_BODY TRUE
J 2
(-2425 5375);
DISPLAY 0.872340 (-2425 5375);
PAINT GREEN (-2425 5375);
DISPLAY INVISIBLE (-2425 5375);
FORCEPROP 2 LAST PATH I204
J 0
(-2000 5525);
DISPLAY 0.680851 (-2000 5525);
DISPLAY INVISIBLE (-2000 5525);
FORCEADD OFFPAGE..2
(-2300 5775);
FORCEPROP 2 LAST $XR2 165 
J 0
(-1901 5775);
DISPLAY 0.638298 (-1901 5775);
PAINT MONO (-1901 5775);
FORCEPROP 2 LAST $XR1 28 
J 0
(-1991 5775);
DISPLAY 0.638298 (-1991 5775);
PAINT MONO (-1991 5775);
FORCEPROP 2 LAST $XR0 167 
J 0
(-2111 5775);
DISPLAY 0.638298 (-2111 5775);
PAINT MONO (-2111 5775);
FORCEPROP 2 LAST CDS_LIB standard
J 0
(-2300 5775);
DISPLAY INVISIBLE (-2300 5775);
FORCEPROP 1 LAST OFFPAGE TRUE
J 0
(-1975 5650);
DISPLAY 0.872340 (-1975 5650);
PAINT GREEN (-1975 5650);
DISPLAY INVISIBLE (-1975 5650);
FORCEPROP 1 LAST COMMENT_BODY TRUE
J 0
(-2345 5680);
DISPLAY 0.872340 (-2345 5680);
PAINT GREEN (-2345 5680);
DISPLAY INVISIBLE (-2345 5680);
FORCEPROP 2 LAST PATH I206
J 0
(-1900 5825);
DISPLAY 0.680851 (-1900 5825);
DISPLAY INVISIBLE (-1900 5825);
FORCEADD OFFPAGE..1
R 2
(-2300 5725);
FORCEPROP 2 LAST $XR0 172 
J 0
(-2114 5725);
DISPLAY 0.638298 (-2114 5725);
PAINT MONO (-2114 5725);
FORCEPROP 2 LAST CDS_LIB standard
J 0
(-2300 5725);
DISPLAY INVISIBLE (-2300 5725);
FORCEPROP 1 LAST OFFPAGE TRUE
J 2
(-2625 5600);
DISPLAY 0.872340 (-2625 5600);
PAINT GREEN (-2625 5600);
DISPLAY INVISIBLE (-2625 5600);
FORCEPROP 1 LAST COMMENT_BODY TRUE
J 2
(-2425 5625);
DISPLAY 0.872340 (-2425 5625);
PAINT GREEN (-2425 5625);
DISPLAY INVISIBLE (-2425 5625);
FORCEPROP 2 LAST PATH I207
J 0
(-2100 5775);
DISPLAY 0.680851 (-2100 5775);
DISPLAY INVISIBLE (-2100 5775);
FORCEADD OFFPAGE..1
R 2
(-2300 5925);
FORCEPROP 2 LAST $XR0 55 
J 0
(-2114 5925);
DISPLAY 0.638298 (-2114 5925);
PAINT MONO (-2114 5925);
FORCEPROP 2 LAST CDS_LIB standard
J 0
(-2300 5925);
DISPLAY INVISIBLE (-2300 5925);
FORCEPROP 1 LAST OFFPAGE TRUE
J 2
(-2625 5800);
DISPLAY 0.872340 (-2625 5800);
PAINT GREEN (-2625 5800);
DISPLAY INVISIBLE (-2625 5800);
FORCEPROP 1 LAST COMMENT_BODY TRUE
J 2
(-2425 5825);
DISPLAY 0.872340 (-2425 5825);
PAINT GREEN (-2425 5825);
DISPLAY INVISIBLE (-2425 5825);
FORCEPROP 2 LAST PATH I209
J 0
(-2100 5975);
DISPLAY 0.680851 (-2100 5975);
DISPLAY INVISIBLE (-2100 5975);
FORCEADD OFFPAGE..5
(-7800 2075);
FORCEPROP 2 LAST $XR0 226 
J 0
(-8055 2075);
DISPLAY 0.638298 (-8055 2075);
PAINT MONO (-8055 2075);
FORCEPROP 2 LAST CDS_LIB standard
J 0
(-7800 2075);
DISPLAY INVISIBLE (-7800 2075);
FORCEPROP 1 LAST OFFPAGE TRUE
J 0
(-7475 1950);
DISPLAY 0.872340 (-7475 1950);
PAINT GREEN (-7475 1950);
DISPLAY INVISIBLE (-7475 1950);
FORCEPROP 1 LAST COMMENT_BODY TRUE
J 0
(-7700 2000);
DISPLAY 0.872340 (-7700 2000);
PAINT GREEN (-7700 2000);
DISPLAY INVISIBLE (-7700 2000);
FORCEPROP 2 LAST PATH I21
J 0
(-8050 2125);
DISPLAY 0.680851 (-8050 2125);
DISPLAY INVISIBLE (-8050 2125);
FORCEADD OFFPAGE..1
R 2
(-2300 5975);
FORCEPROP 2 LAST $XR0 188 
J 0
(-2084 5975);
DISPLAY 0.638298 (-2084 5975);
PAINT MONO (-2084 5975);
FORCEPROP 2 LAST CDS_LIB standard
J 0
(-2300 5975);
DISPLAY INVISIBLE (-2300 5975);
FORCEPROP 1 LAST OFFPAGE TRUE
J 2
(-2625 5850);
DISPLAY 0.872340 (-2625 5850);
PAINT GREEN (-2625 5850);
DISPLAY INVISIBLE (-2625 5850);
FORCEPROP 1 LAST COMMENT_BODY TRUE
J 2
(-2425 5875);
DISPLAY 0.872340 (-2425 5875);
PAINT GREEN (-2425 5875);
DISPLAY INVISIBLE (-2425 5875);
FORCEPROP 2 LAST PATH I210
J 0
(-2100 6025);
DISPLAY 0.680851 (-2100 6025);
DISPLAY INVISIBLE (-2100 6025);
FORCEADD OFFPAGE..6
R 2
(-2300 6025);
FORCEPROP 2 LAST $XR0 151 
J 0
(-2086 6025);
DISPLAY 0.638298 (-2086 6025);
PAINT MONO (-2086 6025);
FORCEPROP 2 LAST CDS_LIB standard
J 0
(-2300 6025);
DISPLAY INVISIBLE (-2300 6025);
FORCEPROP 1 LAST OFFPAGE TRUE
J 2
(-2625 5900);
DISPLAY 0.872340 (-2625 5900);
PAINT GREEN (-2625 5900);
DISPLAY INVISIBLE (-2625 5900);
FORCEPROP 1 LAST COMMENT_BODY TRUE
J 2
(-2400 5950);
DISPLAY 0.872340 (-2400 5950);
PAINT GREEN (-2400 5950);
DISPLAY INVISIBLE (-2400 5950);
FORCEPROP 2 LAST PATH I211
J 0
(-2075 6075);
DISPLAY 0.680851 (-2075 6075);
DISPLAY INVISIBLE (-2075 6075);
FORCEADD OFFPAGE..1
R 2
(-2300 6075);
FORCEPROP 2 LAST $XR0 151 
J 0
(-2114 6075);
DISPLAY 0.638298 (-2114 6075);
PAINT MONO (-2114 6075);
FORCEPROP 2 LAST CDS_LIB standard
J 0
(-2300 6075);
DISPLAY INVISIBLE (-2300 6075);
FORCEPROP 1 LAST OFFPAGE TRUE
J 2
(-2625 5950);
DISPLAY 0.872340 (-2625 5950);
PAINT GREEN (-2625 5950);
DISPLAY INVISIBLE (-2625 5950);
FORCEPROP 1 LAST COMMENT_BODY TRUE
J 2
(-2425 5975);
DISPLAY 0.872340 (-2425 5975);
PAINT GREEN (-2425 5975);
DISPLAY INVISIBLE (-2425 5975);
FORCEPROP 2 LAST PATH I212
J 0
(-2100 6125);
DISPLAY 0.680851 (-2100 6125);
DISPLAY INVISIBLE (-2100 6125);
FORCEADD OFFPAGE..1
R 2
(-2300 6125);
FORCEPROP 2 LAST $XR0 28 
J 0
(-2114 6125);
DISPLAY 0.638298 (-2114 6125);
PAINT MONO (-2114 6125);
FORCEPROP 2 LAST CDS_LIB standard
J 0
(-2300 6125);
DISPLAY INVISIBLE (-2300 6125);
FORCEPROP 1 LAST OFFPAGE TRUE
J 2
(-2625 6000);
DISPLAY 0.872340 (-2625 6000);
PAINT GREEN (-2625 6000);
DISPLAY INVISIBLE (-2625 6000);
FORCEPROP 1 LAST COMMENT_BODY TRUE
J 2
(-2425 6025);
DISPLAY 0.872340 (-2425 6025);
PAINT GREEN (-2425 6025);
DISPLAY INVISIBLE (-2425 6025);
FORCEPROP 2 LAST PATH I213
J 0
(-2100 6175);
DISPLAY 0.680851 (-2100 6175);
DISPLAY INVISIBLE (-2100 6175);
FORCEADD OFFPAGE..2
(-2300 6175);
FORCEPROP 2 LAST $XR0 166 
J 0
(-2111 6175);
DISPLAY 0.638298 (-2111 6175);
PAINT MONO (-2111 6175);
FORCEPROP 2 LAST CDS_LIB standard
J 0
(-2300 6175);
DISPLAY INVISIBLE (-2300 6175);
FORCEPROP 1 LAST OFFPAGE TRUE
J 0
(-1975 6050);
DISPLAY 0.872340 (-1975 6050);
PAINT GREEN (-1975 6050);
DISPLAY INVISIBLE (-1975 6050);
FORCEPROP 1 LAST COMMENT_BODY TRUE
J 0
(-2345 6080);
DISPLAY 0.872340 (-2345 6080);
PAINT GREEN (-2345 6080);
DISPLAY INVISIBLE (-2345 6080);
FORCEPROP 2 LAST PATH I214
J 0
(-2100 6225);
DISPLAY 0.680851 (-2100 6225);
DISPLAY INVISIBLE (-2100 6225);
FORCEADD Q_RES..1
(-3225 6175);
FORCEPROP 1 LAST LOCATION R933
J 0
(-3100 6175);
DISPLAY 0.489362 (-3100 6175);
PAINT SKYBLUE (-3100 6175);
FORCEPROP 0 LAST $SEC 1
J 2
(-3100 6225);
DISPLAY 0.680851 (-3100 6225);
PAINT MONO (-3100 6225);
DISPLAY INVISIBLE (-3100 6225);
FORCEPROP 0 LAST CDS_SEC 1
J 2
(-3100 6225);
DISPLAY 1.021277 (-3100 6225);
DISPLAY INVISIBLE (-3100 6225);
FORCEPROP 1 LASTPIN (-3325 6175) $PN 1
J 0
(-3313 6187);
DISPLAY 0.489362 (-3313 6187);
PAINT MONO (-3313 6187);
FORCEPROP 1 LASTPIN (-3125 6175) $PN 2
J 0
(-3163 6187);
DISPLAY 0.489362 (-3163 6187);
PAINT MONO (-3163 6187);
FORCEPROP 1 LAST VALUE 33
J 2
(-3350 6175);
DISPLAY 0.489362 (-3350 6175);
PAINT SKYBLUE (-3350 6175);
FORCEPROP 2 LAST CDS_LIB pure_quanta
J 2
(-3225 6175);
DISPLAY INVISIBLE (-3225 6175);
FORCEPROP 2 LAST BOM_COST MEM
J 2
(-3200 6325);
DISPLAY 0.744681 (-3200 6325);
PAINT WHITE (-3200 6325);
DISPLAY INVISIBLE (-3200 6325);
FORCEPROP 1 LAST WATTAGE 1/16W
J 2
(-3300 6100);
DISPLAY 0.489362 (-3300 6100);
PAINT SKYBLUE (-3300 6100);
DISPLAY INVISIBLE (-3300 6100);
FORCEPROP 1 LAST MATERIAL CHIP
J 2
(-3050 6150);
DISPLAY 0.489362 (-3050 6150);
PAINT SKYBLUE (-3050 6150);
DISPLAY INVISIBLE (-3050 6150);
FORCEPROP 1 LAST TOLERANCE 5%
J 0
(-3350 6150);
DISPLAY 0.489362 (-3350 6150);
PAINT SKYBLUE (-3350 6150);
DISPLAY INVISIBLE (-3350 6150);
FORCEPROP 1 LAST PACK_TYPE 0402LF
J 2
(-3050 6100);
DISPLAY 0.489362 (-3050 6100);
PAINT SKYBLUE (-3050 6100);
DISPLAY INVISIBLE (-3050 6100);
FORCEPROP 1 LAST PATH I215
J 0
(-3275 6325);
DISPLAY 0.978723 (-3275 6325);
PAINT WHITE (-3275 6325);
DISPLAY INVISIBLE (-3275 6325);
FORCEPROP 1 LAST PART_NUMBER CS03302JB10
J 2
(-3125 6225);
DISPLAY 0.489362 (-3125 6225);
PAINT SKYBLUE (-3125 6225);
DISPLAY INVISIBLE (-3125 6225);
FORCEADD LCMXO3LF9400C5BG484C..2
(-4500 1850);
FORCEPROP 1 LAST LOCATION U18
J 0
(-5225 3408);
DISPLAY 0.723404 (-5225 3408);
PAINT GREEN (-5225 3408);
FORCEPROP 0 LAST $SEC 2
J 0
(-5225 3550);
DISPLAY 0.680851 (-5225 3550);
PAINT MONO (-5225 3550);
DISPLAY INVISIBLE (-5225 3550);
FORCEPROP 0 LAST CDS_SEC 2
J 0
(-5200 3650);
DISPLAY 0.680851 (-5200 3650);
DISPLAY INVISIBLE (-5200 3650);
FORCEPROP 0 LASTPIN (-5375 3175) $PN AA2
J 2
(-5385 3185);
DISPLAY 0.680851 (-5385 3185);
PAINT MONO (-5385 3185);
FORCEPROP 0 LASTPIN (-5375 3125) $PN AB2
J 2
(-5385 3135);
DISPLAY 0.680851 (-5385 3135);
PAINT MONO (-5385 3135);
FORCEPROP 0 LASTPIN (-5375 3075) $PN V6
J 2
(-5385 3085);
DISPLAY 0.680851 (-5385 3085);
PAINT MONO (-5385 3085);
FORCEPROP 0 LASTPIN (-5375 3025) $PN U6
J 2
(-5385 3035);
DISPLAY 0.680851 (-5385 3035);
PAINT MONO (-5385 3035);
FORCEPROP 0 LASTPIN (-5375 2975) $PN AA3
J 2
(-5385 2985);
DISPLAY 0.680851 (-5385 2985);
PAINT MONO (-5385 2985);
FORCEPROP 0 LASTPIN (-5375 2925) $PN AB3
J 2
(-5385 2935);
DISPLAY 0.680851 (-5385 2935);
PAINT MONO (-5385 2935);
FORCEPROP 0 LASTPIN (-5375 2875) $PN Y4
J 2
(-5385 2885);
DISPLAY 0.680851 (-5385 2885);
PAINT MONO (-5385 2885);
FORCEPROP 0 LASTPIN (-5375 2825) $PN W5
J 2
(-5385 2835);
DISPLAY 0.680851 (-5385 2835);
PAINT MONO (-5385 2835);
FORCEPROP 0 LASTPIN (-5375 2775) $PN AA4
J 2
(-5385 2785);
DISPLAY 0.680851 (-5385 2785);
PAINT MONO (-5385 2785);
FORCEPROP 0 LASTPIN (-5375 2725) $PN AB4
J 2
(-5385 2735);
DISPLAY 0.680851 (-5385 2735);
PAINT MONO (-5385 2735);
FORCEPROP 0 LASTPIN (-5375 2675) $PN U7
J 2
(-5385 2685);
DISPLAY 0.680851 (-5385 2685);
PAINT MONO (-5385 2685);
FORCEPROP 0 LASTPIN (-5375 2625) $PN T8
J 2
(-5385 2635);
DISPLAY 0.680851 (-5385 2635);
PAINT MONO (-5385 2635);
FORCEPROP 0 LASTPIN (-5375 2575) $PN AA5
J 2
(-5385 2585);
DISPLAY 0.680851 (-5385 2585);
PAINT MONO (-5385 2585);
FORCEPROP 0 LASTPIN (-5375 2525) $PN AB5
J 2
(-5385 2535);
DISPLAY 0.680851 (-5385 2535);
PAINT MONO (-5385 2535);
FORCEPROP 0 LASTPIN (-5375 2475) $PN Y5
J 2
(-5385 2485);
DISPLAY 0.680851 (-5385 2485);
PAINT MONO (-5385 2485);
FORCEPROP 0 LASTPIN (-5375 2425) $PN Y6
J 2
(-5385 2435);
DISPLAY 0.680851 (-5385 2435);
PAINT MONO (-5385 2435);
FORCEPROP 0 LASTPIN (-5375 2375) $PN AA6
J 2
(-5385 2385);
DISPLAY 0.680851 (-5385 2385);
PAINT MONO (-5385 2385);
FORCEPROP 0 LASTPIN (-5375 2325) $PN AB6
J 2
(-5385 2335);
DISPLAY 0.680851 (-5385 2335);
PAINT MONO (-5385 2335);
FORCEPROP 0 LASTPIN (-5375 2275) $PN W6
J 2
(-5385 2285);
DISPLAY 0.680851 (-5385 2285);
PAINT MONO (-5385 2285);
FORCEPROP 0 LASTPIN (-5375 2225) $PN V7
J 2
(-5385 2235);
DISPLAY 0.680851 (-5385 2235);
PAINT MONO (-5385 2235);
FORCEPROP 0 LASTPIN (-5375 2175) $PN AA7
J 2
(-5385 2185);
DISPLAY 0.680851 (-5385 2185);
PAINT MONO (-5385 2185);
FORCEPROP 0 LASTPIN (-5375 2125) $PN AB7
J 2
(-5385 2135);
DISPLAY 0.680851 (-5385 2135);
PAINT MONO (-5385 2135);
FORCEPROP 0 LASTPIN (-5375 2075) $PN V8
J 2
(-5385 2085);
DISPLAY 0.680851 (-5385 2085);
PAINT MONO (-5385 2085);
FORCEPROP 0 LASTPIN (-5375 2025) $PN U8
J 2
(-5385 2035);
DISPLAY 0.680851 (-5385 2035);
PAINT MONO (-5385 2035);
FORCEPROP 0 LASTPIN (-5375 1975) $PN T9
J 2
(-5385 1985);
DISPLAY 0.680851 (-5385 1985);
PAINT MONO (-5385 1985);
FORCEPROP 0 LASTPIN (-5375 1925) $PN U9
J 2
(-5385 1935);
DISPLAY 0.680851 (-5385 1935);
PAINT MONO (-5385 1935);
FORCEPROP 0 LASTPIN (-5375 1875) $PN V9
J 2
(-5385 1885);
DISPLAY 0.680851 (-5385 1885);
PAINT MONO (-5385 1885);
FORCEPROP 0 LASTPIN (-5375 1825) $PN W8
J 2
(-5385 1835);
DISPLAY 0.680851 (-5385 1835);
PAINT MONO (-5385 1835);
FORCEPROP 0 LASTPIN (-5375 1775) $PN AA8
J 2
(-5385 1785);
DISPLAY 0.680851 (-5385 1785);
PAINT MONO (-5385 1785);
FORCEPROP 0 LASTPIN (-5375 1725) $PN AB8
J 2
(-5385 1735);
DISPLAY 0.680851 (-5385 1735);
PAINT MONO (-5385 1735);
FORCEPROP 0 LASTPIN (-5375 1675) $PN Y8
J 2
(-5385 1685);
DISPLAY 0.680851 (-5385 1685);
PAINT MONO (-5385 1685);
FORCEPROP 0 LASTPIN (-5375 1625) $PN W9
J 2
(-5385 1635);
DISPLAY 0.680851 (-5385 1635);
PAINT MONO (-5385 1635);
FORCEPROP 0 LASTPIN (-5375 1575) $PN AA9
J 2
(-5385 1585);
DISPLAY 0.680851 (-5385 1585);
PAINT MONO (-5385 1585);
FORCEPROP 0 LASTPIN (-5375 1525) $PN AB9
J 2
(-5385 1535);
DISPLAY 0.680851 (-5385 1535);
PAINT MONO (-5385 1535);
FORCEPROP 0 LASTPIN (-5375 1475) $PN T10
J 2
(-5385 1485);
DISPLAY 0.680851 (-5385 1485);
PAINT MONO (-5385 1485);
FORCEPROP 0 LASTPIN (-5375 1425) $PN U10
J 2
(-5385 1435);
DISPLAY 0.680851 (-5385 1435);
PAINT MONO (-5385 1435);
FORCEPROP 0 LASTPIN (-5375 1375) $PN V10
J 2
(-5385 1385);
DISPLAY 0.680851 (-5385 1385);
PAINT MONO (-5385 1385);
FORCEPROP 0 LASTPIN (-5375 1325) $PN W10
J 2
(-5385 1335);
DISPLAY 0.680851 (-5385 1335);
PAINT MONO (-5385 1335);
FORCEPROP 0 LASTPIN (-5375 1275) $PN Y9
J 2
(-5385 1285);
DISPLAY 0.680851 (-5385 1285);
PAINT MONO (-5385 1285);
FORCEPROP 0 LASTPIN (-5375 1225) $PN Y10
J 2
(-5385 1235);
DISPLAY 0.680851 (-5385 1235);
PAINT MONO (-5385 1235);
FORCEPROP 0 LASTPIN (-5375 1125) $PN AA10
J 2
(-5385 1135);
DISPLAY 0.680851 (-5385 1135);
PAINT MONO (-5385 1135);
FORCEPROP 0 LASTPIN (-5375 1075) $PN AB10
J 2
(-5385 1085);
DISPLAY 0.680851 (-5385 1085);
PAINT MONO (-5385 1085);
FORCEPROP 0 LASTPIN (-5375 1025) $PN T11
J 2
(-5385 1035);
DISPLAY 0.680851 (-5385 1035);
PAINT MONO (-5385 1035);
FORCEPROP 0 LASTPIN (-5375 975) $PN U11
J 2
(-5385 985);
DISPLAY 0.680851 (-5385 985);
PAINT MONO (-5385 985);
FORCEPROP 0 LASTPIN (-5375 925) $PN AA11
J 2
(-5385 935);
DISPLAY 0.680851 (-5385 935);
PAINT MONO (-5385 935);
FORCEPROP 0 LASTPIN (-5375 875) $PN AB11
J 2
(-5385 885);
DISPLAY 0.680851 (-5385 885);
PAINT MONO (-5385 885);
FORCEPROP 0 LASTPIN (-5375 825) $PN V11
J 2
(-5385 835);
DISPLAY 0.680851 (-5385 835);
PAINT MONO (-5385 835);
FORCEPROP 0 LASTPIN (-5375 775) $PN Y11
J 2
(-5385 785);
DISPLAY 0.680851 (-5385 785);
PAINT MONO (-5385 785);
FORCEPROP 0 LASTPIN (-5375 725) $PN Y12
J 2
(-5385 735);
DISPLAY 0.680851 (-5385 735);
PAINT MONO (-5385 735);
FORCEPROP 0 LASTPIN (-5375 675) $PN T12
J 2
(-5385 685);
DISPLAY 0.680851 (-5385 685);
PAINT MONO (-5385 685);
FORCEPROP 0 LASTPIN (-5375 625) $PN U12
J 2
(-5385 635);
DISPLAY 0.680851 (-5385 635);
PAINT MONO (-5385 635);
FORCEPROP 0 LASTPIN (-5375 575) $PN V12
J 2
(-5385 585);
DISPLAY 0.680851 (-5385 585);
PAINT MONO (-5385 585);
FORCEPROP 0 LASTPIN (-3625 2975) $PN AB12
J 0
(-3615 2985);
DISPLAY 0.680851 (-3615 2985);
PAINT MONO (-3615 2985);
FORCEPROP 0 LASTPIN (-3625 2925) $PN AA12
J 0
(-3615 2935);
DISPLAY 0.680851 (-3615 2935);
PAINT MONO (-3615 2935);
FORCEPROP 0 LASTPIN (-3625 2875) $PN V13
J 0
(-3615 2885);
DISPLAY 0.680851 (-3615 2885);
PAINT MONO (-3615 2885);
FORCEPROP 0 LASTPIN (-3625 2825) $PN U13
J 0
(-3615 2835);
DISPLAY 0.680851 (-3615 2835);
PAINT MONO (-3615 2835);
FORCEPROP 0 LASTPIN (-3625 2775) $PN AB13
J 0
(-3615 2785);
DISPLAY 0.680851 (-3615 2785);
PAINT MONO (-3615 2785);
FORCEPROP 0 LASTPIN (-3625 2725) $PN AA13
J 0
(-3615 2735);
DISPLAY 0.680851 (-3615 2735);
PAINT MONO (-3615 2735);
FORCEPROP 0 LASTPIN (-3625 2675) $PN Y13
J 0
(-3615 2685);
DISPLAY 0.680851 (-3615 2685);
PAINT MONO (-3615 2685);
FORCEPROP 0 LASTPIN (-3625 2625) $PN W13
J 0
(-3615 2635);
DISPLAY 0.680851 (-3615 2635);
PAINT MONO (-3615 2635);
FORCEPROP 0 LASTPIN (-3625 2575) $PN T13
J 0
(-3615 2585);
DISPLAY 0.680851 (-3615 2585);
PAINT MONO (-3615 2585);
FORCEPROP 0 LASTPIN (-3625 2525) $PN T14
J 0
(-3615 2535);
DISPLAY 0.680851 (-3615 2535);
PAINT MONO (-3615 2535);
FORCEPROP 0 LASTPIN (-3625 2475) $PN U14
J 0
(-3615 2485);
DISPLAY 0.680851 (-3615 2485);
PAINT MONO (-3615 2485);
FORCEPROP 0 LASTPIN (-3625 2425) $PN V14
J 0
(-3615 2435);
DISPLAY 0.680851 (-3615 2435);
PAINT MONO (-3615 2435);
FORCEPROP 0 LASTPIN (-3625 2375) $PN AB14
J 0
(-3615 2385);
DISPLAY 0.680851 (-3615 2385);
PAINT MONO (-3615 2385);
FORCEPROP 0 LASTPIN (-3625 2325) $PN AA14
J 0
(-3615 2335);
DISPLAY 0.680851 (-3615 2335);
PAINT MONO (-3615 2335);
FORCEPROP 0 LASTPIN (-3625 2275) $PN Y14
J 0
(-3615 2285);
DISPLAY 0.680851 (-3615 2285);
PAINT MONO (-3615 2285);
FORCEPROP 0 LASTPIN (-3625 2225) $PN W14
J 0
(-3615 2235);
DISPLAY 0.680851 (-3615 2235);
PAINT MONO (-3615 2235);
FORCEPROP 0 LASTPIN (-3625 2175) $PN AB15
J 0
(-3615 2185);
DISPLAY 0.680851 (-3615 2185);
PAINT MONO (-3615 2185);
FORCEPROP 0 LASTPIN (-3625 2125) $PN AA15
J 0
(-3615 2135);
DISPLAY 0.680851 (-3615 2135);
PAINT MONO (-3615 2135);
FORCEPROP 0 LASTPIN (-3625 2075) $PN Y15
J 0
(-3615 2085);
DISPLAY 0.680851 (-3615 2085);
PAINT MONO (-3615 2085);
FORCEPROP 0 LASTPIN (-3625 2025) $PN W15
J 0
(-3615 2035);
DISPLAY 0.680851 (-3615 2035);
PAINT MONO (-3615 2035);
FORCEPROP 0 LASTPIN (-3625 1975) $PN AB16
J 0
(-3615 1985);
DISPLAY 0.680851 (-3615 1985);
PAINT MONO (-3615 1985);
FORCEPROP 0 LASTPIN (-3625 1925) $PN AA16
J 0
(-3615 1935);
DISPLAY 0.680851 (-3615 1935);
PAINT MONO (-3615 1935);
FORCEPROP 0 LASTPIN (-3625 1875) $PN V15
J 0
(-3615 1885);
DISPLAY 0.680851 (-3615 1885);
PAINT MONO (-3615 1885);
FORCEPROP 0 LASTPIN (-3625 1825) $PN U15
J 0
(-3615 1835);
DISPLAY 0.680851 (-3615 1835);
PAINT MONO (-3615 1835);
FORCEPROP 0 LASTPIN (-3625 1775) $PN AB17
J 0
(-3615 1785);
DISPLAY 0.680851 (-3615 1785);
PAINT MONO (-3615 1785);
FORCEPROP 0 LASTPIN (-3625 1725) $PN AA17
J 0
(-3615 1735);
DISPLAY 0.680851 (-3615 1735);
PAINT MONO (-3615 1735);
FORCEPROP 0 LASTPIN (-3625 1675) $PN Y17
J 0
(-3615 1685);
DISPLAY 0.680851 (-3615 1685);
PAINT MONO (-3615 1685);
FORCEPROP 0 LASTPIN (-3625 1625) $PN V16
J 0
(-3615 1635);
DISPLAY 0.680851 (-3615 1635);
PAINT MONO (-3615 1635);
FORCEPROP 0 LASTPIN (-3625 1575) $PN AB18
J 0
(-3615 1585);
DISPLAY 0.680851 (-3615 1585);
PAINT MONO (-3615 1585);
FORCEPROP 0 LASTPIN (-3625 1525) $PN AA18
J 0
(-3615 1535);
DISPLAY 0.680851 (-3615 1535);
PAINT MONO (-3615 1535);
FORCEPROP 0 LASTPIN (-3625 1475) $PN Y18
J 0
(-3615 1485);
DISPLAY 0.680851 (-3615 1485);
PAINT MONO (-3615 1485);
FORCEPROP 0 LASTPIN (-3625 1425) $PN W17
J 0
(-3615 1435);
DISPLAY 0.680851 (-3615 1435);
PAINT MONO (-3615 1435);
FORCEPROP 0 LASTPIN (-3625 1375) $PN AB19
J 0
(-3615 1385);
DISPLAY 0.680851 (-3615 1385);
PAINT MONO (-3615 1385);
FORCEPROP 0 LASTPIN (-3625 1325) $PN AA19
J 0
(-3615 1335);
DISPLAY 0.680851 (-3615 1335);
PAINT MONO (-3615 1335);
FORCEPROP 0 LASTPIN (-3625 1275) $PN T15
J 0
(-3615 1285);
DISPLAY 0.680851 (-3615 1285);
PAINT MONO (-3615 1285);
FORCEPROP 0 LASTPIN (-3625 1225) $PN U16
J 0
(-3615 1235);
DISPLAY 0.680851 (-3615 1235);
PAINT MONO (-3615 1235);
FORCEPROP 0 LASTPIN (-3625 1175) $PN AB20
J 0
(-3615 1185);
DISPLAY 0.680851 (-3615 1185);
PAINT MONO (-3615 1185);
FORCEPROP 0 LASTPIN (-3625 1125) $PN AA20
J 0
(-3615 1135);
DISPLAY 0.680851 (-3615 1135);
PAINT MONO (-3615 1135);
FORCEPROP 0 LASTPIN (-3625 1075) $PN Y19
J 0
(-3615 1085);
DISPLAY 0.680851 (-3615 1085);
PAINT MONO (-3615 1085);
FORCEPROP 0 LASTPIN (-3625 1025) $PN W18
J 0
(-3615 1035);
DISPLAY 0.680851 (-3615 1035);
PAINT MONO (-3615 1035);
FORCEPROP 0 LASTPIN (-3625 975) $PN AB21
J 0
(-3615 985);
DISPLAY 0.680851 (-3615 985);
PAINT MONO (-3615 985);
FORCEPROP 0 LASTPIN (-3625 925) $PN AA21
J 0
(-3615 935);
DISPLAY 0.680851 (-3615 935);
PAINT MONO (-3615 935);
FORCEPROP 0 LASTPIN (-3625 875) $PN V17
J 0
(-3615 885);
DISPLAY 0.680851 (-3615 885);
PAINT MONO (-3615 885);
FORCEPROP 0 LASTPIN (-3625 825) $PN T16
J 0
(-3615 835);
DISPLAY 0.680851 (-3615 835);
PAINT MONO (-3615 835);
FORCEPROP 2 LAST VALUE LCMXO3LF-9400C-5BG484C
J 0
(-5225 3455);
DISPLAY 0.489362 (-5225 3455);
PAINT SKYBLUE (-5225 3455);
FORCEPROP 2 LAST PART_TYPE SMLF
J 0
(-5225 3500);
DISPLAY 0.680851 (-5225 3500);
FORCEPROP 1 LAST MATERIAL IC
J 0
(-5220 3239);
DISPLAY 0.723404 (-5220 3239);
PAINT GREEN (-5220 3239);
FORCEPROP 2 LAST CDS_LIB pure_quanta
J 0
(-4500 1850);
DISPLAY INVISIBLE (-4500 1850);
FORCEPROP 1 LAST NEEDS_NO_SIZE TRUE
J 0
(-4500 1850);
DISPLAY 0.723404 (-4500 1850);
PAINT GREEN (-4500 1850);
DISPLAY INVISIBLE (-4500 1850);
FORCEPROP 1 LAST CDS_LMAN_SYM_OUTLINE -725,1375,725,-1375
J 0
(-4500 1850);
DISPLAY 0.468085 (-4500 1850);
PAINT GREEN (-4500 1850);
DISPLAY INVISIBLE (-4500 1850);
FORCEPROP 1 LAST PATH I216
J 0
(-4500 1850);
DISPLAY 0.723404 (-4500 1850);
PAINT GREEN (-4500 1850);
DISPLAY INVISIBLE (-4500 1850);
FORCEPROP 1 LAST PART_NUMBER AJ094000T08
J 0
(-5220 3366);
DISPLAY 0.723404 (-5220 3366);
PAINT GREEN (-5220 3366);
DISPLAY INVISIBLE (-5220 3366);
FORCEADD LCMXO3LF9400C5BG484C..7
(-4825 5000);
FORCEPROP 1 LAST LOCATION U18
J 0
(-5300 6477);
DISPLAY 0.723404 (-5300 6477);
PAINT GREEN (-5300 6477);
FORCEPROP 0 LAST $SEC 7
J 0
(-5300 6625);
DISPLAY 0.680851 (-5300 6625);
PAINT MONO (-5300 6625);
DISPLAY INVISIBLE (-5300 6625);
FORCEPROP 0 LAST CDS_SEC 7
J 0
(-5300 6700);
DISPLAY 0.680851 (-5300 6700);
DISPLAY INVISIBLE (-5300 6700);
FORCEPROP 0 LASTPIN (-5450 6175) $PN C21
J 2
(-5460 6185);
DISPLAY 0.680851 (-5460 6185);
PAINT MONO (-5460 6185);
FORCEPROP 0 LASTPIN (-5450 6125) $PN C22
J 2
(-5460 6135);
DISPLAY 0.680851 (-5460 6135);
PAINT MONO (-5460 6135);
FORCEPROP 0 LASTPIN (-5450 6075) $PN F17
J 2
(-5460 6085);
DISPLAY 0.680851 (-5460 6085);
PAINT MONO (-5460 6085);
FORCEPROP 0 LASTPIN (-5450 6025) $PN G16
J 2
(-5460 6035);
DISPLAY 0.680851 (-5460 6035);
PAINT MONO (-5460 6035);
FORCEPROP 0 LASTPIN (-5450 5975) $PN D22
J 2
(-5460 5985);
DISPLAY 0.680851 (-5460 5985);
PAINT MONO (-5460 5985);
FORCEPROP 0 LASTPIN (-5450 5925) $PN D21
J 2
(-5460 5935);
DISPLAY 0.680851 (-5460 5935);
PAINT MONO (-5460 5935);
FORCEPROP 0 LASTPIN (-5450 5875) $PN D19
J 2
(-5460 5885);
DISPLAY 0.680851 (-5460 5885);
PAINT MONO (-5460 5885);
FORCEPROP 0 LASTPIN (-5450 5825) $PN D20
J 2
(-5460 5835);
DISPLAY 0.680851 (-5460 5835);
PAINT MONO (-5460 5835);
FORCEPROP 0 LASTPIN (-5450 5775) $PN E22
J 2
(-5460 5785);
DISPLAY 0.680851 (-5460 5785);
PAINT MONO (-5460 5785);
FORCEPROP 0 LASTPIN (-5450 5725) $PN E21
J 2
(-5460 5735);
DISPLAY 0.680851 (-5460 5735);
PAINT MONO (-5460 5735);
FORCEPROP 0 LASTPIN (-5450 5675) $PN E19
J 2
(-5460 5685);
DISPLAY 0.680851 (-5460 5685);
PAINT MONO (-5460 5685);
FORCEPROP 0 LASTPIN (-5450 5625) $PN E20
J 2
(-5460 5635);
DISPLAY 0.680851 (-5460 5635);
PAINT MONO (-5460 5635);
FORCEPROP 0 LASTPIN (-5450 5575) $PN F22
J 2
(-5460 5585);
DISPLAY 0.680851 (-5460 5585);
PAINT MONO (-5460 5585);
FORCEPROP 0 LASTPIN (-5450 5525) $PN G22
J 2
(-5460 5535);
DISPLAY 0.680851 (-5460 5535);
PAINT MONO (-5460 5535);
FORCEPROP 0 LASTPIN (-5450 5475) $PN F18
J 2
(-5460 5485);
DISPLAY 0.680851 (-5460 5485);
PAINT MONO (-5460 5485);
FORCEPROP 0 LASTPIN (-5450 5425) $PN F19
J 2
(-5460 5435);
DISPLAY 0.680851 (-5460 5435);
PAINT MONO (-5460 5435);
FORCEPROP 0 LASTPIN (-5450 5375) $PN G21
J 2
(-5460 5385);
DISPLAY 0.680851 (-5460 5385);
PAINT MONO (-5460 5385);
FORCEPROP 0 LASTPIN (-5450 5325) $PN G20
J 2
(-5460 5335);
DISPLAY 0.680851 (-5460 5335);
PAINT MONO (-5460 5335);
FORCEPROP 0 LASTPIN (-5450 5275) $PN G19
J 2
(-5460 5285);
DISPLAY 0.680851 (-5460 5285);
PAINT MONO (-5460 5285);
FORCEPROP 0 LASTPIN (-5450 5225) $PN G18
J 2
(-5460 5235);
DISPLAY 0.680851 (-5460 5235);
PAINT MONO (-5460 5235);
FORCEPROP 0 LASTPIN (-5450 5175) $PN H22
J 2
(-5460 5185);
DISPLAY 0.680851 (-5460 5185);
PAINT MONO (-5460 5185);
FORCEPROP 0 LASTPIN (-5450 5125) $PN H21
J 2
(-5460 5135);
DISPLAY 0.680851 (-5460 5135);
PAINT MONO (-5460 5135);
FORCEPROP 0 LASTPIN (-5450 5075) $PN G17
J 2
(-5460 5085);
DISPLAY 0.680851 (-5460 5085);
PAINT MONO (-5460 5085);
FORCEPROP 0 LASTPIN (-5450 5025) $PN H20
J 2
(-5460 5035);
DISPLAY 0.680851 (-5460 5035);
PAINT MONO (-5460 5035);
FORCEPROP 0 LASTPIN (-5450 4975) $PN H19
J 2
(-5460 4985);
DISPLAY 0.680851 (-5460 4985);
PAINT MONO (-5460 4985);
FORCEPROP 0 LASTPIN (-5450 4925) $PN H18
J 2
(-5460 4935);
DISPLAY 0.680851 (-5460 4935);
PAINT MONO (-5460 4935);
FORCEPROP 0 LASTPIN (-5450 4875) $PN H17
J 2
(-5460 4885);
DISPLAY 0.680851 (-5460 4885);
PAINT MONO (-5460 4885);
FORCEPROP 0 LASTPIN (-5450 4825) $PN H16
J 2
(-5460 4835);
DISPLAY 0.680851 (-5460 4835);
PAINT MONO (-5460 4835);
FORCEPROP 0 LASTPIN (-5450 4775) $PN J16
J 2
(-5460 4785);
DISPLAY 0.680851 (-5460 4785);
PAINT MONO (-5460 4785);
FORCEPROP 0 LASTPIN (-5450 4725) $PN J17
J 2
(-5460 4735);
DISPLAY 0.680851 (-5460 4735);
PAINT MONO (-5460 4735);
FORCEPROP 0 LASTPIN (-5450 4675) $PN J18
J 2
(-5460 4685);
DISPLAY 0.680851 (-5460 4685);
PAINT MONO (-5460 4685);
FORCEPROP 0 LASTPIN (-5450 4625) $PN J19
J 2
(-5460 4635);
DISPLAY 0.680851 (-5460 4635);
PAINT MONO (-5460 4635);
FORCEPROP 0 LASTPIN (-5450 4575) $PN J21
J 2
(-5460 4585);
DISPLAY 0.680851 (-5460 4585);
PAINT MONO (-5460 4585);
FORCEPROP 0 LASTPIN (-5450 4525) $PN J22
J 2
(-5460 4535);
DISPLAY 0.680851 (-5460 4535);
PAINT MONO (-5460 4535);
FORCEPROP 0 LASTPIN (-5450 4475) $PN J20
J 2
(-5460 4485);
DISPLAY 0.680851 (-5460 4485);
PAINT MONO (-5460 4485);
FORCEPROP 0 LASTPIN (-5450 4425) $PN K20
J 2
(-5460 4435);
DISPLAY 0.680851 (-5460 4435);
PAINT MONO (-5460 4435);
FORCEPROP 0 LASTPIN (-5450 4375) $PN K19
J 2
(-5460 4385);
DISPLAY 0.680851 (-5460 4385);
PAINT MONO (-5460 4385);
FORCEPROP 0 LASTPIN (-5450 4325) $PN K18
J 2
(-5460 4335);
DISPLAY 0.680851 (-5460 4335);
PAINT MONO (-5460 4335);
FORCEPROP 0 LASTPIN (-5450 4275) $PN K17
J 2
(-5460 4285);
DISPLAY 0.680851 (-5460 4285);
PAINT MONO (-5460 4285);
FORCEPROP 0 LASTPIN (-5450 4225) $PN K16
J 2
(-5460 4235);
DISPLAY 0.680851 (-5460 4235);
PAINT MONO (-5460 4235);
FORCEPROP 0 LASTPIN (-5450 4175) $PN L17
J 2
(-5460 4185);
DISPLAY 0.680851 (-5460 4185);
PAINT MONO (-5460 4185);
FORCEPROP 0 LASTPIN (-5450 4125) $PN L16
J 2
(-5460 4135);
DISPLAY 0.680851 (-5460 4135);
PAINT MONO (-5460 4135);
FORCEPROP 0 LASTPIN (-5450 4075) $PN L19
J 2
(-5460 4085);
DISPLAY 0.680851 (-5460 4085);
PAINT MONO (-5460 4085);
FORCEPROP 0 LASTPIN (-5450 4025) $PN L20
J 2
(-5460 4035);
DISPLAY 0.680851 (-5460 4035);
PAINT MONO (-5460 4035);
FORCEPROP 0 LASTPIN (-5450 3975) $PN K22
J 2
(-5460 3985);
DISPLAY 0.680851 (-5460 3985);
PAINT MONO (-5460 3985);
FORCEPROP 0 LASTPIN (-5450 3925) $PN L21
J 2
(-5460 3935);
DISPLAY 0.680851 (-5460 3935);
PAINT MONO (-5460 3935);
FORCEPROP 0 LASTPIN (-5450 3875) $PN L22
J 2
(-5460 3885);
DISPLAY 0.680851 (-5460 3885);
PAINT MONO (-5460 3885);
FORCEPROP 0 LASTPIN (-5450 3825) $PN M17
J 2
(-5460 3835);
DISPLAY 0.680851 (-5460 3835);
PAINT MONO (-5460 3835);
FORCEPROP 0 LASTPIN (-4200 6175) $PN M22
J 0
(-4190 6185);
DISPLAY 0.680851 (-4190 6185);
PAINT MONO (-4190 6185);
FORCEPROP 0 LASTPIN (-4200 6125) $PN M21
J 0
(-4190 6135);
DISPLAY 0.680851 (-4190 6135);
PAINT MONO (-4190 6135);
FORCEPROP 0 LASTPIN (-4200 6075) $PN M20
J 0
(-4190 6085);
DISPLAY 0.680851 (-4190 6085);
PAINT MONO (-4190 6085);
FORCEPROP 0 LASTPIN (-4200 6025) $PN M19
J 0
(-4190 6035);
DISPLAY 0.680851 (-4190 6035);
PAINT MONO (-4190 6035);
FORCEPROP 0 LASTPIN (-4200 5975) $PN M16
J 0
(-4190 5985);
DISPLAY 0.680851 (-4190 5985);
PAINT MONO (-4190 5985);
FORCEPROP 0 LASTPIN (-4200 5925) $PN N16
J 0
(-4190 5935);
DISPLAY 0.680851 (-4190 5935);
PAINT MONO (-4190 5935);
FORCEPROP 0 LASTPIN (-4200 5875) $PN N17
J 0
(-4190 5885);
DISPLAY 0.680851 (-4190 5885);
PAINT MONO (-4190 5885);
FORCEPROP 0 LASTPIN (-4200 5825) $PN N18
J 0
(-4190 5835);
DISPLAY 0.680851 (-4190 5835);
PAINT MONO (-4190 5835);
FORCEPROP 0 LASTPIN (-4200 5775) $PN N22
J 0
(-4190 5785);
DISPLAY 0.680851 (-4190 5785);
PAINT MONO (-4190 5785);
FORCEPROP 0 LASTPIN (-4200 5725) $PN P21
J 0
(-4190 5735);
DISPLAY 0.680851 (-4190 5735);
PAINT MONO (-4190 5735);
FORCEPROP 0 LASTPIN (-4200 5675) $PN N20
J 0
(-4190 5685);
DISPLAY 0.680851 (-4190 5685);
PAINT MONO (-4190 5685);
FORCEPROP 0 LASTPIN (-4200 5625) $PN N19
J 0
(-4190 5635);
DISPLAY 0.680851 (-4190 5635);
PAINT MONO (-4190 5635);
FORCEPROP 0 LASTPIN (-4200 5575) $PN R22
J 0
(-4190 5585);
DISPLAY 0.680851 (-4190 5585);
PAINT MONO (-4190 5585);
FORCEPROP 0 LASTPIN (-4200 5525) $PN R21
J 0
(-4190 5535);
DISPLAY 0.680851 (-4190 5535);
PAINT MONO (-4190 5535);
FORCEPROP 0 LASTPIN (-4200 5475) $PN P22
J 0
(-4190 5485);
DISPLAY 0.680851 (-4190 5485);
PAINT MONO (-4190 5485);
FORCEPROP 0 LASTPIN (-4200 5425) $PN P20
J 0
(-4190 5435);
DISPLAY 0.680851 (-4190 5435);
PAINT MONO (-4190 5435);
FORCEPROP 0 LASTPIN (-4200 5375) $PN T22
J 0
(-4190 5385);
DISPLAY 0.680851 (-4190 5385);
PAINT MONO (-4190 5385);
FORCEPROP 0 LASTPIN (-4200 5325) $PN T21
J 0
(-4190 5335);
DISPLAY 0.680851 (-4190 5335);
PAINT MONO (-4190 5335);
FORCEPROP 0 LASTPIN (-4200 5275) $PN P19
J 0
(-4190 5285);
DISPLAY 0.680851 (-4190 5285);
PAINT MONO (-4190 5285);
FORCEPROP 0 LASTPIN (-4200 5225) $PN P18
J 0
(-4190 5235);
DISPLAY 0.680851 (-4190 5235);
PAINT MONO (-4190 5235);
FORCEPROP 0 LASTPIN (-4200 5175) $PN P17
J 0
(-4190 5185);
DISPLAY 0.680851 (-4190 5185);
PAINT MONO (-4190 5185);
FORCEPROP 0 LASTPIN (-4200 5125) $PN P16
J 0
(-4190 5135);
DISPLAY 0.680851 (-4190 5135);
PAINT MONO (-4190 5135);
FORCEPROP 0 LASTPIN (-4200 5075) $PN U22
J 0
(-4190 5085);
DISPLAY 0.680851 (-4190 5085);
PAINT MONO (-4190 5085);
FORCEPROP 0 LASTPIN (-4200 5025) $PN U21
J 0
(-4190 5035);
DISPLAY 0.680851 (-4190 5035);
PAINT MONO (-4190 5035);
FORCEPROP 0 LASTPIN (-4200 4975) $PN V22
J 0
(-4190 4985);
DISPLAY 0.680851 (-4190 4985);
PAINT MONO (-4190 4985);
FORCEPROP 0 LASTPIN (-4200 4925) $PN W22
J 0
(-4190 4935);
DISPLAY 0.680851 (-4190 4935);
PAINT MONO (-4190 4935);
FORCEPROP 0 LASTPIN (-4200 4875) $PN R20
J 0
(-4190 4885);
DISPLAY 0.680851 (-4190 4885);
PAINT MONO (-4190 4885);
FORCEPROP 0 LASTPIN (-4200 4825) $PN R19
J 0
(-4190 4835);
DISPLAY 0.680851 (-4190 4835);
PAINT MONO (-4190 4835);
FORCEPROP 0 LASTPIN (-4200 4725) $PN R18
J 0
(-4190 4735);
DISPLAY 0.680851 (-4190 4735);
PAINT MONO (-4190 4735);
FORCEPROP 0 LASTPIN (-4200 4675) $PN R17
J 0
(-4190 4685);
DISPLAY 0.680851 (-4190 4685);
PAINT MONO (-4190 4685);
FORCEPROP 0 LASTPIN (-4200 4625) $PN R16
J 0
(-4190 4635);
DISPLAY 0.680851 (-4190 4635);
PAINT MONO (-4190 4635);
FORCEPROP 0 LASTPIN (-4200 4575) $PN T20
J 0
(-4190 4585);
DISPLAY 0.680851 (-4190 4585);
PAINT MONO (-4190 4585);
FORCEPROP 0 LASTPIN (-4200 4525) $PN T19
J 0
(-4190 4535);
DISPLAY 0.680851 (-4190 4535);
PAINT MONO (-4190 4535);
FORCEPROP 0 LASTPIN (-4200 4475) $PN T18
J 0
(-4190 4485);
DISPLAY 0.680851 (-4190 4485);
PAINT MONO (-4190 4485);
FORCEPROP 0 LASTPIN (-4200 4425) $PN T17
J 0
(-4190 4435);
DISPLAY 0.680851 (-4190 4435);
PAINT MONO (-4190 4435);
FORCEPROP 0 LASTPIN (-4200 4375) $PN U20
J 0
(-4190 4385);
DISPLAY 0.680851 (-4190 4385);
PAINT MONO (-4190 4385);
FORCEPROP 0 LASTPIN (-4200 4325) $PN Y22
J 0
(-4190 4335);
DISPLAY 0.680851 (-4190 4335);
PAINT MONO (-4190 4335);
FORCEPROP 0 LASTPIN (-4200 4275) $PN W21
J 0
(-4190 4285);
DISPLAY 0.680851 (-4190 4285);
PAINT MONO (-4190 4285);
FORCEPROP 0 LASTPIN (-4200 4225) $PN U19
J 0
(-4190 4235);
DISPLAY 0.680851 (-4190 4235);
PAINT MONO (-4190 4235);
FORCEPROP 0 LASTPIN (-4200 4175) $PN U18
J 0
(-4190 4185);
DISPLAY 0.680851 (-4190 4185);
PAINT MONO (-4190 4185);
FORCEPROP 0 LASTPIN (-4200 4125) $PN AA22
J 0
(-4190 4135);
DISPLAY 0.680851 (-4190 4135);
PAINT MONO (-4190 4135);
FORCEPROP 0 LASTPIN (-4200 4075) $PN Y21
J 0
(-4190 4085);
DISPLAY 0.680851 (-4190 4085);
PAINT MONO (-4190 4085);
FORCEPROP 0 LASTPIN (-4200 4025) $PN U17
J 0
(-4190 4035);
DISPLAY 0.680851 (-4190 4035);
PAINT MONO (-4190 4035);
FORCEPROP 0 LASTPIN (-4200 3975) $PN V19
J 0
(-4190 3985);
DISPLAY 0.680851 (-4190 3985);
PAINT MONO (-4190 3985);
FORCEPROP 0 LASTPIN (-4200 3925) $PN V18
J 0
(-4190 3935);
DISPLAY 0.680851 (-4190 3935);
PAINT MONO (-4190 3935);
FORCEPROP 0 LASTPIN (-4200 3875) $PN W20
J 0
(-4190 3885);
DISPLAY 0.680851 (-4190 3885);
PAINT MONO (-4190 3885);
FORCEPROP 0 LASTPIN (-4200 3825) $PN W19
J 0
(-4190 3835);
DISPLAY 0.680851 (-4190 3835);
PAINT MONO (-4190 3835);
FORCEPROP 0 LASTPIN (-4200 3775) $PN Y20
J 0
(-4190 3785);
DISPLAY 0.680851 (-4190 3785);
PAINT MONO (-4190 3785);
FORCEPROP 2 LAST PART_TYPE SMLF
J 0
(-5300 6575);
DISPLAY 0.680851 (-5300 6575);
FORCEPROP 1 LAST MATERIAL IC
J 0
(-5303 6293);
DISPLAY 0.723404 (-5303 6293);
PAINT GREEN (-5303 6293);
FORCEPROP 2 LAST VALUE LCMXO3LF-9400C-5BG484C
J 0
(-5300 6530);
DISPLAY 0.489362 (-5300 6530);
PAINT SKYBLUE (-5300 6530);
FORCEPROP 2 LAST CDS_LIB pure_quanta
J 0
(-4825 5000);
DISPLAY INVISIBLE (-4825 5000);
FORCEPROP 1 LAST NEEDS_NO_SIZE TRUE
J 0
(-4825 5000);
DISPLAY 0.723404 (-4825 5000);
PAINT GREEN (-4825 5000);
DISPLAY INVISIBLE (-4825 5000);
FORCEPROP 1 LAST CDS_LMAN_SYM_OUTLINE -475,1275,475,-1275
J 0
(-4825 5000);
DISPLAY 0.468085 (-4825 5000);
PAINT GREEN (-4825 5000);
DISPLAY INVISIBLE (-4825 5000);
FORCEPROP 1 LAST PATH I217
J 0
(-4825 5000);
DISPLAY 0.723404 (-4825 5000);
PAINT GREEN (-4825 5000);
DISPLAY INVISIBLE (-4825 5000);
FORCEPROP 1 LAST PART_NUMBER AJ094000T08
J 0
(-5300 6420);
DISPLAY 0.723404 (-5300 6420);
PAINT GREEN (-5300 6420);
DISPLAY INVISIBLE (-5300 6420);
FORCEADD OFFPAGE..2
(-1450 825);
FORCEPROP 2 LAST $XR0 188 
J 0
(-1261 825);
DISPLAY 0.638298 (-1261 825);
PAINT MONO (-1261 825);
FORCEPROP 2 LAST CDS_LIB standard
J 0
(-1450 825);
DISPLAY INVISIBLE (-1450 825);
FORCEPROP 1 LAST OFFPAGE TRUE
J 0
(-1125 700);
DISPLAY 0.872340 (-1125 700);
PAINT GREEN (-1125 700);
DISPLAY INVISIBLE (-1125 700);
FORCEPROP 1 LAST COMMENT_BODY TRUE
J 0
(-1495 730);
DISPLAY 0.872340 (-1495 730);
PAINT GREEN (-1495 730);
DISPLAY INVISIBLE (-1495 730);
FORCEPROP 2 LAST PATH I218
J 0
(-1275 900);
DISPLAY 0.680851 (-1275 900);
DISPLAY INVISIBLE (-1275 900);
FORCEADD OFFPAGE..1
R 2
(-2300 5625);
FORCEPROP 2 LAST $XR0 260 
J 0
(-2114 5625);
DISPLAY 0.638298 (-2114 5625);
PAINT MONO (-2114 5625);
FORCEPROP 2 LAST CDS_LIB standard
J 0
(-2300 5625);
DISPLAY INVISIBLE (-2300 5625);
FORCEPROP 1 LAST OFFPAGE TRUE
J 2
(-2625 5500);
DISPLAY 0.872340 (-2625 5500);
PAINT GREEN (-2625 5500);
DISPLAY INVISIBLE (-2625 5500);
FORCEPROP 1 LAST COMMENT_BODY TRUE
J 2
(-2425 5525);
DISPLAY 0.872340 (-2425 5525);
PAINT GREEN (-2425 5525);
DISPLAY INVISIBLE (-2425 5525);
FORCEPROP 2 LAST PATH I219
J 0
(-2100 5675);
DISPLAY 0.680851 (-2100 5675);
DISPLAY INVISIBLE (-2100 5675);
FORCEADD Q_RES..1
(-6725 925);
FORCEPROP 1 LAST LOCATION R199
J 0
(-6625 925);
DISPLAY 0.489362 (-6625 925);
PAINT SKYBLUE (-6625 925);
FORCEPROP 0 LAST $SEC 1
J 0
(-6625 975);
DISPLAY 0.680851 (-6625 975);
PAINT MONO (-6625 975);
DISPLAY INVISIBLE (-6625 975);
FORCEPROP 0 LAST CDS_SEC 1
J 0
(-6625 975);
DISPLAY 0.680851 (-6625 975);
DISPLAY INVISIBLE (-6625 975);
FORCEPROP 1 LASTPIN (-6825 925) $PN 1
J 0
(-6813 937);
DISPLAY 0.489362 (-6813 937);
PAINT MONO (-6813 937);
FORCEPROP 1 LASTPIN (-6625 925) $PN 2
J 0
(-6663 937);
DISPLAY 0.489362 (-6663 937);
PAINT MONO (-6663 937);
FORCEPROP 1 LAST VALUE 33
J 2
(-6850 925);
DISPLAY 0.489362 (-6850 925);
PAINT SKYBLUE (-6850 925);
FORCEPROP 2 LAST BOM_COST MEM
J 2
(-6700 1075);
DISPLAY 0.744681 (-6700 1075);
PAINT WHITE (-6700 1075);
DISPLAY INVISIBLE (-6700 1075);
FORCEPROP 2 LAST CDS_LIB pure_quanta
J 0
(-6725 925);
DISPLAY INVISIBLE (-6725 925);
FORCEPROP 1 LAST WATTAGE 1/16W
J 2
(-6800 850);
DISPLAY 0.489362 (-6800 850);
PAINT SKYBLUE (-6800 850);
DISPLAY INVISIBLE (-6800 850);
FORCEPROP 1 LAST MATERIAL CHIP
J 2
(-6550 900);
DISPLAY 0.489362 (-6550 900);
PAINT SKYBLUE (-6550 900);
DISPLAY INVISIBLE (-6550 900);
FORCEPROP 1 LAST TOLERANCE 5%
J 0
(-6850 900);
DISPLAY 0.489362 (-6850 900);
PAINT SKYBLUE (-6850 900);
DISPLAY INVISIBLE (-6850 900);
FORCEPROP 1 LAST PACK_TYPE 0402LF
J 2
(-6550 850);
DISPLAY 0.489362 (-6550 850);
PAINT SKYBLUE (-6550 850);
DISPLAY INVISIBLE (-6550 850);
FORCEPROP 1 LAST PATH I22
J 0
(-6775 1075);
DISPLAY 0.978723 (-6775 1075);
PAINT WHITE (-6775 1075);
DISPLAY INVISIBLE (-6775 1075);
FORCEPROP 1 LAST PART_NUMBER CS03302JB10
J 2
(-6625 975);
DISPLAY 0.489362 (-6625 975);
PAINT SKYBLUE (-6625 975);
DISPLAY INVISIBLE (-6625 975);
FORCEADD Q_RES..1
(-2300 2975);
FORCEPROP 1 LAST LOCATION R4170
J 0
(-2575 2975);
DISPLAY 0.787234 (-2575 2975);
FORCEPROP 2 LAST $SEC 1
J 0
(-2350 3175);
DISPLAY 0.680851 (-2350 3175);
PAINT MONO (-2350 3175);
DISPLAY INVISIBLE (-2350 3175);
FORCEPROP 2 LAST CDS_SEC 1
J 0
(-2350 3175);
DISPLAY 1.021277 (-2350 3175);
DISPLAY INVISIBLE (-2350 3175);
FORCEPROP 1 LASTPIN (-2400 2975) $PN 1
J 0
(-2388 2987);
DISPLAY 0.787234 (-2388 2987);
FORCEPROP 1 LASTPIN (-2200 2975) $PN 2
J 0
(-2238 2987);
DISPLAY 0.787234 (-2238 2987);
FORCEPROP 1 LAST TOLERANCE 1%
J 0
(-2025 2975);
DISPLAY 0.638298 (-2025 2975);
FORCEPROP 1 LAST MATERIAL CHIP
J 0
(-1950 2975);
DISPLAY 0.638298 (-1950 2975);
FORCEPROP 1 LAST VALUE 33.2
J 2
(-2050 2975);
DISPLAY 0.638298 (-2050 2975);
FORCEPROP 1 LAST WATTAGE 1/16W
J 2
(-2100 3100);
DISPLAY 0.638298 (-2100 3100);
DISPLAY INVISIBLE (-2100 3100);
FORCEPROP 1 LAST PACK_TYPE 0402LF
J 0
(-2450 3100);
DISPLAY 0.638298 (-2450 3100);
DISPLAY INVISIBLE (-2450 3100);
FORCEPROP 2 LAST CDS_LIB pure_quanta
J 0
(-2300 2975);
PAINT MONO (-2300 2975);
DISPLAY INVISIBLE (-2300 2975);
FORCEPROP 1 LAST PATH I220
J 0
(-2350 3125);
DISPLAY 0.978723 (-2350 3125);
PAINT WHITE (-2350 3125);
DISPLAY INVISIBLE (-2350 3125);
FORCEPROP 1 LAST PART_NUMBER CS03322FB03
J 0
(-2450 3050);
DISPLAY 0.638298 (-2450 3050);
DISPLAY INVISIBLE (-2450 3050);
FORCEADD OFFPAGE..1
R 2
(-800 2975);
FORCEPROP 2 LAST $XR0 124 
J 0
(-614 2975);
DISPLAY 0.638298 (-614 2975);
PAINT MONO (-614 2975);
FORCEPROP 2 LAST CDS_LIB standard
J 0
(-800 2975);
DISPLAY INVISIBLE (-800 2975);
FORCEPROP 1 LAST OFFPAGE TRUE
J 2
(-1125 2850);
DISPLAY 0.872340 (-1125 2850);
PAINT GREEN (-1125 2850);
DISPLAY INVISIBLE (-1125 2850);
FORCEPROP 1 LAST COMMENT_BODY TRUE
J 2
(-925 2875);
DISPLAY 0.872340 (-925 2875);
PAINT GREEN (-925 2875);
DISPLAY INVISIBLE (-925 2875);
FORCEPROP 2 LAST PATH I221
J 0
(-600 3025);
DISPLAY 0.680851 (-600 3025);
DISPLAY INVISIBLE (-600 3025);
FORCEADD OFFPAGE..1
R 2
(-800 2925);
FORCEPROP 2 LAST $XR0 124 
J 0
(-614 2925);
DISPLAY 0.638298 (-614 2925);
PAINT MONO (-614 2925);
FORCEPROP 2 LAST CDS_LIB standard
J 0
(-800 2925);
DISPLAY INVISIBLE (-800 2925);
FORCEPROP 1 LAST OFFPAGE TRUE
J 2
(-1125 2800);
DISPLAY 0.872340 (-1125 2800);
PAINT GREEN (-1125 2800);
DISPLAY INVISIBLE (-1125 2800);
FORCEPROP 1 LAST COMMENT_BODY TRUE
J 2
(-925 2825);
DISPLAY 0.872340 (-925 2825);
PAINT GREEN (-925 2825);
DISPLAY INVISIBLE (-925 2825);
FORCEPROP 2 LAST PATH I222
J 0
(-600 2975);
DISPLAY 0.680851 (-600 2975);
DISPLAY INVISIBLE (-600 2975);
FORCEADD Q_RES..1
(-2300 2925);
FORCEPROP 1 LAST LOCATION R4171
J 0
(-2575 2925);
DISPLAY 0.787234 (-2575 2925);
FORCEPROP 2 LAST $SEC 1
J 0
(-2350 3125);
DISPLAY 0.680851 (-2350 3125);
PAINT MONO (-2350 3125);
DISPLAY INVISIBLE (-2350 3125);
FORCEPROP 2 LAST CDS_SEC 1
J 0
(-2350 3125);
DISPLAY 1.021277 (-2350 3125);
DISPLAY INVISIBLE (-2350 3125);
FORCEPROP 1 LASTPIN (-2400 2925) $PN 1
J 0
(-2388 2937);
DISPLAY 0.787234 (-2388 2937);
FORCEPROP 1 LASTPIN (-2200 2925) $PN 2
J 0
(-2238 2937);
DISPLAY 0.787234 (-2238 2937);
FORCEPROP 1 LAST MATERIAL CHIP
J 0
(-1950 2925);
DISPLAY 0.638298 (-1950 2925);
FORCEPROP 1 LAST TOLERANCE 1%
J 0
(-2025 2925);
DISPLAY 0.638298 (-2025 2925);
FORCEPROP 1 LAST VALUE 33.2
J 2
(-2050 2925);
DISPLAY 0.638298 (-2050 2925);
FORCEPROP 2 LAST CDS_LIB pure_quanta
J 0
(-2300 2925);
PAINT MONO (-2300 2925);
DISPLAY INVISIBLE (-2300 2925);
FORCEPROP 1 LAST PACK_TYPE 0402LF
J 0
(-2450 3050);
DISPLAY 0.638298 (-2450 3050);
DISPLAY INVISIBLE (-2450 3050);
FORCEPROP 1 LAST WATTAGE 1/16W
J 2
(-2100 3050);
DISPLAY 0.638298 (-2100 3050);
DISPLAY INVISIBLE (-2100 3050);
FORCEPROP 1 LAST PATH I223
J 0
(-2350 3075);
DISPLAY 0.978723 (-2350 3075);
PAINT WHITE (-2350 3075);
DISPLAY INVISIBLE (-2350 3075);
FORCEPROP 1 LAST PART_NUMBER CS03322FB03
J 0
(-2450 3000);
DISPLAY 0.638298 (-2450 3000);
DISPLAY INVISIBLE (-2450 3000);
FORCEADD Q_RES..1
(-2300 2875);
FORCEPROP 1 LAST LOCATION R4172
J 0
(-2575 2875);
DISPLAY 0.787234 (-2575 2875);
FORCEPROP 2 LAST $SEC 1
J 0
(-2350 3075);
DISPLAY 0.680851 (-2350 3075);
PAINT MONO (-2350 3075);
DISPLAY INVISIBLE (-2350 3075);
FORCEPROP 2 LAST CDS_SEC 1
J 0
(-2350 3075);
DISPLAY 1.021277 (-2350 3075);
DISPLAY INVISIBLE (-2350 3075);
FORCEPROP 1 LASTPIN (-2400 2875) $PN 1
J 0
(-2388 2887);
DISPLAY 0.787234 (-2388 2887);
FORCEPROP 1 LASTPIN (-2200 2875) $PN 2
J 0
(-2238 2887);
DISPLAY 0.787234 (-2238 2887);
FORCEPROP 1 LAST MATERIAL CHIP
J 0
(-1950 2875);
DISPLAY 0.638298 (-1950 2875);
FORCEPROP 1 LAST VALUE 33.2
J 2
(-2050 2875);
DISPLAY 0.638298 (-2050 2875);
FORCEPROP 1 LAST TOLERANCE 1%
J 0
(-2025 2875);
DISPLAY 0.638298 (-2025 2875);
FORCEPROP 2 LAST CDS_LIB pure_quanta
J 0
(-2300 2875);
PAINT MONO (-2300 2875);
DISPLAY INVISIBLE (-2300 2875);
FORCEPROP 1 LAST PACK_TYPE 0402LF
J 0
(-2450 3000);
DISPLAY 0.638298 (-2450 3000);
DISPLAY INVISIBLE (-2450 3000);
FORCEPROP 1 LAST WATTAGE 1/16W
J 2
(-2100 3000);
DISPLAY 0.638298 (-2100 3000);
DISPLAY INVISIBLE (-2100 3000);
FORCEPROP 1 LAST PATH I224
J 0
(-2350 3025);
DISPLAY 0.978723 (-2350 3025);
PAINT WHITE (-2350 3025);
DISPLAY INVISIBLE (-2350 3025);
FORCEPROP 1 LAST PART_NUMBER CS03322FB03
J 0
(-2450 2950);
DISPLAY 0.638298 (-2450 2950);
DISPLAY INVISIBLE (-2450 2950);
FORCEADD OFFPAGE..1
R 2
(-800 2875);
FORCEPROP 2 LAST $XR0 124 
J 0
(-614 2875);
DISPLAY 0.638298 (-614 2875);
PAINT MONO (-614 2875);
FORCEPROP 2 LAST CDS_LIB standard
J 0
(-800 2875);
DISPLAY INVISIBLE (-800 2875);
FORCEPROP 1 LAST OFFPAGE TRUE
J 2
(-1125 2750);
DISPLAY 0.872340 (-1125 2750);
PAINT GREEN (-1125 2750);
DISPLAY INVISIBLE (-1125 2750);
FORCEPROP 1 LAST COMMENT_BODY TRUE
J 2
(-925 2775);
DISPLAY 0.872340 (-925 2775);
PAINT GREEN (-925 2775);
DISPLAY INVISIBLE (-925 2775);
FORCEPROP 2 LAST PATH I225
J 0
(-600 2925);
DISPLAY 0.680851 (-600 2925);
DISPLAY INVISIBLE (-600 2925);
FORCEADD Q_RES..1
(-2300 2825);
FORCEPROP 1 LAST LOCATION R4556
J 0
(-2575 2825);
DISPLAY 0.787234 (-2575 2825);
FORCEPROP 2 LAST $SEC 1
J 0
(-2350 3025);
DISPLAY 0.680851 (-2350 3025);
PAINT MONO (-2350 3025);
DISPLAY INVISIBLE (-2350 3025);
FORCEPROP 2 LAST CDS_SEC 1
J 0
(-2350 3025);
DISPLAY 1.021277 (-2350 3025);
DISPLAY INVISIBLE (-2350 3025);
FORCEPROP 1 LASTPIN (-2400 2825) $PN 1
J 0
(-2388 2837);
DISPLAY 0.787234 (-2388 2837);
FORCEPROP 1 LASTPIN (-2200 2825) $PN 2
J 0
(-2238 2837);
DISPLAY 0.787234 (-2238 2837);
FORCEPROP 1 LAST MATERIAL CHIP
J 0
(-1950 2825);
DISPLAY 0.638298 (-1950 2825);
FORCEPROP 1 LAST VALUE 33.2
J 2
(-2050 2825);
DISPLAY 0.638298 (-2050 2825);
FORCEPROP 1 LAST TOLERANCE 1%
J 0
(-2025 2825);
DISPLAY 0.638298 (-2025 2825);
FORCEPROP 2 LAST CDS_LIB pure_quanta
J 0
(-2300 2825);
PAINT MONO (-2300 2825);
DISPLAY INVISIBLE (-2300 2825);
FORCEPROP 1 LAST PACK_TYPE 0402LF
J 0
(-2450 2950);
DISPLAY 0.638298 (-2450 2950);
DISPLAY INVISIBLE (-2450 2950);
FORCEPROP 1 LAST WATTAGE 1/16W
J 2
(-2100 2950);
DISPLAY 0.638298 (-2100 2950);
DISPLAY INVISIBLE (-2100 2950);
FORCEPROP 1 LAST PATH I226
J 0
(-2350 2975);
DISPLAY 0.978723 (-2350 2975);
PAINT WHITE (-2350 2975);
DISPLAY INVISIBLE (-2350 2975);
FORCEPROP 1 LAST PART_NUMBER CS03322FB03
J 0
(-2450 2900);
DISPLAY 0.638298 (-2450 2900);
DISPLAY INVISIBLE (-2450 2900);
FORCEADD OFFPAGE..2
(-800 2825);
FORCEPROP 2 LAST $XR0 124 
J 0
(-611 2825);
DISPLAY 0.638298 (-611 2825);
PAINT MONO (-611 2825);
FORCEPROP 2 LAST CDS_LIB standard
J 0
(-800 2825);
DISPLAY INVISIBLE (-800 2825);
FORCEPROP 1 LAST OFFPAGE TRUE
J 0
(-475 2700);
DISPLAY 0.872340 (-475 2700);
PAINT GREEN (-475 2700);
DISPLAY INVISIBLE (-475 2700);
FORCEPROP 1 LAST COMMENT_BODY TRUE
J 0
(-845 2730);
DISPLAY 0.872340 (-845 2730);
PAINT GREEN (-845 2730);
DISPLAY INVISIBLE (-845 2730);
FORCEPROP 2 LAST PATH I227
J 0
(-600 2875);
DISPLAY 0.680851 (-600 2875);
DISPLAY INVISIBLE (-600 2875);
FORCEADD Q_RES..1
(-2300 2675);
FORCEPROP 1 LAST LOCATION R4558
J 0
(-2575 2675);
DISPLAY 0.787234 (-2575 2675);
FORCEPROP 2 LAST $SEC 1
J 0
(-2350 2875);
DISPLAY 0.680851 (-2350 2875);
PAINT MONO (-2350 2875);
DISPLAY INVISIBLE (-2350 2875);
FORCEPROP 2 LAST CDS_SEC 1
J 0
(-2350 2875);
DISPLAY 1.021277 (-2350 2875);
DISPLAY INVISIBLE (-2350 2875);
FORCEPROP 1 LASTPIN (-2400 2675) $PN 1
J 0
(-2388 2687);
DISPLAY 0.787234 (-2388 2687);
FORCEPROP 1 LASTPIN (-2200 2675) $PN 2
J 0
(-2238 2687);
DISPLAY 0.787234 (-2238 2687);
FORCEPROP 1 LAST VALUE 33.2
J 2
(-2050 2675);
DISPLAY 0.638298 (-2050 2675);
FORCEPROP 1 LAST MATERIAL CHIP
J 0
(-1950 2675);
DISPLAY 0.638298 (-1950 2675);
FORCEPROP 1 LAST TOLERANCE 1%
J 0
(-2025 2675);
DISPLAY 0.638298 (-2025 2675);
FORCEPROP 2 LAST CDS_LIB pure_quanta
J 0
(-2300 2675);
PAINT MONO (-2300 2675);
DISPLAY INVISIBLE (-2300 2675);
FORCEPROP 1 LAST PACK_TYPE 0402LF
J 0
(-2450 2800);
DISPLAY 0.638298 (-2450 2800);
DISPLAY INVISIBLE (-2450 2800);
FORCEPROP 1 LAST WATTAGE 1/16W
J 2
(-2100 2800);
DISPLAY 0.638298 (-2100 2800);
DISPLAY INVISIBLE (-2100 2800);
FORCEPROP 1 LAST PATH I228
J 0
(-2350 2825);
DISPLAY 0.978723 (-2350 2825);
PAINT WHITE (-2350 2825);
DISPLAY INVISIBLE (-2350 2825);
FORCEPROP 1 LAST PART_NUMBER CS03322FB03
J 0
(-2450 2750);
DISPLAY 0.638298 (-2450 2750);
DISPLAY INVISIBLE (-2450 2750);
FORCEADD OFFPAGE..1
R 2
(-800 2625);
FORCEPROP 2 LAST $XR0 125 
J 0
(-614 2625);
DISPLAY 0.638298 (-614 2625);
PAINT MONO (-614 2625);
FORCEPROP 2 LAST CDS_LIB standard
J 0
(-800 2625);
DISPLAY INVISIBLE (-800 2625);
FORCEPROP 1 LAST OFFPAGE TRUE
J 2
(-1125 2500);
DISPLAY 0.872340 (-1125 2500);
PAINT GREEN (-1125 2500);
DISPLAY INVISIBLE (-1125 2500);
FORCEPROP 1 LAST COMMENT_BODY TRUE
J 2
(-925 2525);
DISPLAY 0.872340 (-925 2525);
PAINT GREEN (-925 2525);
DISPLAY INVISIBLE (-925 2525);
FORCEPROP 2 LAST PATH I229
J 0
(-625 2700);
DISPLAY 0.680851 (-625 2700);
DISPLAY INVISIBLE (-625 2700);
FORCEADD Q_RES..1
(-2300 2625);
FORCEPROP 1 LAST LOCATION R4143
J 0
(-2575 2625);
DISPLAY 0.787234 (-2575 2625);
FORCEPROP 2 LAST $SEC 1
J 0
(-2350 2825);
DISPLAY 0.680851 (-2350 2825);
PAINT MONO (-2350 2825);
DISPLAY INVISIBLE (-2350 2825);
FORCEPROP 2 LAST CDS_SEC 1
J 0
(-2350 2825);
DISPLAY 1.021277 (-2350 2825);
DISPLAY INVISIBLE (-2350 2825);
FORCEPROP 1 LASTPIN (-2400 2625) $PN 1
J 0
(-2388 2637);
DISPLAY 0.787234 (-2388 2637);
FORCEPROP 1 LASTPIN (-2200 2625) $PN 2
J 0
(-2238 2637);
DISPLAY 0.787234 (-2238 2637);
FORCEPROP 1 LAST TOLERANCE 1%
J 0
(-2025 2625);
DISPLAY 0.638298 (-2025 2625);
FORCEPROP 1 LAST VALUE 33.2
J 2
(-2050 2625);
DISPLAY 0.638298 (-2050 2625);
FORCEPROP 1 LAST MATERIAL CHIP
J 0
(-1950 2625);
DISPLAY 0.638298 (-1950 2625);
FORCEPROP 2 LAST CDS_LIB pure_quanta
J 0
(-2300 2625);
PAINT MONO (-2300 2625);
DISPLAY INVISIBLE (-2300 2625);
FORCEPROP 1 LAST PACK_TYPE 0402LF
J 0
(-2450 2750);
DISPLAY 0.638298 (-2450 2750);
DISPLAY INVISIBLE (-2450 2750);
FORCEPROP 1 LAST WATTAGE 1/16W
J 2
(-2100 2750);
DISPLAY 0.638298 (-2100 2750);
DISPLAY INVISIBLE (-2100 2750);
FORCEPROP 1 LAST PATH I231
J 0
(-2350 2775);
DISPLAY 0.978723 (-2350 2775);
PAINT WHITE (-2350 2775);
DISPLAY INVISIBLE (-2350 2775);
FORCEPROP 1 LAST PART_NUMBER CS03322FB03
J 0
(-2450 2700);
DISPLAY 0.638298 (-2450 2700);
DISPLAY INVISIBLE (-2450 2700);
FORCEADD OFFPAGE..2
(-800 2675);
FORCEPROP 2 LAST $XR0 124 
J 0
(-581 2675);
DISPLAY 0.638298 (-581 2675);
PAINT MONO (-581 2675);
FORCEPROP 2 LAST CDS_LIB standard
J 0
(-800 2675);
DISPLAY INVISIBLE (-800 2675);
FORCEPROP 1 LAST OFFPAGE TRUE
J 0
(-475 2550);
DISPLAY 0.872340 (-475 2550);
PAINT GREEN (-475 2550);
DISPLAY INVISIBLE (-475 2550);
FORCEPROP 1 LAST COMMENT_BODY TRUE
J 0
(-845 2580);
DISPLAY 0.872340 (-845 2580);
PAINT GREEN (-845 2580);
DISPLAY INVISIBLE (-845 2580);
FORCEPROP 2 LAST PATH I232
J 0
(-625 2750);
DISPLAY 0.680851 (-625 2750);
DISPLAY INVISIBLE (-625 2750);
FORCEADD Q_RES..1
(-2300 2575);
FORCEPROP 1 LAST LOCATION R4144
J 0
(-2575 2575);
DISPLAY 0.787234 (-2575 2575);
FORCEPROP 2 LAST $SEC 1
J 0
(-2350 2775);
DISPLAY 0.680851 (-2350 2775);
PAINT MONO (-2350 2775);
DISPLAY INVISIBLE (-2350 2775);
FORCEPROP 2 LAST CDS_SEC 1
J 0
(-2350 2775);
DISPLAY 1.021277 (-2350 2775);
DISPLAY INVISIBLE (-2350 2775);
FORCEPROP 1 LASTPIN (-2400 2575) $PN 1
J 0
(-2388 2587);
DISPLAY 0.787234 (-2388 2587);
FORCEPROP 1 LASTPIN (-2200 2575) $PN 2
J 0
(-2238 2587);
DISPLAY 0.787234 (-2238 2587);
FORCEPROP 1 LAST VALUE 33.2
J 2
(-2050 2575);
DISPLAY 0.638298 (-2050 2575);
FORCEPROP 1 LAST TOLERANCE 1%
J 0
(-2025 2575);
DISPLAY 0.638298 (-2025 2575);
FORCEPROP 1 LAST MATERIAL CHIP
J 0
(-1950 2575);
DISPLAY 0.638298 (-1950 2575);
FORCEPROP 1 LAST WATTAGE 1/16W
J 2
(-2100 2700);
DISPLAY 0.638298 (-2100 2700);
DISPLAY INVISIBLE (-2100 2700);
FORCEPROP 1 LAST PACK_TYPE 0402LF
J 0
(-2450 2700);
DISPLAY 0.638298 (-2450 2700);
DISPLAY INVISIBLE (-2450 2700);
FORCEPROP 2 LAST CDS_LIB pure_quanta
J 0
(-2300 2575);
PAINT MONO (-2300 2575);
DISPLAY INVISIBLE (-2300 2575);
FORCEPROP 1 LAST PATH I233
J 0
(-2350 2725);
DISPLAY 0.978723 (-2350 2725);
PAINT WHITE (-2350 2725);
DISPLAY INVISIBLE (-2350 2725);
FORCEPROP 1 LAST PART_NUMBER CS03322FB03
J 0
(-2450 2650);
DISPLAY 0.638298 (-2450 2650);
DISPLAY INVISIBLE (-2450 2650);
FORCEADD OFFPAGE..1
R 2
(-800 2575);
FORCEPROP 2 LAST $XR0 125 
J 0
(-614 2575);
DISPLAY 0.638298 (-614 2575);
PAINT MONO (-614 2575);
FORCEPROP 2 LAST CDS_LIB standard
J 0
(-800 2575);
DISPLAY INVISIBLE (-800 2575);
FORCEPROP 1 LAST OFFPAGE TRUE
J 2
(-1125 2450);
DISPLAY 0.872340 (-1125 2450);
PAINT GREEN (-1125 2450);
DISPLAY INVISIBLE (-1125 2450);
FORCEPROP 1 LAST COMMENT_BODY TRUE
J 2
(-925 2475);
DISPLAY 0.872340 (-925 2475);
PAINT GREEN (-925 2475);
DISPLAY INVISIBLE (-925 2475);
FORCEPROP 2 LAST PATH I234
J 0
(-625 2650);
DISPLAY 0.680851 (-625 2650);
DISPLAY INVISIBLE (-625 2650);
FORCEADD OFFPAGE..2
(-800 2525);
FORCEPROP 2 LAST $XR1 85 
J 0
(-521 2525);
DISPLAY 0.638298 (-521 2525);
PAINT MONO (-521 2525);
FORCEPROP 2 LAST $XR0 83 
J 0
(-611 2525);
DISPLAY 0.638298 (-611 2525);
PAINT MONO (-611 2525);
FORCEPROP 2 LAST CDS_LIB standard
J 2
(-800 2525);
DISPLAY INVISIBLE (-800 2525);
FORCEPROP 1 LAST OFFPAGE TRUE
J 0
(-475 2400);
DISPLAY 0.872340 (-475 2400);
DISPLAY INVISIBLE (-475 2400);
FORCEPROP 1 LAST COMMENT_BODY TRUE
J 0
(-845 2430);
DISPLAY 0.872340 (-845 2430);
PAINT GREEN (-845 2430);
DISPLAY INVISIBLE (-845 2430);
FORCEPROP 2 LAST PATH I235
J 2
(-975 2600);
DISPLAY 0.680851 (-975 2600);
DISPLAY INVISIBLE (-975 2600);
FORCEADD OFFPAGE..1
R 2
(-800 2425);
FORCEPROP 2 LAST $XR1 246 
J 0
(-494 2425);
DISPLAY 0.638298 (-494 2425);
PAINT MONO (-494 2425);
FORCEPROP 2 LAST $XR0 125 
J 0
(-614 2425);
DISPLAY 0.638298 (-614 2425);
PAINT MONO (-614 2425);
FORCEPROP 2 LAST CDS_LIB standard
J 0
(-800 2425);
DISPLAY INVISIBLE (-800 2425);
FORCEPROP 1 LAST OFFPAGE TRUE
J 2
(-1125 2300);
DISPLAY 0.872340 (-1125 2300);
PAINT GREEN (-1125 2300);
DISPLAY INVISIBLE (-1125 2300);
FORCEPROP 1 LAST COMMENT_BODY TRUE
J 2
(-925 2325);
DISPLAY 0.872340 (-925 2325);
PAINT GREEN (-925 2325);
DISPLAY INVISIBLE (-925 2325);
FORCEPROP 2 LAST PATH I239
J 0
(-625 2500);
DISPLAY 0.680851 (-625 2500);
DISPLAY INVISIBLE (-625 2500);
FORCEADD Q_RES..1
(-2300 2425);
FORCEPROP 1 LAST LOCATION R4147
J 0
(-2575 2425);
DISPLAY 0.787234 (-2575 2425);
FORCEPROP 2 LAST $SEC 1
J 0
(-2350 2625);
DISPLAY 0.680851 (-2350 2625);
PAINT MONO (-2350 2625);
DISPLAY INVISIBLE (-2350 2625);
FORCEPROP 2 LAST CDS_SEC 1
J 0
(-2350 2625);
DISPLAY 1.021277 (-2350 2625);
DISPLAY INVISIBLE (-2350 2625);
FORCEPROP 1 LASTPIN (-2400 2425) $PN 1
J 0
(-2388 2437);
DISPLAY 0.787234 (-2388 2437);
FORCEPROP 1 LASTPIN (-2200 2425) $PN 2
J 0
(-2238 2437);
DISPLAY 0.787234 (-2238 2437);
FORCEPROP 1 LAST TOLERANCE 1%
J 0
(-2025 2425);
DISPLAY 0.638298 (-2025 2425);
FORCEPROP 1 LAST VALUE 33.2
J 2
(-2050 2425);
DISPLAY 0.638298 (-2050 2425);
FORCEPROP 1 LAST MATERIAL CHIP
J 0
(-1950 2425);
DISPLAY 0.638298 (-1950 2425);
FORCEPROP 2 LAST CDS_LIB pure_quanta
J 0
(-2300 2425);
PAINT MONO (-2300 2425);
DISPLAY INVISIBLE (-2300 2425);
FORCEPROP 1 LAST PACK_TYPE 0402LF
J 0
(-2450 2550);
DISPLAY 0.638298 (-2450 2550);
DISPLAY INVISIBLE (-2450 2550);
FORCEPROP 1 LAST WATTAGE 1/16W
J 2
(-2100 2550);
DISPLAY 0.638298 (-2100 2550);
DISPLAY INVISIBLE (-2100 2550);
FORCEPROP 1 LAST PATH I240
J 0
(-2350 2575);
DISPLAY 0.978723 (-2350 2575);
PAINT WHITE (-2350 2575);
DISPLAY INVISIBLE (-2350 2575);
FORCEPROP 1 LAST PART_NUMBER CS03322FB03
J 0
(-2450 2500);
DISPLAY 0.638298 (-2450 2500);
DISPLAY INVISIBLE (-2450 2500);
FORCEADD OFFPAGE..1
R 2
(-800 2375);
FORCEPROP 2 LAST $XR0 125 
J 0
(-614 2375);
DISPLAY 0.638298 (-614 2375);
PAINT MONO (-614 2375);
FORCEPROP 2 LAST CDS_LIB standard
J 0
(-800 2375);
DISPLAY INVISIBLE (-800 2375);
FORCEPROP 1 LAST OFFPAGE TRUE
J 2
(-1125 2250);
DISPLAY 0.872340 (-1125 2250);
PAINT GREEN (-1125 2250);
DISPLAY INVISIBLE (-1125 2250);
FORCEPROP 1 LAST COMMENT_BODY TRUE
J 2
(-925 2275);
DISPLAY 0.872340 (-925 2275);
PAINT GREEN (-925 2275);
DISPLAY INVISIBLE (-925 2275);
FORCEPROP 2 LAST PATH I241
J 0
(-625 2450);
DISPLAY 0.680851 (-625 2450);
DISPLAY INVISIBLE (-625 2450);
FORCEADD Q_RES..1
(-2300 2375);
FORCEPROP 1 LAST LOCATION R4148
J 0
(-2575 2375);
DISPLAY 0.787234 (-2575 2375);
FORCEPROP 2 LAST $SEC 1
J 0
(-2350 2575);
DISPLAY 0.680851 (-2350 2575);
PAINT MONO (-2350 2575);
DISPLAY INVISIBLE (-2350 2575);
FORCEPROP 2 LAST CDS_SEC 1
J 0
(-2350 2575);
DISPLAY 1.021277 (-2350 2575);
DISPLAY INVISIBLE (-2350 2575);
FORCEPROP 1 LASTPIN (-2400 2375) $PN 1
J 0
(-2388 2387);
DISPLAY 0.787234 (-2388 2387);
FORCEPROP 1 LASTPIN (-2200 2375) $PN 2
J 0
(-2238 2387);
DISPLAY 0.787234 (-2238 2387);
FORCEPROP 1 LAST TOLERANCE 1%
J 0
(-2025 2375);
DISPLAY 0.638298 (-2025 2375);
FORCEPROP 1 LAST VALUE 33.2
J 2
(-2050 2375);
DISPLAY 0.638298 (-2050 2375);
FORCEPROP 1 LAST MATERIAL CHIP
J 0
(-1950 2375);
DISPLAY 0.638298 (-1950 2375);
FORCEPROP 2 LAST CDS_LIB pure_quanta
J 0
(-2300 2375);
PAINT MONO (-2300 2375);
DISPLAY INVISIBLE (-2300 2375);
FORCEPROP 1 LAST PACK_TYPE 0402LF
J 0
(-2450 2500);
DISPLAY 0.638298 (-2450 2500);
DISPLAY INVISIBLE (-2450 2500);
FORCEPROP 1 LAST WATTAGE 1/16W
J 2
(-2100 2500);
DISPLAY 0.638298 (-2100 2500);
DISPLAY INVISIBLE (-2100 2500);
FORCEPROP 1 LAST PATH I242
J 0
(-2350 2525);
DISPLAY 0.978723 (-2350 2525);
PAINT WHITE (-2350 2525);
DISPLAY INVISIBLE (-2350 2525);
FORCEPROP 1 LAST PART_NUMBER CS03322FB03
J 0
(-2450 2450);
DISPLAY 0.638298 (-2450 2450);
DISPLAY INVISIBLE (-2450 2450);
FORCEADD Q_RES..1
(-2300 2275);
FORCEPROP 1 LAST LOCATION R4563
J 0
(-2575 2275);
DISPLAY 0.787234 (-2575 2275);
FORCEPROP 2 LAST $SEC 1
J 0
(-2350 2475);
DISPLAY 0.680851 (-2350 2475);
PAINT MONO (-2350 2475);
DISPLAY INVISIBLE (-2350 2475);
FORCEPROP 2 LAST CDS_SEC 1
J 0
(-2350 2475);
DISPLAY 1.021277 (-2350 2475);
DISPLAY INVISIBLE (-2350 2475);
FORCEPROP 1 LASTPIN (-2400 2275) $PN 1
J 0
(-2388 2287);
DISPLAY 0.787234 (-2388 2287);
FORCEPROP 1 LASTPIN (-2200 2275) $PN 2
J 0
(-2238 2287);
DISPLAY 0.787234 (-2238 2287);
FORCEPROP 1 LAST TOLERANCE 1%
J 0
(-2025 2275);
DISPLAY 0.638298 (-2025 2275);
FORCEPROP 1 LAST MATERIAL CHIP
J 0
(-1950 2275);
DISPLAY 0.638298 (-1950 2275);
FORCEPROP 1 LAST VALUE 33.2
J 2
(-2050 2275);
DISPLAY 0.638298 (-2050 2275);
FORCEPROP 1 LAST WATTAGE 1/16W
J 2
(-2100 2400);
DISPLAY 0.638298 (-2100 2400);
DISPLAY INVISIBLE (-2100 2400);
FORCEPROP 1 LAST PACK_TYPE 0402LF
J 0
(-2450 2400);
DISPLAY 0.638298 (-2450 2400);
DISPLAY INVISIBLE (-2450 2400);
FORCEPROP 2 LAST CDS_LIB pure_quanta
J 0
(-2300 2275);
PAINT MONO (-2300 2275);
DISPLAY INVISIBLE (-2300 2275);
FORCEPROP 1 LAST PATH I243
J 0
(-2350 2425);
DISPLAY 0.978723 (-2350 2425);
PAINT WHITE (-2350 2425);
DISPLAY INVISIBLE (-2350 2425);
FORCEPROP 1 LAST PART_NUMBER CS03322FB03
J 0
(-2450 2350);
DISPLAY 0.638298 (-2450 2350);
DISPLAY INVISIBLE (-2450 2350);
FORCEADD OFFPAGE..1
R 2
(-800 2275);
FORCEPROP 2 LAST $XR0 125 
J 0
(-614 2275);
DISPLAY 0.638298 (-614 2275);
PAINT MONO (-614 2275);
FORCEPROP 2 LAST CDS_LIB standard
J 0
(-800 2275);
DISPLAY INVISIBLE (-800 2275);
FORCEPROP 1 LAST OFFPAGE TRUE
J 2
(-1125 2150);
DISPLAY 0.872340 (-1125 2150);
PAINT GREEN (-1125 2150);
DISPLAY INVISIBLE (-1125 2150);
FORCEPROP 1 LAST COMMENT_BODY TRUE
J 2
(-925 2175);
DISPLAY 0.872340 (-925 2175);
PAINT GREEN (-925 2175);
DISPLAY INVISIBLE (-925 2175);
FORCEPROP 2 LAST PATH I244
J 0
(-625 2350);
DISPLAY 0.680851 (-625 2350);
DISPLAY INVISIBLE (-625 2350);
FORCEADD OFFPAGE..1
R 2
(-800 2325);
FORCEPROP 2 LAST $XR1 246 
J 0
(-494 2325);
DISPLAY 0.638298 (-494 2325);
PAINT MONO (-494 2325);
FORCEPROP 2 LAST $XR0 125 
J 0
(-614 2325);
DISPLAY 0.638298 (-614 2325);
PAINT MONO (-614 2325);
FORCEPROP 2 LAST CDS_LIB standard
J 0
(-800 2325);
DISPLAY INVISIBLE (-800 2325);
FORCEPROP 1 LAST OFFPAGE TRUE
J 2
(-1125 2200);
DISPLAY 0.872340 (-1125 2200);
PAINT GREEN (-1125 2200);
DISPLAY INVISIBLE (-1125 2200);
FORCEPROP 1 LAST COMMENT_BODY TRUE
J 2
(-925 2225);
DISPLAY 0.872340 (-925 2225);
PAINT GREEN (-925 2225);
DISPLAY INVISIBLE (-925 2225);
FORCEPROP 2 LAST PATH I245
J 0
(-625 2400);
DISPLAY 0.680851 (-625 2400);
DISPLAY INVISIBLE (-625 2400);
FORCEADD Q_RES..1
(-2300 2325);
FORCEPROP 1 LAST LOCATION R4157
J 0
(-2575 2325);
DISPLAY 0.787234 (-2575 2325);
FORCEPROP 2 LAST $SEC 1
J 0
(-2350 2525);
DISPLAY 0.680851 (-2350 2525);
PAINT MONO (-2350 2525);
DISPLAY INVISIBLE (-2350 2525);
FORCEPROP 2 LAST CDS_SEC 1
J 0
(-2350 2525);
DISPLAY 1.021277 (-2350 2525);
DISPLAY INVISIBLE (-2350 2525);
FORCEPROP 1 LASTPIN (-2400 2325) $PN 1
J 0
(-2388 2337);
DISPLAY 0.787234 (-2388 2337);
FORCEPROP 1 LASTPIN (-2200 2325) $PN 2
J 0
(-2238 2337);
DISPLAY 0.787234 (-2238 2337);
FORCEPROP 1 LAST VALUE 33.2
J 2
(-2050 2325);
DISPLAY 0.638298 (-2050 2325);
FORCEPROP 1 LAST TOLERANCE 1%
J 0
(-2025 2325);
DISPLAY 0.638298 (-2025 2325);
FORCEPROP 1 LAST MATERIAL CHIP
J 0
(-1950 2325);
DISPLAY 0.638298 (-1950 2325);
FORCEPROP 1 LAST WATTAGE 1/16W
J 2
(-2100 2450);
DISPLAY 0.638298 (-2100 2450);
DISPLAY INVISIBLE (-2100 2450);
FORCEPROP 1 LAST PACK_TYPE 0402LF
J 0
(-2450 2450);
DISPLAY 0.638298 (-2450 2450);
DISPLAY INVISIBLE (-2450 2450);
FORCEPROP 2 LAST CDS_LIB pure_quanta
J 0
(-2300 2325);
PAINT MONO (-2300 2325);
DISPLAY INVISIBLE (-2300 2325);
FORCEPROP 1 LAST PATH I246
J 0
(-2350 2475);
DISPLAY 0.978723 (-2350 2475);
PAINT WHITE (-2350 2475);
DISPLAY INVISIBLE (-2350 2475);
FORCEPROP 1 LAST PART_NUMBER CS03322FB03
J 0
(-2450 2400);
DISPLAY 0.638298 (-2450 2400);
DISPLAY INVISIBLE (-2450 2400);
FORCEADD Q_RES..1
(-2300 2175);
FORCEPROP 1 LAST LOCATION R3480
J 0
(-2575 2175);
DISPLAY 0.787234 (-2575 2175);
FORCEPROP 2 LAST $SEC 1
J 0
(-2350 2375);
DISPLAY 0.680851 (-2350 2375);
PAINT MONO (-2350 2375);
DISPLAY INVISIBLE (-2350 2375);
FORCEPROP 2 LAST CDS_SEC 1
J 0
(-2350 2375);
DISPLAY 1.021277 (-2350 2375);
DISPLAY INVISIBLE (-2350 2375);
FORCEPROP 1 LASTPIN (-2400 2175) $PN 1
J 0
(-2388 2187);
DISPLAY 0.787234 (-2388 2187);
FORCEPROP 1 LASTPIN (-2200 2175) $PN 2
J 0
(-2238 2187);
DISPLAY 0.787234 (-2238 2187);
FORCEPROP 1 LAST MATERIAL CHIP
J 0
(-1950 2175);
DISPLAY 0.638298 (-1950 2175);
FORCEPROP 1 LAST TOLERANCE 1%
J 0
(-2025 2175);
DISPLAY 0.638298 (-2025 2175);
FORCEPROP 1 LAST VALUE 33.2
J 2
(-2050 2175);
DISPLAY 0.638298 (-2050 2175);
FORCEPROP 2 LAST CDS_LIB pure_quanta
J 0
(-2300 2175);
PAINT MONO (-2300 2175);
DISPLAY INVISIBLE (-2300 2175);
FORCEPROP 1 LAST PACK_TYPE 0402LF
J 0
(-2450 2300);
DISPLAY 0.638298 (-2450 2300);
DISPLAY INVISIBLE (-2450 2300);
FORCEPROP 1 LAST WATTAGE 1/16W
J 2
(-2100 2300);
DISPLAY 0.638298 (-2100 2300);
DISPLAY INVISIBLE (-2100 2300);
FORCEPROP 1 LAST PATH I247
J 0
(-2350 2325);
DISPLAY 0.978723 (-2350 2325);
PAINT WHITE (-2350 2325);
DISPLAY INVISIBLE (-2350 2325);
FORCEPROP 1 LAST PART_NUMBER CS03322FB03
J 0
(-2450 2250);
DISPLAY 0.638298 (-2450 2250);
DISPLAY INVISIBLE (-2450 2250);
FORCEADD OFFPAGE..1
R 2
(-800 2225);
FORCEPROP 2 LAST $XR0 126 
J 0
(-614 2225);
DISPLAY 0.638298 (-614 2225);
PAINT MONO (-614 2225);
FORCEPROP 2 LAST CDS_LIB standard
J 0
(-800 2225);
DISPLAY INVISIBLE (-800 2225);
FORCEPROP 1 LAST OFFPAGE TRUE
J 2
(-1125 2100);
DISPLAY 0.872340 (-1125 2100);
PAINT GREEN (-1125 2100);
DISPLAY INVISIBLE (-1125 2100);
FORCEPROP 1 LAST COMMENT_BODY TRUE
J 2
(-925 2125);
DISPLAY 0.872340 (-925 2125);
PAINT GREEN (-925 2125);
DISPLAY INVISIBLE (-925 2125);
FORCEPROP 2 LAST PATH I248
J 0
(-625 2300);
DISPLAY 0.680851 (-625 2300);
DISPLAY INVISIBLE (-625 2300);
FORCEADD OFFPAGE..1
R 2
(-800 2175);
FORCEPROP 2 LAST $XR0 126 
J 0
(-614 2175);
DISPLAY 0.638298 (-614 2175);
PAINT MONO (-614 2175);
FORCEPROP 2 LAST CDS_LIB standard
J 0
(-800 2175);
DISPLAY INVISIBLE (-800 2175);
FORCEPROP 1 LAST OFFPAGE TRUE
J 2
(-1125 2050);
DISPLAY 0.872340 (-1125 2050);
PAINT GREEN (-1125 2050);
DISPLAY INVISIBLE (-1125 2050);
FORCEPROP 1 LAST COMMENT_BODY TRUE
J 2
(-925 2075);
DISPLAY 0.872340 (-925 2075);
PAINT GREEN (-925 2075);
DISPLAY INVISIBLE (-925 2075);
FORCEPROP 2 LAST PATH I249
J 0
(-625 2250);
DISPLAY 0.680851 (-625 2250);
DISPLAY INVISIBLE (-625 2250);
FORCEADD Q_RES..1
(-6725 575);
FORCEPROP 1 LAST LOCATION R648
J 0
(-6625 575);
DISPLAY 0.489362 (-6625 575);
PAINT SKYBLUE (-6625 575);
FORCEPROP 0 LAST $SEC 1
J 0
(-6625 625);
DISPLAY 0.680851 (-6625 625);
PAINT MONO (-6625 625);
DISPLAY INVISIBLE (-6625 625);
FORCEPROP 0 LAST CDS_SEC 1
J 0
(-6625 625);
DISPLAY 0.680851 (-6625 625);
DISPLAY INVISIBLE (-6625 625);
FORCEPROP 1 LASTPIN (-6825 575) $PN 1
J 0
(-6813 587);
DISPLAY 0.489362 (-6813 587);
PAINT MONO (-6813 587);
FORCEPROP 1 LASTPIN (-6625 575) $PN 2
J 0
(-6663 587);
DISPLAY 0.489362 (-6663 587);
PAINT MONO (-6663 587);
FORCEPROP 1 LAST VALUE 33
J 2
(-6850 575);
DISPLAY 0.489362 (-6850 575);
PAINT SKYBLUE (-6850 575);
FORCEPROP 2 LAST CDS_LIB pure_quanta
J 0
(-6725 575);
DISPLAY INVISIBLE (-6725 575);
FORCEPROP 2 LAST BOM_COST MEM
J 2
(-6700 725);
DISPLAY 0.744681 (-6700 725);
PAINT WHITE (-6700 725);
DISPLAY INVISIBLE (-6700 725);
FORCEPROP 1 LAST WATTAGE 1/16W
J 2
(-6800 500);
DISPLAY 0.489362 (-6800 500);
PAINT SKYBLUE (-6800 500);
DISPLAY INVISIBLE (-6800 500);
FORCEPROP 1 LAST MATERIAL CHIP
J 2
(-6550 550);
DISPLAY 0.489362 (-6550 550);
PAINT SKYBLUE (-6550 550);
DISPLAY INVISIBLE (-6550 550);
FORCEPROP 1 LAST TOLERANCE 5%
J 0
(-6850 550);
DISPLAY 0.489362 (-6850 550);
PAINT SKYBLUE (-6850 550);
DISPLAY INVISIBLE (-6850 550);
FORCEPROP 1 LAST PACK_TYPE 0402LF
J 2
(-6550 500);
DISPLAY 0.489362 (-6550 500);
PAINT SKYBLUE (-6550 500);
DISPLAY INVISIBLE (-6550 500);
FORCEPROP 1 LAST PATH I25
J 0
(-6775 725);
DISPLAY 0.978723 (-6775 725);
PAINT WHITE (-6775 725);
DISPLAY INVISIBLE (-6775 725);
FORCEPROP 1 LAST PART_NUMBER CS03302JB10
J 2
(-6625 625);
DISPLAY 0.489362 (-6625 625);
PAINT SKYBLUE (-6625 625);
DISPLAY INVISIBLE (-6625 625);
FORCEADD Q_RES..1
(-2300 2225);
FORCEPROP 1 LAST LOCATION R3476
J 0
(-2575 2225);
DISPLAY 0.787234 (-2575 2225);
FORCEPROP 2 LAST $SEC 1
J 0
(-2350 2425);
DISPLAY 0.680851 (-2350 2425);
PAINT MONO (-2350 2425);
DISPLAY INVISIBLE (-2350 2425);
FORCEPROP 2 LAST CDS_SEC 1
J 0
(-2350 2425);
DISPLAY 1.021277 (-2350 2425);
DISPLAY INVISIBLE (-2350 2425);
FORCEPROP 1 LASTPIN (-2400 2225) $PN 1
J 0
(-2388 2237);
DISPLAY 0.787234 (-2388 2237);
FORCEPROP 1 LASTPIN (-2200 2225) $PN 2
J 0
(-2238 2237);
DISPLAY 0.787234 (-2238 2237);
FORCEPROP 1 LAST MATERIAL CHIP
J 0
(-1950 2225);
DISPLAY 0.638298 (-1950 2225);
FORCEPROP 1 LAST TOLERANCE 1%
J 0
(-2025 2225);
DISPLAY 0.638298 (-2025 2225);
FORCEPROP 1 LAST VALUE 33.2
J 2
(-2050 2225);
DISPLAY 0.638298 (-2050 2225);
FORCEPROP 2 LAST CDS_LIB pure_quanta
J 0
(-2300 2225);
PAINT MONO (-2300 2225);
DISPLAY INVISIBLE (-2300 2225);
FORCEPROP 1 LAST PACK_TYPE 0402LF
J 0
(-2450 2350);
DISPLAY 0.638298 (-2450 2350);
DISPLAY INVISIBLE (-2450 2350);
FORCEPROP 1 LAST WATTAGE 1/16W
J 2
(-2100 2350);
DISPLAY 0.638298 (-2100 2350);
DISPLAY INVISIBLE (-2100 2350);
FORCEPROP 1 LAST PATH I250
J 0
(-2350 2375);
DISPLAY 0.978723 (-2350 2375);
PAINT WHITE (-2350 2375);
DISPLAY INVISIBLE (-2350 2375);
FORCEPROP 1 LAST PART_NUMBER CS03322FB03
J 0
(-2450 2300);
DISPLAY 0.638298 (-2450 2300);
DISPLAY INVISIBLE (-2450 2300);
FORCEADD Q_RES..1
(-2300 2125);
FORCEPROP 1 LAST LOCATION R3481
J 0
(-2575 2125);
DISPLAY 0.787234 (-2575 2125);
FORCEPROP 2 LAST $SEC 1
J 0
(-2350 2325);
DISPLAY 0.680851 (-2350 2325);
PAINT MONO (-2350 2325);
DISPLAY INVISIBLE (-2350 2325);
FORCEPROP 2 LAST CDS_SEC 1
J 0
(-2350 2325);
DISPLAY 1.021277 (-2350 2325);
DISPLAY INVISIBLE (-2350 2325);
FORCEPROP 1 LASTPIN (-2400 2125) $PN 1
J 0
(-2388 2137);
DISPLAY 0.787234 (-2388 2137);
FORCEPROP 1 LASTPIN (-2200 2125) $PN 2
J 0
(-2238 2137);
DISPLAY 0.787234 (-2238 2137);
FORCEPROP 1 LAST TOLERANCE 1%
J 0
(-2025 2125);
DISPLAY 0.638298 (-2025 2125);
FORCEPROP 1 LAST MATERIAL CHIP
J 0
(-1950 2125);
DISPLAY 0.638298 (-1950 2125);
FORCEPROP 1 LAST VALUE 33.2
J 2
(-2050 2125);
DISPLAY 0.638298 (-2050 2125);
FORCEPROP 1 LAST WATTAGE 1/16W
J 2
(-2100 2250);
DISPLAY 0.638298 (-2100 2250);
DISPLAY INVISIBLE (-2100 2250);
FORCEPROP 1 LAST PACK_TYPE 0402LF
J 0
(-2450 2250);
DISPLAY 0.638298 (-2450 2250);
DISPLAY INVISIBLE (-2450 2250);
FORCEPROP 2 LAST CDS_LIB pure_quanta
J 0
(-2300 2125);
PAINT MONO (-2300 2125);
DISPLAY INVISIBLE (-2300 2125);
FORCEPROP 1 LAST PATH I251
J 0
(-2350 2275);
DISPLAY 0.978723 (-2350 2275);
PAINT WHITE (-2350 2275);
DISPLAY INVISIBLE (-2350 2275);
FORCEPROP 1 LAST PART_NUMBER CS03322FB03
J 0
(-2450 2200);
DISPLAY 0.638298 (-2450 2200);
DISPLAY INVISIBLE (-2450 2200);
FORCEADD OFFPAGE..1
R 2
(-800 2075);
FORCEPROP 2 LAST $XR0 126 
J 0
(-614 2075);
DISPLAY 0.638298 (-614 2075);
PAINT MONO (-614 2075);
FORCEPROP 2 LAST CDS_LIB standard
J 0
(-800 2075);
DISPLAY INVISIBLE (-800 2075);
FORCEPROP 1 LAST OFFPAGE TRUE
J 2
(-1125 1950);
DISPLAY 0.872340 (-1125 1950);
PAINT GREEN (-1125 1950);
DISPLAY INVISIBLE (-1125 1950);
FORCEPROP 1 LAST COMMENT_BODY TRUE
J 2
(-925 1975);
DISPLAY 0.872340 (-925 1975);
PAINT GREEN (-925 1975);
DISPLAY INVISIBLE (-925 1975);
FORCEPROP 2 LAST PATH I252
J 0
(-625 2150);
DISPLAY 0.680851 (-625 2150);
DISPLAY INVISIBLE (-625 2150);
FORCEADD OFFPAGE..1
R 2
(-800 2125);
FORCEPROP 2 LAST $XR0 126 
J 0
(-614 2125);
DISPLAY 0.638298 (-614 2125);
PAINT MONO (-614 2125);
FORCEPROP 2 LAST CDS_LIB standard
J 0
(-800 2125);
DISPLAY INVISIBLE (-800 2125);
FORCEPROP 1 LAST OFFPAGE TRUE
J 2
(-1125 2000);
DISPLAY 0.872340 (-1125 2000);
PAINT GREEN (-1125 2000);
DISPLAY INVISIBLE (-1125 2000);
FORCEPROP 1 LAST COMMENT_BODY TRUE
J 2
(-925 2025);
DISPLAY 0.872340 (-925 2025);
PAINT GREEN (-925 2025);
DISPLAY INVISIBLE (-925 2025);
FORCEPROP 2 LAST PATH I253
J 0
(-625 2200);
DISPLAY 0.680851 (-625 2200);
DISPLAY INVISIBLE (-625 2200);
FORCEADD Q_RES..1
(-2300 2075);
FORCEPROP 1 LAST LOCATION R3484
J 0
(-2575 2075);
DISPLAY 0.787234 (-2575 2075);
FORCEPROP 2 LAST $SEC 1
J 0
(-2350 2275);
DISPLAY 0.680851 (-2350 2275);
PAINT MONO (-2350 2275);
DISPLAY INVISIBLE (-2350 2275);
FORCEPROP 2 LAST CDS_SEC 1
J 0
(-2350 2275);
DISPLAY 1.021277 (-2350 2275);
DISPLAY INVISIBLE (-2350 2275);
FORCEPROP 1 LASTPIN (-2400 2075) $PN 1
J 0
(-2388 2087);
DISPLAY 0.787234 (-2388 2087);
FORCEPROP 1 LASTPIN (-2200 2075) $PN 2
J 0
(-2238 2087);
DISPLAY 0.787234 (-2238 2087);
FORCEPROP 1 LAST TOLERANCE 1%
J 0
(-2025 2075);
DISPLAY 0.638298 (-2025 2075);
FORCEPROP 1 LAST MATERIAL CHIP
J 0
(-1950 2075);
DISPLAY 0.638298 (-1950 2075);
FORCEPROP 1 LAST VALUE 33.2
J 2
(-2050 2075);
DISPLAY 0.638298 (-2050 2075);
FORCEPROP 1 LAST WATTAGE 1/16W
J 2
(-2100 2200);
DISPLAY 0.638298 (-2100 2200);
DISPLAY INVISIBLE (-2100 2200);
FORCEPROP 1 LAST PACK_TYPE 0402LF
J 0
(-2450 2200);
DISPLAY 0.638298 (-2450 2200);
DISPLAY INVISIBLE (-2450 2200);
FORCEPROP 2 LAST CDS_LIB pure_quanta
J 0
(-2300 2075);
PAINT MONO (-2300 2075);
DISPLAY INVISIBLE (-2300 2075);
FORCEPROP 1 LAST PATH I254
J 0
(-2350 2225);
DISPLAY 0.978723 (-2350 2225);
PAINT WHITE (-2350 2225);
DISPLAY INVISIBLE (-2350 2225);
FORCEPROP 1 LAST PART_NUMBER CS03322FB03
J 0
(-2450 2150);
DISPLAY 0.638298 (-2450 2150);
DISPLAY INVISIBLE (-2450 2150);
FORCEADD Q_RES..1
(-2300 2025);
FORCEPROP 1 LAST LOCATION R3485
J 0
(-2575 2025);
DISPLAY 0.787234 (-2575 2025);
FORCEPROP 2 LAST $SEC 1
J 0
(-2350 2225);
DISPLAY 0.680851 (-2350 2225);
PAINT MONO (-2350 2225);
DISPLAY INVISIBLE (-2350 2225);
FORCEPROP 2 LAST CDS_SEC 1
J 0
(-2350 2225);
DISPLAY 1.021277 (-2350 2225);
DISPLAY INVISIBLE (-2350 2225);
FORCEPROP 1 LASTPIN (-2400 2025) $PN 1
J 0
(-2388 2037);
DISPLAY 0.787234 (-2388 2037);
FORCEPROP 1 LASTPIN (-2200 2025) $PN 2
J 0
(-2238 2037);
DISPLAY 0.787234 (-2238 2037);
FORCEPROP 1 LAST TOLERANCE 1%
J 0
(-2025 2025);
DISPLAY 0.638298 (-2025 2025);
FORCEPROP 1 LAST VALUE 33.2
J 2
(-2050 2025);
DISPLAY 0.638298 (-2050 2025);
FORCEPROP 1 LAST MATERIAL CHIP
J 0
(-1950 2025);
DISPLAY 0.638298 (-1950 2025);
FORCEPROP 1 LAST WATTAGE 1/16W
J 2
(-2100 2150);
DISPLAY 0.638298 (-2100 2150);
DISPLAY INVISIBLE (-2100 2150);
FORCEPROP 1 LAST PACK_TYPE 0402LF
J 0
(-2450 2150);
DISPLAY 0.638298 (-2450 2150);
DISPLAY INVISIBLE (-2450 2150);
FORCEPROP 2 LAST CDS_LIB pure_quanta
J 0
(-2300 2025);
PAINT MONO (-2300 2025);
DISPLAY INVISIBLE (-2300 2025);
FORCEPROP 1 LAST PATH I255
J 0
(-2350 2175);
DISPLAY 0.978723 (-2350 2175);
PAINT WHITE (-2350 2175);
DISPLAY INVISIBLE (-2350 2175);
FORCEPROP 1 LAST PART_NUMBER CS03322FB03
J 0
(-2450 2100);
DISPLAY 0.638298 (-2450 2100);
DISPLAY INVISIBLE (-2450 2100);
FORCEADD OFFPAGE..1
R 2
(-800 1975);
FORCEPROP 2 LAST $XR1 246 
J 0
(-494 1975);
DISPLAY 0.638298 (-494 1975);
PAINT MONO (-494 1975);
FORCEPROP 2 LAST $XR0 126 
J 0
(-614 1975);
DISPLAY 0.638298 (-614 1975);
PAINT MONO (-614 1975);
FORCEPROP 2 LAST CDS_LIB standard
J 0
(-800 1975);
DISPLAY INVISIBLE (-800 1975);
FORCEPROP 1 LAST OFFPAGE TRUE
J 2
(-1125 1850);
DISPLAY 0.872340 (-1125 1850);
PAINT GREEN (-1125 1850);
DISPLAY INVISIBLE (-1125 1850);
FORCEPROP 1 LAST COMMENT_BODY TRUE
J 2
(-925 1875);
DISPLAY 0.872340 (-925 1875);
PAINT GREEN (-925 1875);
DISPLAY INVISIBLE (-925 1875);
FORCEPROP 2 LAST PATH I256
J 0
(-625 2050);
DISPLAY 0.680851 (-625 2050);
DISPLAY INVISIBLE (-625 2050);
FORCEADD OFFPAGE..2
(-800 2025);
FORCEPROP 2 LAST $XR0 126 
J 0
(-611 2025);
DISPLAY 0.638298 (-611 2025);
PAINT MONO (-611 2025);
FORCEPROP 2 LAST CDS_LIB standard
J 2
(-800 2025);
DISPLAY INVISIBLE (-800 2025);
FORCEPROP 1 LAST OFFPAGE TRUE
J 0
(-475 1900);
DISPLAY 0.872340 (-475 1900);
DISPLAY INVISIBLE (-475 1900);
FORCEPROP 1 LAST COMMENT_BODY TRUE
J 0
(-845 1930);
DISPLAY 0.872340 (-845 1930);
PAINT GREEN (-845 1930);
DISPLAY INVISIBLE (-845 1930);
FORCEPROP 2 LAST PATH I257
J 2
(-975 2100);
DISPLAY 0.680851 (-975 2100);
DISPLAY INVISIBLE (-975 2100);
FORCEADD Q_RES..1
(-2300 1975);
FORCEPROP 1 LAST LOCATION R3486
J 0
(-2575 1975);
DISPLAY 0.787234 (-2575 1975);
FORCEPROP 2 LAST $SEC 1
J 0
(-2350 2175);
DISPLAY 0.680851 (-2350 2175);
PAINT MONO (-2350 2175);
DISPLAY INVISIBLE (-2350 2175);
FORCEPROP 2 LAST CDS_SEC 1
J 0
(-2350 2175);
DISPLAY 1.021277 (-2350 2175);
DISPLAY INVISIBLE (-2350 2175);
FORCEPROP 1 LASTPIN (-2400 1975) $PN 1
J 0
(-2388 1987);
DISPLAY 0.787234 (-2388 1987);
FORCEPROP 1 LASTPIN (-2200 1975) $PN 2
J 0
(-2238 1987);
DISPLAY 0.787234 (-2238 1987);
FORCEPROP 1 LAST MATERIAL CHIP
J 0
(-1950 1975);
DISPLAY 0.638298 (-1950 1975);
FORCEPROP 1 LAST TOLERANCE 1%
J 0
(-2025 1975);
DISPLAY 0.638298 (-2025 1975);
FORCEPROP 1 LAST VALUE 33.2
J 2
(-2050 1975);
DISPLAY 0.638298 (-2050 1975);
FORCEPROP 1 LAST WATTAGE 1/16W
J 2
(-2100 2100);
DISPLAY 0.638298 (-2100 2100);
DISPLAY INVISIBLE (-2100 2100);
FORCEPROP 1 LAST PACK_TYPE 0402LF
J 0
(-2450 2100);
DISPLAY 0.638298 (-2450 2100);
DISPLAY INVISIBLE (-2450 2100);
FORCEPROP 2 LAST CDS_LIB pure_quanta
J 0
(-2300 1975);
PAINT MONO (-2300 1975);
DISPLAY INVISIBLE (-2300 1975);
FORCEPROP 1 LAST PATH I258
J 0
(-2350 2125);
DISPLAY 0.978723 (-2350 2125);
PAINT WHITE (-2350 2125);
DISPLAY INVISIBLE (-2350 2125);
FORCEPROP 1 LAST PART_NUMBER CS03322FB03
J 0
(-2450 2050);
DISPLAY 0.638298 (-2450 2050);
DISPLAY INVISIBLE (-2450 2050);
FORCEADD Q_RES..1
(-2300 1925);
FORCEPROP 1 LAST LOCATION R3505
J 0
(-2575 1925);
DISPLAY 0.787234 (-2575 1925);
FORCEPROP 2 LAST $SEC 1
J 0
(-2350 2125);
DISPLAY 0.680851 (-2350 2125);
PAINT MONO (-2350 2125);
DISPLAY INVISIBLE (-2350 2125);
FORCEPROP 2 LAST CDS_SEC 1
J 0
(-2350 2125);
DISPLAY 1.021277 (-2350 2125);
DISPLAY INVISIBLE (-2350 2125);
FORCEPROP 1 LASTPIN (-2400 1925) $PN 1
J 0
(-2388 1937);
DISPLAY 0.787234 (-2388 1937);
FORCEPROP 1 LASTPIN (-2200 1925) $PN 2
J 0
(-2238 1937);
DISPLAY 0.787234 (-2238 1937);
FORCEPROP 1 LAST TOLERANCE 1%
J 0
(-2025 1925);
DISPLAY 0.638298 (-2025 1925);
FORCEPROP 1 LAST VALUE 33.2
J 2
(-2050 1925);
DISPLAY 0.638298 (-2050 1925);
FORCEPROP 1 LAST MATERIAL CHIP
J 0
(-1950 1925);
DISPLAY 0.638298 (-1950 1925);
FORCEPROP 2 LAST CDS_LIB pure_quanta
J 0
(-2300 1925);
PAINT MONO (-2300 1925);
DISPLAY INVISIBLE (-2300 1925);
FORCEPROP 1 LAST PACK_TYPE 0402LF
J 0
(-2450 2050);
DISPLAY 0.638298 (-2450 2050);
DISPLAY INVISIBLE (-2450 2050);
FORCEPROP 1 LAST WATTAGE 1/16W
J 2
(-2100 2050);
DISPLAY 0.638298 (-2100 2050);
DISPLAY INVISIBLE (-2100 2050);
FORCEPROP 1 LAST PATH I259
J 0
(-2350 2075);
DISPLAY 0.978723 (-2350 2075);
PAINT WHITE (-2350 2075);
DISPLAY INVISIBLE (-2350 2075);
FORCEPROP 1 LAST PART_NUMBER CS03322FB03
J 0
(-2450 2000);
DISPLAY 0.638298 (-2450 2000);
DISPLAY INVISIBLE (-2450 2000);
FORCEADD OFFPAGE..1
R 2
(-800 1875);
FORCEPROP 2 LAST $XR0 127 
J 0
(-614 1875);
DISPLAY 0.638298 (-614 1875);
PAINT MONO (-614 1875);
FORCEPROP 2 LAST CDS_LIB standard
J 0
(-800 1875);
DISPLAY INVISIBLE (-800 1875);
FORCEPROP 1 LAST OFFPAGE TRUE
J 2
(-1125 1750);
DISPLAY 0.872340 (-1125 1750);
PAINT GREEN (-1125 1750);
DISPLAY INVISIBLE (-1125 1750);
FORCEPROP 1 LAST COMMENT_BODY TRUE
J 2
(-925 1775);
DISPLAY 0.872340 (-925 1775);
PAINT GREEN (-925 1775);
DISPLAY INVISIBLE (-925 1775);
FORCEPROP 2 LAST PATH I260
J 0
(-625 1950);
DISPLAY 0.680851 (-625 1950);
DISPLAY INVISIBLE (-625 1950);
FORCEADD OFFPAGE..1
R 2
(-800 1925);
FORCEPROP 2 LAST $XR0 126 
J 0
(-614 1925);
DISPLAY 0.638298 (-614 1925);
PAINT MONO (-614 1925);
FORCEPROP 2 LAST CDS_LIB standard
J 0
(-800 1925);
DISPLAY INVISIBLE (-800 1925);
FORCEPROP 1 LAST OFFPAGE TRUE
J 2
(-1125 1800);
DISPLAY 0.872340 (-1125 1800);
PAINT GREEN (-1125 1800);
DISPLAY INVISIBLE (-1125 1800);
FORCEPROP 1 LAST COMMENT_BODY TRUE
J 2
(-925 1825);
DISPLAY 0.872340 (-925 1825);
PAINT GREEN (-925 1825);
DISPLAY INVISIBLE (-925 1825);
FORCEPROP 2 LAST PATH I261
J 0
(-625 2000);
DISPLAY 0.680851 (-625 2000);
DISPLAY INVISIBLE (-625 2000);
FORCEADD Q_RES..1
(-2300 1875);
FORCEPROP 1 LAST LOCATION R2846
J 0
(-2575 1875);
DISPLAY 0.787234 (-2575 1875);
FORCEPROP 2 LAST $SEC 1
J 0
(-2350 2075);
DISPLAY 0.680851 (-2350 2075);
PAINT MONO (-2350 2075);
DISPLAY INVISIBLE (-2350 2075);
FORCEPROP 2 LAST CDS_SEC 1
J 0
(-2350 2075);
DISPLAY 1.021277 (-2350 2075);
DISPLAY INVISIBLE (-2350 2075);
FORCEPROP 1 LASTPIN (-2400 1875) $PN 1
J 0
(-2388 1887);
DISPLAY 0.787234 (-2388 1887);
FORCEPROP 1 LASTPIN (-2200 1875) $PN 2
J 0
(-2238 1887);
DISPLAY 0.787234 (-2238 1887);
FORCEPROP 1 LAST TOLERANCE 1%
J 0
(-2025 1875);
DISPLAY 0.638298 (-2025 1875);
FORCEPROP 1 LAST VALUE 33.2
J 2
(-2050 1875);
DISPLAY 0.638298 (-2050 1875);
FORCEPROP 1 LAST MATERIAL CHIP
J 0
(-1950 1875);
DISPLAY 0.638298 (-1950 1875);
FORCEPROP 2 LAST CDS_LIB pure_quanta
J 0
(-2300 1875);
PAINT MONO (-2300 1875);
DISPLAY INVISIBLE (-2300 1875);
FORCEPROP 1 LAST PACK_TYPE 0402LF
J 0
(-2450 2000);
DISPLAY 0.638298 (-2450 2000);
DISPLAY INVISIBLE (-2450 2000);
FORCEPROP 1 LAST WATTAGE 1/16W
J 2
(-2100 2000);
DISPLAY 0.638298 (-2100 2000);
DISPLAY INVISIBLE (-2100 2000);
FORCEPROP 1 LAST PATH I262
J 0
(-2350 2025);
DISPLAY 0.978723 (-2350 2025);
PAINT WHITE (-2350 2025);
DISPLAY INVISIBLE (-2350 2025);
FORCEPROP 1 LAST PART_NUMBER CS03322FB03
J 0
(-2450 1950);
DISPLAY 0.638298 (-2450 1950);
DISPLAY INVISIBLE (-2450 1950);
FORCEADD Q_RES..1
(-2300 1775);
FORCEPROP 1 LAST LOCATION R2844
J 0
(-2575 1775);
DISPLAY 0.787234 (-2575 1775);
FORCEPROP 2 LAST $SEC 1
J 0
(-2350 1975);
DISPLAY 0.680851 (-2350 1975);
PAINT MONO (-2350 1975);
DISPLAY INVISIBLE (-2350 1975);
FORCEPROP 2 LAST CDS_SEC 1
J 0
(-2350 1975);
DISPLAY 1.021277 (-2350 1975);
DISPLAY INVISIBLE (-2350 1975);
FORCEPROP 1 LASTPIN (-2400 1775) $PN 1
J 0
(-2388 1787);
DISPLAY 0.787234 (-2388 1787);
FORCEPROP 1 LASTPIN (-2200 1775) $PN 2
J 0
(-2238 1787);
DISPLAY 0.787234 (-2238 1787);
FORCEPROP 1 LAST TOLERANCE 1%
J 0
(-2025 1775);
DISPLAY 0.638298 (-2025 1775);
FORCEPROP 1 LAST VALUE 33.2
J 2
(-2050 1775);
DISPLAY 0.638298 (-2050 1775);
FORCEPROP 1 LAST MATERIAL CHIP
J 0
(-1950 1775);
DISPLAY 0.638298 (-1950 1775);
FORCEPROP 1 LAST WATTAGE 1/16W
J 2
(-2100 1900);
DISPLAY 0.638298 (-2100 1900);
DISPLAY INVISIBLE (-2100 1900);
FORCEPROP 1 LAST PACK_TYPE 0402LF
J 0
(-2450 1900);
DISPLAY 0.638298 (-2450 1900);
DISPLAY INVISIBLE (-2450 1900);
FORCEPROP 2 LAST CDS_LIB pure_quanta
J 0
(-2300 1775);
PAINT MONO (-2300 1775);
DISPLAY INVISIBLE (-2300 1775);
FORCEPROP 1 LAST PATH I263
J 0
(-2350 1925);
DISPLAY 0.978723 (-2350 1925);
PAINT WHITE (-2350 1925);
DISPLAY INVISIBLE (-2350 1925);
FORCEPROP 1 LAST PART_NUMBER CS03322FB03
J 0
(-2450 1850);
DISPLAY 0.638298 (-2450 1850);
DISPLAY INVISIBLE (-2450 1850);
FORCEADD OFFPAGE..1
R 2
(-800 1825);
FORCEPROP 2 LAST $XR0 127 
J 0
(-614 1825);
DISPLAY 0.638298 (-614 1825);
PAINT MONO (-614 1825);
FORCEPROP 2 LAST CDS_LIB standard
J 0
(-800 1825);
DISPLAY INVISIBLE (-800 1825);
FORCEPROP 1 LAST OFFPAGE TRUE
J 2
(-1125 1700);
DISPLAY 0.872340 (-1125 1700);
PAINT GREEN (-1125 1700);
DISPLAY INVISIBLE (-1125 1700);
FORCEPROP 1 LAST COMMENT_BODY TRUE
J 2
(-925 1725);
DISPLAY 0.872340 (-925 1725);
PAINT GREEN (-925 1725);
DISPLAY INVISIBLE (-925 1725);
FORCEPROP 2 LAST PATH I264
J 0
(-625 1900);
DISPLAY 0.680851 (-625 1900);
DISPLAY INVISIBLE (-625 1900);
FORCEADD OFFPAGE..1
R 2
(-800 1775);
FORCEPROP 2 LAST $XR0 127 
J 0
(-614 1775);
DISPLAY 0.638298 (-614 1775);
PAINT MONO (-614 1775);
FORCEPROP 2 LAST CDS_LIB standard
J 0
(-800 1775);
DISPLAY INVISIBLE (-800 1775);
FORCEPROP 1 LAST OFFPAGE TRUE
J 2
(-1125 1650);
DISPLAY 0.872340 (-1125 1650);
PAINT GREEN (-1125 1650);
DISPLAY INVISIBLE (-1125 1650);
FORCEPROP 1 LAST COMMENT_BODY TRUE
J 2
(-925 1675);
DISPLAY 0.872340 (-925 1675);
PAINT GREEN (-925 1675);
DISPLAY INVISIBLE (-925 1675);
FORCEPROP 2 LAST PATH I265
J 0
(-625 1850);
DISPLAY 0.680851 (-625 1850);
DISPLAY INVISIBLE (-625 1850);
FORCEADD Q_RES..1
(-2300 1825);
FORCEPROP 1 LAST LOCATION R2847
J 0
(-2575 1825);
DISPLAY 0.787234 (-2575 1825);
FORCEPROP 2 LAST $SEC 1
J 0
(-2350 2025);
DISPLAY 0.680851 (-2350 2025);
PAINT MONO (-2350 2025);
DISPLAY INVISIBLE (-2350 2025);
FORCEPROP 2 LAST CDS_SEC 1
J 0
(-2350 2025);
DISPLAY 1.021277 (-2350 2025);
DISPLAY INVISIBLE (-2350 2025);
FORCEPROP 1 LASTPIN (-2400 1825) $PN 1
J 0
(-2388 1837);
DISPLAY 0.787234 (-2388 1837);
FORCEPROP 1 LASTPIN (-2200 1825) $PN 2
J 0
(-2238 1837);
DISPLAY 0.787234 (-2238 1837);
FORCEPROP 1 LAST TOLERANCE 1%
J 0
(-2025 1825);
DISPLAY 0.638298 (-2025 1825);
FORCEPROP 1 LAST VALUE 33.2
J 2
(-2050 1825);
DISPLAY 0.638298 (-2050 1825);
FORCEPROP 1 LAST MATERIAL CHIP
J 0
(-1950 1825);
DISPLAY 0.638298 (-1950 1825);
FORCEPROP 1 LAST WATTAGE 1/16W
J 2
(-2100 1950);
DISPLAY 0.638298 (-2100 1950);
DISPLAY INVISIBLE (-2100 1950);
FORCEPROP 1 LAST PACK_TYPE 0402LF
J 0
(-2450 1950);
DISPLAY 0.638298 (-2450 1950);
DISPLAY INVISIBLE (-2450 1950);
FORCEPROP 2 LAST CDS_LIB pure_quanta
J 0
(-2300 1825);
PAINT MONO (-2300 1825);
DISPLAY INVISIBLE (-2300 1825);
FORCEPROP 1 LAST PATH I266
J 0
(-2350 1975);
DISPLAY 0.978723 (-2350 1975);
PAINT WHITE (-2350 1975);
DISPLAY INVISIBLE (-2350 1975);
FORCEPROP 1 LAST PART_NUMBER CS03322FB03
J 0
(-2450 1900);
DISPLAY 0.638298 (-2450 1900);
DISPLAY INVISIBLE (-2450 1900);
FORCEADD OFFPAGE..1
R 2
(-800 1725);
FORCEPROP 2 LAST $XR0 127 
J 0
(-614 1725);
DISPLAY 0.638298 (-614 1725);
PAINT MONO (-614 1725);
FORCEPROP 2 LAST CDS_LIB standard
J 0
(-800 1725);
DISPLAY INVISIBLE (-800 1725);
FORCEPROP 1 LAST OFFPAGE TRUE
J 2
(-1125 1600);
DISPLAY 0.872340 (-1125 1600);
PAINT GREEN (-1125 1600);
DISPLAY INVISIBLE (-1125 1600);
FORCEPROP 1 LAST COMMENT_BODY TRUE
J 2
(-925 1625);
DISPLAY 0.872340 (-925 1625);
PAINT GREEN (-925 1625);
DISPLAY INVISIBLE (-925 1625);
FORCEPROP 2 LAST PATH I267
J 0
(-625 1800);
DISPLAY 0.680851 (-625 1800);
DISPLAY INVISIBLE (-625 1800);
FORCEADD Q_RES..1
(-2300 1725);
FORCEPROP 1 LAST LOCATION R3066
J 0
(-2575 1725);
DISPLAY 0.787234 (-2575 1725);
FORCEPROP 2 LAST $SEC 1
J 0
(-2350 1925);
DISPLAY 0.680851 (-2350 1925);
PAINT MONO (-2350 1925);
DISPLAY INVISIBLE (-2350 1925);
FORCEPROP 2 LAST CDS_SEC 1
J 0
(-2350 1925);
DISPLAY 1.021277 (-2350 1925);
DISPLAY INVISIBLE (-2350 1925);
FORCEPROP 1 LASTPIN (-2400 1725) $PN 1
J 0
(-2388 1737);
DISPLAY 0.787234 (-2388 1737);
FORCEPROP 1 LASTPIN (-2200 1725) $PN 2
J 0
(-2238 1737);
DISPLAY 0.787234 (-2238 1737);
FORCEPROP 1 LAST TOLERANCE 1%
J 0
(-2025 1725);
DISPLAY 0.638298 (-2025 1725);
FORCEPROP 1 LAST VALUE 33.2
J 2
(-2050 1725);
DISPLAY 0.638298 (-2050 1725);
FORCEPROP 1 LAST MATERIAL CHIP
J 0
(-1950 1725);
DISPLAY 0.638298 (-1950 1725);
FORCEPROP 2 LAST CDS_LIB pure_quanta
J 0
(-2300 1725);
PAINT MONO (-2300 1725);
DISPLAY INVISIBLE (-2300 1725);
FORCEPROP 1 LAST PACK_TYPE 0402LF
J 0
(-2450 1850);
DISPLAY 0.638298 (-2450 1850);
DISPLAY INVISIBLE (-2450 1850);
FORCEPROP 1 LAST WATTAGE 1/16W
J 2
(-2100 1850);
DISPLAY 0.638298 (-2100 1850);
DISPLAY INVISIBLE (-2100 1850);
FORCEPROP 1 LAST PATH I268
J 0
(-2350 1875);
DISPLAY 0.978723 (-2350 1875);
PAINT WHITE (-2350 1875);
DISPLAY INVISIBLE (-2350 1875);
FORCEPROP 1 LAST PART_NUMBER CS03322FB03
J 0
(-2450 1800);
DISPLAY 0.638298 (-2450 1800);
DISPLAY INVISIBLE (-2450 1800);
FORCEADD OFFPAGE..1
R 2
(-800 1525);
FORCEPROP 2 LAST $XR0 127 
J 0
(-614 1525);
DISPLAY 0.638298 (-614 1525);
PAINT MONO (-614 1525);
FORCEPROP 2 LAST CDS_LIB standard
J 0
(-800 1525);
DISPLAY INVISIBLE (-800 1525);
FORCEPROP 1 LAST OFFPAGE TRUE
J 2
(-1125 1400);
DISPLAY 0.872340 (-1125 1400);
PAINT GREEN (-1125 1400);
DISPLAY INVISIBLE (-1125 1400);
FORCEPROP 1 LAST COMMENT_BODY TRUE
J 2
(-925 1425);
DISPLAY 0.872340 (-925 1425);
PAINT GREEN (-925 1425);
DISPLAY INVISIBLE (-925 1425);
FORCEPROP 2 LAST PATH I269
J 0
(-625 1600);
DISPLAY 0.680851 (-625 1600);
DISPLAY INVISIBLE (-625 1600);
FORCEADD OFFPAGE..1
R 2
(-800 1575);
FORCEPROP 2 LAST $XR0 127 
J 0
(-584 1575);
DISPLAY 0.638298 (-584 1575);
PAINT MONO (-584 1575);
FORCEPROP 2 LAST CDS_LIB standard
J 0
(-800 1575);
DISPLAY INVISIBLE (-800 1575);
FORCEPROP 1 LAST OFFPAGE TRUE
J 2
(-1125 1450);
DISPLAY 0.872340 (-1125 1450);
PAINT GREEN (-1125 1450);
DISPLAY INVISIBLE (-1125 1450);
FORCEPROP 1 LAST COMMENT_BODY TRUE
J 2
(-925 1475);
DISPLAY 0.872340 (-925 1475);
PAINT GREEN (-925 1475);
DISPLAY INVISIBLE (-925 1475);
FORCEPROP 2 LAST PATH I270
J 0
(-625 1650);
DISPLAY 0.680851 (-625 1650);
DISPLAY INVISIBLE (-625 1650);
FORCEADD Q_RES..1
(-2300 1575);
FORCEPROP 1 LAST LOCATION R2663
J 0
(-2575 1575);
DISPLAY 0.787234 (-2575 1575);
FORCEPROP 2 LAST $SEC 1
J 0
(-2350 1775);
DISPLAY 0.680851 (-2350 1775);
PAINT MONO (-2350 1775);
DISPLAY INVISIBLE (-2350 1775);
FORCEPROP 2 LAST CDS_SEC 1
J 0
(-2350 1775);
DISPLAY 1.021277 (-2350 1775);
DISPLAY INVISIBLE (-2350 1775);
FORCEPROP 1 LASTPIN (-2400 1575) $PN 1
J 0
(-2388 1587);
DISPLAY 0.787234 (-2388 1587);
FORCEPROP 1 LASTPIN (-2200 1575) $PN 2
J 0
(-2238 1587);
DISPLAY 0.787234 (-2238 1587);
FORCEPROP 1 LAST VALUE 33.2
J 2
(-2050 1575);
DISPLAY 0.638298 (-2050 1575);
FORCEPROP 1 LAST TOLERANCE 1%
J 0
(-2025 1575);
DISPLAY 0.638298 (-2025 1575);
FORCEPROP 1 LAST MATERIAL CHIP
J 0
(-1950 1575);
DISPLAY 0.638298 (-1950 1575);
FORCEPROP 2 LAST CDS_LIB pure_quanta
J 0
(-2300 1575);
PAINT MONO (-2300 1575);
DISPLAY INVISIBLE (-2300 1575);
FORCEPROP 1 LAST PACK_TYPE 0402LF
J 0
(-2450 1700);
DISPLAY 0.638298 (-2450 1700);
DISPLAY INVISIBLE (-2450 1700);
FORCEPROP 1 LAST WATTAGE 1/16W
J 2
(-2100 1700);
DISPLAY 0.638298 (-2100 1700);
DISPLAY INVISIBLE (-2100 1700);
FORCEPROP 1 LAST PATH I271
J 0
(-2350 1725);
DISPLAY 0.978723 (-2350 1725);
PAINT WHITE (-2350 1725);
DISPLAY INVISIBLE (-2350 1725);
FORCEPROP 1 LAST PART_NUMBER CS03322FB03
J 0
(-2450 1650);
DISPLAY 0.638298 (-2450 1650);
DISPLAY INVISIBLE (-2450 1650);
FORCEADD Q_RES..1
(-2300 1525);
FORCEPROP 1 LAST LOCATION R2664
J 0
(-2575 1525);
DISPLAY 0.787234 (-2575 1525);
FORCEPROP 2 LAST $SEC 1
J 0
(-2350 1725);
DISPLAY 0.680851 (-2350 1725);
PAINT MONO (-2350 1725);
DISPLAY INVISIBLE (-2350 1725);
FORCEPROP 2 LAST CDS_SEC 1
J 0
(-2350 1725);
DISPLAY 1.021277 (-2350 1725);
DISPLAY INVISIBLE (-2350 1725);
FORCEPROP 1 LASTPIN (-2400 1525) $PN 1
J 0
(-2388 1537);
DISPLAY 0.787234 (-2388 1537);
FORCEPROP 1 LASTPIN (-2200 1525) $PN 2
J 0
(-2238 1537);
DISPLAY 0.787234 (-2238 1537);
FORCEPROP 1 LAST MATERIAL CHIP
J 0
(-1950 1525);
DISPLAY 0.638298 (-1950 1525);
FORCEPROP 1 LAST TOLERANCE 1%
J 0
(-2025 1525);
DISPLAY 0.638298 (-2025 1525);
FORCEPROP 1 LAST VALUE 33.2
J 2
(-2050 1525);
DISPLAY 0.638298 (-2050 1525);
FORCEPROP 2 LAST CDS_LIB pure_quanta
J 0
(-2300 1525);
PAINT MONO (-2300 1525);
DISPLAY INVISIBLE (-2300 1525);
FORCEPROP 1 LAST PACK_TYPE 0402LF
J 0
(-2450 1650);
DISPLAY 0.638298 (-2450 1650);
DISPLAY INVISIBLE (-2450 1650);
FORCEPROP 1 LAST WATTAGE 1/16W
J 2
(-2100 1650);
DISPLAY 0.638298 (-2100 1650);
DISPLAY INVISIBLE (-2100 1650);
FORCEPROP 1 LAST PATH I272
J 0
(-2350 1675);
DISPLAY 0.978723 (-2350 1675);
PAINT WHITE (-2350 1675);
DISPLAY INVISIBLE (-2350 1675);
FORCEPROP 1 LAST PART_NUMBER CS03322FB03
J 0
(-2450 1600);
DISPLAY 0.638298 (-2450 1600);
DISPLAY INVISIBLE (-2450 1600);
FORCEADD OFFPAGE..1
R 2
(-800 1475);
FORCEPROP 2 LAST $XR0 127 
J 0
(-614 1475);
DISPLAY 0.638298 (-614 1475);
PAINT MONO (-614 1475);
FORCEPROP 2 LAST CDS_LIB standard
J 0
(-800 1475);
DISPLAY INVISIBLE (-800 1475);
FORCEPROP 1 LAST OFFPAGE TRUE
J 2
(-1125 1350);
DISPLAY 0.872340 (-1125 1350);
PAINT GREEN (-1125 1350);
DISPLAY INVISIBLE (-1125 1350);
FORCEPROP 1 LAST COMMENT_BODY TRUE
J 2
(-925 1375);
DISPLAY 0.872340 (-925 1375);
PAINT GREEN (-925 1375);
DISPLAY INVISIBLE (-925 1375);
FORCEPROP 2 LAST PATH I273
J 0
(-625 1550);
DISPLAY 0.680851 (-625 1550);
DISPLAY INVISIBLE (-625 1550);
FORCEADD Q_RES..1
(-2300 1475);
FORCEPROP 1 LAST LOCATION R11667
J 0
(-2575 1475);
DISPLAY 0.787234 (-2575 1475);
FORCEPROP 2 LAST $SEC 1
J 0
(-2350 1675);
DISPLAY 0.680851 (-2350 1675);
PAINT MONO (-2350 1675);
DISPLAY INVISIBLE (-2350 1675);
FORCEPROP 2 LAST CDS_SEC 1
J 0
(-2350 1675);
DISPLAY 1.021277 (-2350 1675);
DISPLAY INVISIBLE (-2350 1675);
FORCEPROP 1 LASTPIN (-2400 1475) $PN 1
J 0
(-2388 1487);
DISPLAY 0.787234 (-2388 1487);
FORCEPROP 1 LASTPIN (-2200 1475) $PN 2
J 0
(-2238 1487);
DISPLAY 0.787234 (-2238 1487);
FORCEPROP 1 LAST VALUE 33.2
J 2
(-2050 1475);
DISPLAY 0.638298 (-2050 1475);
FORCEPROP 1 LAST TOLERANCE 1%
J 0
(-2025 1475);
DISPLAY 0.638298 (-2025 1475);
FORCEPROP 1 LAST MATERIAL CHIP
J 0
(-1950 1475);
DISPLAY 0.638298 (-1950 1475);
FORCEPROP 1 LAST WATTAGE 1/16W
J 2
(-2100 1600);
DISPLAY 0.638298 (-2100 1600);
DISPLAY INVISIBLE (-2100 1600);
FORCEPROP 1 LAST PACK_TYPE 0402LF
J 0
(-2450 1600);
DISPLAY 0.638298 (-2450 1600);
DISPLAY INVISIBLE (-2450 1600);
FORCEPROP 2 LAST CDS_LIB pure_quanta
J 0
(-2300 1475);
PAINT MONO (-2300 1475);
DISPLAY INVISIBLE (-2300 1475);
FORCEPROP 1 LAST PATH I274
J 0
(-2350 1625);
DISPLAY 0.978723 (-2350 1625);
PAINT WHITE (-2350 1625);
DISPLAY INVISIBLE (-2350 1625);
FORCEPROP 1 LAST PART_NUMBER CS03322FB03
J 0
(-2450 1550);
DISPLAY 0.638298 (-2450 1550);
DISPLAY INVISIBLE (-2450 1550);
FORCEADD OFFPAGE..1
R 2
(-800 1375);
FORCEPROP 2 LAST $XR0 127 
J 0
(-584 1375);
DISPLAY 0.638298 (-584 1375);
PAINT MONO (-584 1375);
FORCEPROP 2 LAST CDS_LIB standard
J 0
(-800 1375);
DISPLAY INVISIBLE (-800 1375);
FORCEPROP 1 LAST OFFPAGE TRUE
J 2
(-1125 1250);
DISPLAY 0.872340 (-1125 1250);
PAINT GREEN (-1125 1250);
DISPLAY INVISIBLE (-1125 1250);
FORCEPROP 1 LAST COMMENT_BODY TRUE
J 2
(-925 1275);
DISPLAY 0.872340 (-925 1275);
PAINT GREEN (-925 1275);
DISPLAY INVISIBLE (-925 1275);
FORCEPROP 2 LAST PATH I275
J 0
(-625 1450);
DISPLAY 0.680851 (-625 1450);
DISPLAY INVISIBLE (-625 1450);
FORCEADD Q_RES..1
(-2300 1375);
FORCEPROP 1 LAST LOCATION R3324
J 0
(-2575 1375);
DISPLAY 0.787234 (-2575 1375);
FORCEPROP 2 LAST $SEC 1
J 0
(-2350 1575);
DISPLAY 0.680851 (-2350 1575);
PAINT MONO (-2350 1575);
DISPLAY INVISIBLE (-2350 1575);
FORCEPROP 2 LAST CDS_SEC 1
J 0
(-2350 1575);
DISPLAY 1.021277 (-2350 1575);
DISPLAY INVISIBLE (-2350 1575);
FORCEPROP 1 LASTPIN (-2400 1375) $PN 1
J 0
(-2388 1387);
DISPLAY 0.787234 (-2388 1387);
FORCEPROP 1 LASTPIN (-2200 1375) $PN 2
J 0
(-2238 1387);
DISPLAY 0.787234 (-2238 1387);
FORCEPROP 1 LAST TOLERANCE 1%
J 0
(-2025 1375);
DISPLAY 0.638298 (-2025 1375);
FORCEPROP 1 LAST VALUE 33.2
J 2
(-2050 1375);
DISPLAY 0.638298 (-2050 1375);
FORCEPROP 1 LAST MATERIAL CHIP
J 0
(-1950 1375);
DISPLAY 0.638298 (-1950 1375);
FORCEPROP 1 LAST WATTAGE 1/16W
J 2
(-2100 1500);
DISPLAY 0.638298 (-2100 1500);
DISPLAY INVISIBLE (-2100 1500);
FORCEPROP 1 LAST PACK_TYPE 0402LF
J 0
(-2450 1500);
DISPLAY 0.638298 (-2450 1500);
DISPLAY INVISIBLE (-2450 1500);
FORCEPROP 2 LAST CDS_LIB pure_quanta
J 0
(-2300 1375);
PAINT MONO (-2300 1375);
DISPLAY INVISIBLE (-2300 1375);
FORCEPROP 1 LAST PATH I276
J 0
(-2350 1525);
DISPLAY 0.978723 (-2350 1525);
PAINT WHITE (-2350 1525);
DISPLAY INVISIBLE (-2350 1525);
FORCEPROP 1 LAST PART_NUMBER CS03322FB03
J 0
(-2450 1450);
DISPLAY 0.638298 (-2450 1450);
DISPLAY INVISIBLE (-2450 1450);
FORCEADD Q_RES..1
(-2300 1275);
FORCEPROP 1 LAST LOCATION R3482
J 0
(-2575 1275);
DISPLAY 0.787234 (-2575 1275);
FORCEPROP 2 LAST $SEC 1
J 0
(-2350 1475);
DISPLAY 0.680851 (-2350 1475);
PAINT MONO (-2350 1475);
DISPLAY INVISIBLE (-2350 1475);
FORCEPROP 2 LAST CDS_SEC 1
J 0
(-2350 1475);
DISPLAY 1.021277 (-2350 1475);
DISPLAY INVISIBLE (-2350 1475);
FORCEPROP 1 LASTPIN (-2400 1275) $PN 1
J 0
(-2388 1287);
DISPLAY 0.787234 (-2388 1287);
FORCEPROP 1 LASTPIN (-2200 1275) $PN 2
J 0
(-2238 1287);
DISPLAY 0.787234 (-2238 1287);
FORCEPROP 1 LAST VALUE 33.2
J 2
(-2050 1275);
DISPLAY 0.638298 (-2050 1275);
FORCEPROP 1 LAST TOLERANCE 1%
J 0
(-2025 1275);
DISPLAY 0.638298 (-2025 1275);
FORCEPROP 1 LAST MATERIAL CHIP
J 0
(-1950 1275);
DISPLAY 0.638298 (-1950 1275);
FORCEPROP 1 LAST WATTAGE 1/16W
J 2
(-2100 1400);
DISPLAY 0.638298 (-2100 1400);
DISPLAY INVISIBLE (-2100 1400);
FORCEPROP 1 LAST PACK_TYPE 0402LF
J 0
(-2450 1400);
DISPLAY 0.638298 (-2450 1400);
DISPLAY INVISIBLE (-2450 1400);
FORCEPROP 2 LAST CDS_LIB pure_quanta
J 0
(-2300 1275);
PAINT MONO (-2300 1275);
DISPLAY INVISIBLE (-2300 1275);
FORCEPROP 1 LAST PATH I278
J 0
(-2350 1425);
DISPLAY 0.978723 (-2350 1425);
PAINT WHITE (-2350 1425);
DISPLAY INVISIBLE (-2350 1425);
FORCEPROP 1 LAST PART_NUMBER CS03322FB03
J 0
(-2450 1350);
DISPLAY 0.638298 (-2450 1350);
DISPLAY INVISIBLE (-2450 1350);
FORCEADD OFFPAGE..2
(-800 1275);
FORCEPROP 2 LAST $XR0 128 
J 0
(-581 1275);
DISPLAY 0.638298 (-581 1275);
PAINT MONO (-581 1275);
FORCEPROP 2 LAST CDS_LIB standard
J 0
(-800 1275);
DISPLAY INVISIBLE (-800 1275);
FORCEPROP 1 LAST OFFPAGE TRUE
J 0
(-475 1150);
DISPLAY 0.872340 (-475 1150);
PAINT GREEN (-475 1150);
DISPLAY INVISIBLE (-475 1150);
FORCEPROP 1 LAST COMMENT_BODY TRUE
J 0
(-845 1180);
DISPLAY 0.872340 (-845 1180);
PAINT GREEN (-845 1180);
DISPLAY INVISIBLE (-845 1180);
FORCEPROP 2 LAST PATH I279
J 0
(-600 1325);
DISPLAY 0.680851 (-600 1325);
DISPLAY INVISIBLE (-600 1325);
FORCEADD Q_RES..1
(-6725 1425);
FORCEPROP 1 LAST LOCATION R6048
J 0
(-6600 1425);
DISPLAY 0.489362 (-6600 1425);
PAINT SKYBLUE (-6600 1425);
FORCEPROP 0 LAST $SEC 1
J 0
(-6600 1475);
DISPLAY 0.680851 (-6600 1475);
PAINT MONO (-6600 1475);
DISPLAY INVISIBLE (-6600 1475);
FORCEPROP 0 LAST CDS_SEC 1
J 0
(-6600 1475);
DISPLAY 1.021277 (-6600 1475);
DISPLAY INVISIBLE (-6600 1475);
FORCEPROP 1 LASTPIN (-6825 1425) $PN 1
J 0
(-6813 1437);
DISPLAY 0.489362 (-6813 1437);
PAINT MONO (-6813 1437);
FORCEPROP 1 LASTPIN (-6625 1425) $PN 2
J 0
(-6663 1437);
DISPLAY 0.489362 (-6663 1437);
PAINT MONO (-6663 1437);
FORCEPROP 1 LAST VALUE 0
J 2
(-6850 1425);
DISPLAY 0.489362 (-6850 1425);
PAINT SKYBLUE (-6850 1425);
FORCEPROP 1 LAST PACK_TYPE 0402LF
J 2
(-6550 1350);
DISPLAY 0.489362 (-6550 1350);
PAINT SKYBLUE (-6550 1350);
DISPLAY INVISIBLE (-6550 1350);
FORCEPROP 1 LAST TOLERANCE 5%
J 0
(-6850 1400);
DISPLAY 0.489362 (-6850 1400);
PAINT SKYBLUE (-6850 1400);
DISPLAY INVISIBLE (-6850 1400);
FORCEPROP 1 LAST MATERIAL CHIP
J 2
(-6550 1400);
DISPLAY 0.489362 (-6550 1400);
PAINT SKYBLUE (-6550 1400);
DISPLAY INVISIBLE (-6550 1400);
FORCEPROP 1 LAST WATTAGE 1/16W
J 2
(-6800 1350);
DISPLAY 0.489362 (-6800 1350);
PAINT SKYBLUE (-6800 1350);
DISPLAY INVISIBLE (-6800 1350);
FORCEPROP 2 LAST BOM_COST MEM
J 2
(-6700 1575);
DISPLAY 0.744681 (-6700 1575);
PAINT WHITE (-6700 1575);
DISPLAY INVISIBLE (-6700 1575);
FORCEPROP 2 LAST CDS_LIB pure_quanta
J 2
(-6725 1425);
DISPLAY INVISIBLE (-6725 1425);
FORCEPROP 1 LAST PATH I28
J 0
(-6775 1575);
DISPLAY 0.978723 (-6775 1575);
PAINT WHITE (-6775 1575);
DISPLAY INVISIBLE (-6775 1575);
FORCEPROP 1 LAST PART_NUMBER CS00002JB13
J 2
(-6625 1475);
DISPLAY 0.489362 (-6625 1475);
PAINT SKYBLUE (-6625 1475);
DISPLAY INVISIBLE (-6625 1475);
FORCEADD OFFPAGE..2
(-800 1075);
FORCEPROP 2 LAST $XR0 128 
J 0
(-611 1075);
DISPLAY 0.638298 (-611 1075);
PAINT MONO (-611 1075);
FORCEPROP 2 LAST CDS_LIB standard
J 0
(-800 1075);
DISPLAY INVISIBLE (-800 1075);
FORCEPROP 1 LAST OFFPAGE TRUE
J 0
(-475 950);
DISPLAY 0.872340 (-475 950);
PAINT GREEN (-475 950);
DISPLAY INVISIBLE (-475 950);
FORCEPROP 1 LAST COMMENT_BODY TRUE
J 0
(-845 980);
DISPLAY 0.872340 (-845 980);
PAINT GREEN (-845 980);
DISPLAY INVISIBLE (-845 980);
FORCEPROP 2 LAST PATH I280
J 0
(-600 1125);
DISPLAY 0.680851 (-600 1125);
DISPLAY INVISIBLE (-600 1125);
FORCEADD Q_RES..1
(-2300 1075);
FORCEPROP 1 LAST LOCATION R3479
J 0
(-2575 1075);
DISPLAY 0.787234 (-2575 1075);
FORCEPROP 2 LAST $SEC 1
J 0
(-2350 1275);
DISPLAY 0.680851 (-2350 1275);
PAINT MONO (-2350 1275);
DISPLAY INVISIBLE (-2350 1275);
FORCEPROP 2 LAST CDS_SEC 1
J 0
(-2350 1275);
DISPLAY 1.021277 (-2350 1275);
DISPLAY INVISIBLE (-2350 1275);
FORCEPROP 1 LASTPIN (-2400 1075) $PN 1
J 0
(-2388 1087);
DISPLAY 0.787234 (-2388 1087);
FORCEPROP 1 LASTPIN (-2200 1075) $PN 2
J 0
(-2238 1087);
DISPLAY 0.787234 (-2238 1087);
FORCEPROP 1 LAST MATERIAL CHIP
J 0
(-1950 1075);
DISPLAY 0.638298 (-1950 1075);
FORCEPROP 1 LAST TOLERANCE 1%
J 0
(-2025 1075);
DISPLAY 0.638298 (-2025 1075);
FORCEPROP 1 LAST VALUE 33.2
J 2
(-2050 1075);
DISPLAY 0.638298 (-2050 1075);
FORCEPROP 2 LAST CDS_LIB pure_quanta
J 0
(-2300 1075);
PAINT MONO (-2300 1075);
DISPLAY INVISIBLE (-2300 1075);
FORCEPROP 1 LAST PACK_TYPE 0402LF
J 0
(-2450 1200);
DISPLAY 0.638298 (-2450 1200);
DISPLAY INVISIBLE (-2450 1200);
FORCEPROP 1 LAST WATTAGE 1/16W
J 2
(-2100 1200);
DISPLAY 0.638298 (-2100 1200);
DISPLAY INVISIBLE (-2100 1200);
FORCEPROP 1 LAST PATH I281
J 0
(-2350 1225);
DISPLAY 0.978723 (-2350 1225);
PAINT WHITE (-2350 1225);
DISPLAY INVISIBLE (-2350 1225);
FORCEPROP 1 LAST PART_NUMBER CS03322FB03
J 0
(-2450 1150);
DISPLAY 0.638298 (-2450 1150);
DISPLAY INVISIBLE (-2450 1150);
FORCEADD Q_RES..1
(-6725 3175);
FORCEPROP 1 LAST LOCATION R2261
J 0
(-6950 3175);
DISPLAY 0.510638 (-6950 3175);
FORCEPROP 2 LAST $SEC 1
J 0
(-6775 3375);
DISPLAY 0.680851 (-6775 3375);
PAINT MONO (-6775 3375);
DISPLAY INVISIBLE (-6775 3375);
FORCEPROP 2 LAST CDS_SEC 1
J 0
(-6775 3375);
DISPLAY 1.021277 (-6775 3375);
DISPLAY INVISIBLE (-6775 3375);
FORCEPROP 1 LASTPIN (-6825 3175) $PN 1
J 0
(-6813 3187);
DISPLAY 0.638298 (-6813 3187);
FORCEPROP 1 LASTPIN (-6625 3175) $PN 2
J 0
(-6663 3187);
DISPLAY 0.638298 (-6663 3187);
FORCEPROP 1 LAST VALUE 33.2
J 2
(-6500 3175);
DISPLAY 0.404255 (-6500 3175);
FORCEPROP 1 LAST MATERIAL CHIP
J 0
(-6400 3175);
DISPLAY 0.404255 (-6400 3175);
FORCEPROP 1 LAST TOLERANCE 1%
J 0
(-6475 3175);
DISPLAY 0.404255 (-6475 3175);
FORCEPROP 1 LAST WATTAGE 1/16W
J 2
(-6525 3300);
DISPLAY 0.638298 (-6525 3300);
DISPLAY INVISIBLE (-6525 3300);
FORCEPROP 1 LAST PACK_TYPE 0402LF
J 0
(-6875 3300);
DISPLAY 0.638298 (-6875 3300);
DISPLAY INVISIBLE (-6875 3300);
FORCEPROP 2 LAST CDS_LIB pure_quanta
J 0
(-6725 3175);
PAINT MONO (-6725 3175);
DISPLAY INVISIBLE (-6725 3175);
FORCEPROP 1 LAST PATH I284
J 0
(-6775 3325);
DISPLAY 0.978723 (-6775 3325);
PAINT WHITE (-6775 3325);
DISPLAY INVISIBLE (-6775 3325);
FORCEPROP 1 LAST PART_NUMBER CS03322FB03
J 0
(-6875 3250);
DISPLAY 0.638298 (-6875 3250);
DISPLAY INVISIBLE (-6875 3250);
FORCEADD OFFPAGE..2
R 2
(-7800 3175);
FORCEPROP 2 LAST $XR0 128 
J 0
(-8055 3175);
DISPLAY 0.638298 (-8055 3175);
PAINT MONO (-8055 3175);
FORCEPROP 2 LAST CDS_LIB standard
J 0
(-7800 3175);
DISPLAY INVISIBLE (-7800 3175);
FORCEPROP 1 LAST OFFPAGE TRUE
J 2
(-8125 3050);
DISPLAY 0.872340 (-8125 3050);
PAINT GREEN (-8125 3050);
DISPLAY INVISIBLE (-8125 3050);
FORCEPROP 1 LAST COMMENT_BODY TRUE
J 2
(-7755 3080);
DISPLAY 0.872340 (-7755 3080);
PAINT GREEN (-7755 3080);
DISPLAY INVISIBLE (-7755 3080);
FORCEPROP 2 LAST PATH I285
J 0
(-8050 3225);
DISPLAY 0.680851 (-8050 3225);
DISPLAY INVISIBLE (-8050 3225);
FORCEADD Q_RES..1
(-6725 3125);
FORCEPROP 1 LAST LOCATION R3477
J 0
(-6950 3125);
DISPLAY 0.510638 (-6950 3125);
FORCEPROP 2 LAST $SEC 1
J 0
(-6775 3325);
DISPLAY 0.680851 (-6775 3325);
PAINT MONO (-6775 3325);
DISPLAY INVISIBLE (-6775 3325);
FORCEPROP 2 LAST CDS_SEC 1
J 0
(-6775 3325);
DISPLAY 1.021277 (-6775 3325);
DISPLAY INVISIBLE (-6775 3325);
FORCEPROP 1 LASTPIN (-6825 3125) $PN 1
J 0
(-6813 3137);
DISPLAY 0.638298 (-6813 3137);
FORCEPROP 1 LASTPIN (-6625 3125) $PN 2
J 0
(-6663 3137);
DISPLAY 0.638298 (-6663 3137);
FORCEPROP 1 LAST TOLERANCE 1%
J 0
(-6475 3125);
DISPLAY 0.404255 (-6475 3125);
FORCEPROP 1 LAST MATERIAL CHIP
J 0
(-6400 3125);
DISPLAY 0.404255 (-6400 3125);
FORCEPROP 1 LAST VALUE 33.2
J 2
(-6500 3125);
DISPLAY 0.404255 (-6500 3125);
FORCEPROP 1 LAST WATTAGE 1/16W
J 2
(-6525 3250);
DISPLAY 0.638298 (-6525 3250);
DISPLAY INVISIBLE (-6525 3250);
FORCEPROP 1 LAST PACK_TYPE 0402LF
J 0
(-6875 3250);
DISPLAY 0.638298 (-6875 3250);
DISPLAY INVISIBLE (-6875 3250);
FORCEPROP 2 LAST CDS_LIB pure_quanta
J 0
(-6725 3125);
PAINT MONO (-6725 3125);
DISPLAY INVISIBLE (-6725 3125);
FORCEPROP 1 LAST PATH I286
J 0
(-6775 3275);
DISPLAY 0.978723 (-6775 3275);
PAINT WHITE (-6775 3275);
DISPLAY INVISIBLE (-6775 3275);
FORCEPROP 1 LAST PART_NUMBER CS03322FB03
J 0
(-6875 3200);
DISPLAY 0.638298 (-6875 3200);
DISPLAY INVISIBLE (-6875 3200);
FORCEADD OFFPAGE..2
R 2
(-7800 3125);
FORCEPROP 2 LAST $XR0 129 
J 0
(-8055 3125);
DISPLAY 0.638298 (-8055 3125);
PAINT MONO (-8055 3125);
FORCEPROP 2 LAST CDS_LIB standard
J 0
(-7800 3125);
DISPLAY INVISIBLE (-7800 3125);
FORCEPROP 1 LAST OFFPAGE TRUE
J 2
(-8125 3000);
DISPLAY 0.872340 (-8125 3000);
PAINT GREEN (-8125 3000);
DISPLAY INVISIBLE (-8125 3000);
FORCEPROP 1 LAST COMMENT_BODY TRUE
J 2
(-7755 3030);
DISPLAY 0.872340 (-7755 3030);
PAINT GREEN (-7755 3030);
DISPLAY INVISIBLE (-7755 3030);
FORCEPROP 2 LAST PATH I287
J 0
(-7750 3200);
DISPLAY 0.680851 (-7750 3200);
DISPLAY INVISIBLE (-7750 3200);
FORCEADD Q_RES..1
(-6725 2775);
FORCEPROP 1 LAST LOCATION R3478
J 0
(-6950 2775);
DISPLAY 0.510638 (-6950 2775);
FORCEPROP 2 LAST $SEC 1
J 0
(-6775 2975);
DISPLAY 0.680851 (-6775 2975);
PAINT MONO (-6775 2975);
DISPLAY INVISIBLE (-6775 2975);
FORCEPROP 2 LAST CDS_SEC 1
J 0
(-6775 2975);
DISPLAY 1.021277 (-6775 2975);
DISPLAY INVISIBLE (-6775 2975);
FORCEPROP 1 LASTPIN (-6825 2775) $PN 1
J 0
(-6813 2787);
DISPLAY 0.638298 (-6813 2787);
FORCEPROP 1 LASTPIN (-6625 2775) $PN 2
J 0
(-6663 2787);
DISPLAY 0.638298 (-6663 2787);
FORCEPROP 1 LAST MATERIAL CHIP
J 0
(-6400 2775);
DISPLAY 0.404255 (-6400 2775);
FORCEPROP 1 LAST VALUE 33.2
J 2
(-6500 2775);
DISPLAY 0.404255 (-6500 2775);
FORCEPROP 1 LAST TOLERANCE 1%
J 0
(-6475 2775);
DISPLAY 0.404255 (-6475 2775);
FORCEPROP 1 LAST PACK_TYPE 0402LF
J 0
(-6875 2900);
DISPLAY 0.638298 (-6875 2900);
DISPLAY INVISIBLE (-6875 2900);
FORCEPROP 1 LAST WATTAGE 1/16W
J 2
(-6525 2900);
DISPLAY 0.638298 (-6525 2900);
DISPLAY INVISIBLE (-6525 2900);
FORCEPROP 2 LAST CDS_LIB pure_quanta
J 0
(-6725 2775);
PAINT MONO (-6725 2775);
DISPLAY INVISIBLE (-6725 2775);
FORCEPROP 1 LAST PATH I288
J 0
(-6775 2925);
DISPLAY 0.978723 (-6775 2925);
PAINT WHITE (-6775 2925);
DISPLAY INVISIBLE (-6775 2925);
FORCEPROP 1 LAST PART_NUMBER CS03322FB03
J 0
(-6875 2850);
DISPLAY 0.638298 (-6875 2850);
DISPLAY INVISIBLE (-6875 2850);
FORCEADD OFFPAGE..2
R 2
(-7800 2775);
FORCEPROP 2 LAST $XR0 129 
J 0
(-8055 2775);
DISPLAY 0.638298 (-8055 2775);
PAINT MONO (-8055 2775);
FORCEPROP 2 LAST CDS_LIB standard
J 0
(-7800 2775);
DISPLAY INVISIBLE (-7800 2775);
FORCEPROP 1 LAST OFFPAGE TRUE
J 2
(-8125 2650);
DISPLAY 0.872340 (-8125 2650);
PAINT GREEN (-8125 2650);
DISPLAY INVISIBLE (-8125 2650);
FORCEPROP 1 LAST COMMENT_BODY TRUE
J 2
(-7755 2680);
DISPLAY 0.872340 (-7755 2680);
PAINT GREEN (-7755 2680);
DISPLAY INVISIBLE (-7755 2680);
FORCEPROP 2 LAST PATH I289
J 0
(-7750 2850);
DISPLAY 0.680851 (-7750 2850);
DISPLAY INVISIBLE (-7750 2850);
FORCEADD Q_RES..1
(-6725 1325);
FORCEPROP 1 LAST LOCATION R1282
J 0
(-6600 1325);
DISPLAY 0.489362 (-6600 1325);
PAINT SKYBLUE (-6600 1325);
FORCEPROP 0 LAST $SEC 1
J 0
(-6650 1375);
DISPLAY 0.680851 (-6650 1375);
PAINT MONO (-6650 1375);
DISPLAY INVISIBLE (-6650 1375);
FORCEPROP 0 LAST CDS_SEC 1
J 0
(-6650 1375);
DISPLAY 0.680851 (-6650 1375);
DISPLAY INVISIBLE (-6650 1375);
FORCEPROP 1 LASTPIN (-6825 1325) $PN 1
J 0
(-6813 1337);
DISPLAY 0.489362 (-6813 1337);
PAINT MONO (-6813 1337);
FORCEPROP 1 LASTPIN (-6625 1325) $PN 2
J 0
(-6663 1337);
DISPLAY 0.489362 (-6663 1337);
PAINT MONO (-6663 1337);
FORCEPROP 1 LAST VALUE 33
J 2
(-6850 1325);
DISPLAY 0.489362 (-6850 1325);
PAINT SKYBLUE (-6850 1325);
FORCEPROP 2 LAST BOM_COST MEM
J 2
(-6700 1475);
DISPLAY 0.744681 (-6700 1475);
PAINT WHITE (-6700 1475);
DISPLAY INVISIBLE (-6700 1475);
FORCEPROP 1 LAST WATTAGE 1/16W
J 2
(-6800 1250);
DISPLAY 0.489362 (-6800 1250);
PAINT SKYBLUE (-6800 1250);
DISPLAY INVISIBLE (-6800 1250);
FORCEPROP 1 LAST MATERIAL CHIP
J 2
(-6550 1300);
DISPLAY 0.489362 (-6550 1300);
PAINT SKYBLUE (-6550 1300);
DISPLAY INVISIBLE (-6550 1300);
FORCEPROP 1 LAST TOLERANCE 5%
J 0
(-6850 1300);
DISPLAY 0.489362 (-6850 1300);
PAINT SKYBLUE (-6850 1300);
DISPLAY INVISIBLE (-6850 1300);
FORCEPROP 1 LAST PACK_TYPE 0402LF
J 2
(-6550 1250);
DISPLAY 0.489362 (-6550 1250);
PAINT SKYBLUE (-6550 1250);
DISPLAY INVISIBLE (-6550 1250);
FORCEPROP 2 LAST CDS_LIB pure_quanta
J 0
(-6725 1325);
DISPLAY INVISIBLE (-6725 1325);
FORCEPROP 1 LAST PATH I29
J 0
(-6775 1475);
DISPLAY 0.978723 (-6775 1475);
PAINT WHITE (-6775 1475);
DISPLAY INVISIBLE (-6775 1475);
FORCEPROP 1 LAST PART_NUMBER CS03302JB10
J 2
(-6625 1375);
DISPLAY 0.489362 (-6625 1375);
PAINT SKYBLUE (-6625 1375);
DISPLAY INVISIBLE (-6625 1375);
FORCEADD Q_RES..1
(-6725 2575);
FORCEPROP 1 LAST LOCATION R3483
J 0
(-6950 2575);
DISPLAY 0.510638 (-6950 2575);
FORCEPROP 2 LAST $SEC 1
J 0
(-6775 2775);
DISPLAY 0.680851 (-6775 2775);
PAINT MONO (-6775 2775);
DISPLAY INVISIBLE (-6775 2775);
FORCEPROP 2 LAST CDS_SEC 1
J 0
(-6775 2775);
DISPLAY 1.021277 (-6775 2775);
DISPLAY INVISIBLE (-6775 2775);
FORCEPROP 1 LASTPIN (-6825 2575) $PN 1
J 0
(-6813 2587);
DISPLAY 0.638298 (-6813 2587);
FORCEPROP 1 LASTPIN (-6625 2575) $PN 2
J 0
(-6663 2587);
DISPLAY 0.638298 (-6663 2587);
FORCEPROP 1 LAST VALUE 33.2
J 2
(-6500 2575);
DISPLAY 0.404255 (-6500 2575);
FORCEPROP 1 LAST TOLERANCE 1%
J 0
(-6475 2575);
DISPLAY 0.404255 (-6475 2575);
FORCEPROP 1 LAST MATERIAL CHIP
J 0
(-6400 2575);
DISPLAY 0.404255 (-6400 2575);
FORCEPROP 1 LAST WATTAGE 1/16W
J 2
(-6525 2700);
DISPLAY 0.638298 (-6525 2700);
DISPLAY INVISIBLE (-6525 2700);
FORCEPROP 1 LAST PACK_TYPE 0402LF
J 0
(-6875 2700);
DISPLAY 0.638298 (-6875 2700);
DISPLAY INVISIBLE (-6875 2700);
FORCEPROP 2 LAST CDS_LIB pure_quanta
J 0
(-6725 2575);
PAINT MONO (-6725 2575);
DISPLAY INVISIBLE (-6725 2575);
FORCEPROP 1 LAST PATH I290
J 0
(-6775 2725);
DISPLAY 0.978723 (-6775 2725);
PAINT WHITE (-6775 2725);
DISPLAY INVISIBLE (-6775 2725);
FORCEPROP 1 LAST PART_NUMBER CS03322FB03
J 0
(-6875 2650);
DISPLAY 0.638298 (-6875 2650);
DISPLAY INVISIBLE (-6875 2650);
FORCEADD OFFPAGE..2
R 2
(-7800 2575);
FORCEPROP 2 LAST $XR0 129 
J 0
(-8055 2575);
DISPLAY 0.638298 (-8055 2575);
PAINT MONO (-8055 2575);
FORCEPROP 2 LAST CDS_LIB standard
J 0
(-7800 2575);
DISPLAY INVISIBLE (-7800 2575);
FORCEPROP 1 LAST OFFPAGE TRUE
J 2
(-8125 2450);
DISPLAY 0.872340 (-8125 2450);
PAINT GREEN (-8125 2450);
DISPLAY INVISIBLE (-8125 2450);
FORCEPROP 1 LAST COMMENT_BODY TRUE
J 2
(-7755 2480);
DISPLAY 0.872340 (-7755 2480);
PAINT GREEN (-7755 2480);
DISPLAY INVISIBLE (-7755 2480);
FORCEPROP 2 LAST PATH I291
J 0
(-7750 2650);
DISPLAY 0.680851 (-7750 2650);
DISPLAY INVISIBLE (-7750 2650);
FORCEADD OFFPAGE..2
R 2
(-7800 2525);
FORCEPROP 2 LAST $XR0 130 
J 0
(-8055 2525);
DISPLAY 0.638298 (-8055 2525);
PAINT MONO (-8055 2525);
FORCEPROP 2 LAST CDS_LIB standard
J 0
(-7800 2525);
DISPLAY INVISIBLE (-7800 2525);
FORCEPROP 1 LAST OFFPAGE TRUE
J 2
(-8125 2400);
DISPLAY 0.872340 (-8125 2400);
PAINT GREEN (-8125 2400);
DISPLAY INVISIBLE (-8125 2400);
FORCEPROP 1 LAST COMMENT_BODY TRUE
J 2
(-7755 2430);
DISPLAY 0.872340 (-7755 2430);
PAINT GREEN (-7755 2430);
DISPLAY INVISIBLE (-7755 2430);
FORCEPROP 2 LAST PATH I292
J 0
(-7750 2600);
DISPLAY 0.680851 (-7750 2600);
DISPLAY INVISIBLE (-7750 2600);
FORCEADD Q_RES..1
(-6725 2525);
FORCEPROP 1 LAST LOCATION R2845
J 0
(-6950 2525);
DISPLAY 0.510638 (-6950 2525);
FORCEPROP 2 LAST $SEC 1
J 0
(-6775 2725);
DISPLAY 0.680851 (-6775 2725);
PAINT MONO (-6775 2725);
DISPLAY INVISIBLE (-6775 2725);
FORCEPROP 2 LAST CDS_SEC 1
J 0
(-6775 2725);
DISPLAY 1.021277 (-6775 2725);
DISPLAY INVISIBLE (-6775 2725);
FORCEPROP 1 LASTPIN (-6825 2525) $PN 1
J 0
(-6813 2537);
DISPLAY 0.638298 (-6813 2537);
FORCEPROP 1 LASTPIN (-6625 2525) $PN 2
J 0
(-6663 2537);
DISPLAY 0.638298 (-6663 2537);
FORCEPROP 1 LAST VALUE 33.2
J 2
(-6500 2525);
DISPLAY 0.404255 (-6500 2525);
FORCEPROP 1 LAST MATERIAL CHIP
J 0
(-6400 2525);
DISPLAY 0.404255 (-6400 2525);
FORCEPROP 1 LAST TOLERANCE 1%
J 0
(-6475 2525);
DISPLAY 0.404255 (-6475 2525);
FORCEPROP 2 LAST CDS_LIB pure_quanta
J 0
(-6725 2525);
PAINT MONO (-6725 2525);
DISPLAY INVISIBLE (-6725 2525);
FORCEPROP 1 LAST PACK_TYPE 0402LF
J 0
(-6875 2650);
DISPLAY 0.638298 (-6875 2650);
DISPLAY INVISIBLE (-6875 2650);
FORCEPROP 1 LAST WATTAGE 1/16W
J 2
(-6525 2650);
DISPLAY 0.638298 (-6525 2650);
DISPLAY INVISIBLE (-6525 2650);
FORCEPROP 1 LAST PATH I293
J 0
(-6775 2675);
DISPLAY 0.978723 (-6775 2675);
PAINT WHITE (-6775 2675);
DISPLAY INVISIBLE (-6775 2675);
FORCEPROP 1 LAST PART_NUMBER CS03322FB03
J 0
(-6875 2600);
DISPLAY 0.638298 (-6875 2600);
DISPLAY INVISIBLE (-6875 2600);
FORCEADD Q_RES..1
(-6725 2275);
FORCEPROP 1 LAST LOCATION R2262
J 0
(-6950 2275);
DISPLAY 0.510638 (-6950 2275);
FORCEPROP 2 LAST $SEC 1
J 0
(-6775 2475);
DISPLAY 0.680851 (-6775 2475);
PAINT MONO (-6775 2475);
DISPLAY INVISIBLE (-6775 2475);
FORCEPROP 2 LAST CDS_SEC 1
J 0
(-6775 2475);
DISPLAY 1.021277 (-6775 2475);
DISPLAY INVISIBLE (-6775 2475);
FORCEPROP 1 LASTPIN (-6825 2275) $PN 1
J 0
(-6813 2287);
DISPLAY 0.638298 (-6813 2287);
FORCEPROP 1 LASTPIN (-6625 2275) $PN 2
J 0
(-6663 2287);
DISPLAY 0.638298 (-6663 2287);
FORCEPROP 1 LAST VALUE 33.2
J 2
(-6500 2275);
DISPLAY 0.404255 (-6500 2275);
FORCEPROP 1 LAST TOLERANCE 1%
J 0
(-6475 2275);
DISPLAY 0.404255 (-6475 2275);
FORCEPROP 1 LAST MATERIAL CHIP
J 0
(-6400 2275);
DISPLAY 0.404255 (-6400 2275);
FORCEPROP 2 LAST CDS_LIB pure_quanta
J 0
(-6725 2275);
PAINT MONO (-6725 2275);
DISPLAY INVISIBLE (-6725 2275);
FORCEPROP 1 LAST PACK_TYPE 0402LF
J 0
(-6875 2400);
DISPLAY 0.638298 (-6875 2400);
DISPLAY INVISIBLE (-6875 2400);
FORCEPROP 1 LAST WATTAGE 1/16W
J 2
(-6525 2400);
DISPLAY 0.638298 (-6525 2400);
DISPLAY INVISIBLE (-6525 2400);
FORCEPROP 1 LAST PATH I294
J 0
(-6775 2425);
DISPLAY 0.978723 (-6775 2425);
PAINT WHITE (-6775 2425);
DISPLAY INVISIBLE (-6775 2425);
FORCEPROP 1 LAST PART_NUMBER CS03322FB03
J 0
(-6875 2350);
DISPLAY 0.638298 (-6875 2350);
DISPLAY INVISIBLE (-6875 2350);
FORCEADD Q_RES..1
(-6725 2225);
FORCEPROP 1 LAST LOCATION R4608
J 0
(-6950 2225);
DISPLAY 0.510638 (-6950 2225);
FORCEPROP 2 LAST $SEC 1
J 0
(-6775 2425);
DISPLAY 0.680851 (-6775 2425);
PAINT MONO (-6775 2425);
DISPLAY INVISIBLE (-6775 2425);
FORCEPROP 2 LAST CDS_SEC 1
J 0
(-6775 2425);
DISPLAY 1.021277 (-6775 2425);
DISPLAY INVISIBLE (-6775 2425);
FORCEPROP 1 LASTPIN (-6825 2225) $PN 1
J 0
(-6813 2237);
DISPLAY 0.638298 (-6813 2237);
FORCEPROP 1 LASTPIN (-6625 2225) $PN 2
J 0
(-6663 2237);
DISPLAY 0.638298 (-6663 2237);
FORCEPROP 1 LAST MATERIAL CHIP
J 0
(-6400 2225);
DISPLAY 0.404255 (-6400 2225);
FORCEPROP 1 LAST VALUE 33.2
J 2
(-6500 2225);
DISPLAY 0.404255 (-6500 2225);
FORCEPROP 1 LAST TOLERANCE 1%
J 0
(-6475 2225);
DISPLAY 0.404255 (-6475 2225);
FORCEPROP 2 LAST CDS_LIB pure_quanta
J 0
(-6725 2225);
PAINT MONO (-6725 2225);
DISPLAY INVISIBLE (-6725 2225);
FORCEPROP 1 LAST PACK_TYPE 0402LF
J 0
(-6875 2350);
DISPLAY 0.638298 (-6875 2350);
DISPLAY INVISIBLE (-6875 2350);
FORCEPROP 1 LAST WATTAGE 1/16W
J 2
(-6525 2350);
DISPLAY 0.638298 (-6525 2350);
DISPLAY INVISIBLE (-6525 2350);
FORCEPROP 1 LAST PATH I295
J 0
(-6775 2375);
DISPLAY 0.978723 (-6775 2375);
PAINT WHITE (-6775 2375);
DISPLAY INVISIBLE (-6775 2375);
FORCEPROP 1 LAST PART_NUMBER CS03322FB03
J 0
(-6875 2300);
DISPLAY 0.638298 (-6875 2300);
DISPLAY INVISIBLE (-6875 2300);
FORCEADD OFFPAGE..2
R 2
(-7800 2275);
FORCEPROP 2 LAST $XR0 130 
J 0
(-8055 2275);
DISPLAY 0.638298 (-8055 2275);
PAINT MONO (-8055 2275);
FORCEPROP 2 LAST CDS_LIB standard
J 0
(-7800 2275);
DISPLAY INVISIBLE (-7800 2275);
FORCEPROP 1 LAST OFFPAGE TRUE
J 2
(-8125 2150);
DISPLAY 0.872340 (-8125 2150);
PAINT GREEN (-8125 2150);
DISPLAY INVISIBLE (-8125 2150);
FORCEPROP 1 LAST COMMENT_BODY TRUE
J 2
(-7755 2180);
DISPLAY 0.872340 (-7755 2180);
PAINT GREEN (-7755 2180);
DISPLAY INVISIBLE (-7755 2180);
FORCEPROP 2 LAST PATH I296
J 0
(-7750 2350);
DISPLAY 0.680851 (-7750 2350);
DISPLAY INVISIBLE (-7750 2350);
FORCEADD OFFPAGE..2
R 2
(-7800 2225);
FORCEPROP 2 LAST $XR0 130 
J 0
(-8055 2225);
DISPLAY 0.638298 (-8055 2225);
PAINT MONO (-8055 2225);
FORCEPROP 2 LAST CDS_LIB standard
J 0
(-7800 2225);
DISPLAY INVISIBLE (-7800 2225);
FORCEPROP 1 LAST OFFPAGE TRUE
J 2
(-8125 2100);
DISPLAY 0.872340 (-8125 2100);
PAINT GREEN (-8125 2100);
DISPLAY INVISIBLE (-8125 2100);
FORCEPROP 1 LAST COMMENT_BODY TRUE
J 2
(-7755 2130);
DISPLAY 0.872340 (-7755 2130);
PAINT GREEN (-7755 2130);
DISPLAY INVISIBLE (-7755 2130);
FORCEPROP 2 LAST PATH I297
J 0
(-7750 2300);
DISPLAY 0.680851 (-7750 2300);
DISPLAY INVISIBLE (-7750 2300);
FORCEADD Q_RES..2
(-275 1125);
FORCEPROP 1 LAST LOCATION R6085
J 0
(-250 1125);
DISPLAY 0.638298 (-250 1125);
FORCEPROP 0 LAST $SEC 1
J 0
(-250 1175);
DISPLAY 0.680851 (-250 1175);
PAINT MONO (-250 1175);
DISPLAY INVISIBLE (-250 1175);
FORCEPROP 0 LAST CDS_SEC 1
J 0
(-250 1175);
DISPLAY 0.680851 (-250 1175);
DISPLAY INVISIBLE (-250 1175);
FORCEPROP 1 LASTPIN (-275 1225) $PN 1
J 0
(-270 1187);
DISPLAY 0.787234 (-270 1187);
PAINT MONO (-270 1187);
FORCEPROP 1 LASTPIN (-275 1025) $PN 2
J 0
(-270 1035);
DISPLAY 0.787234 (-270 1035);
PAINT MONO (-270 1035);
FORCEPROP 1 LAST WATTAGE 1/16W
J 0
(-450 800);
DISPLAY 0.638298 (-450 800);
FORCEPROP 1 LAST MATERIAL CHIP
J 0
(-450 750);
DISPLAY 0.638298 (-450 750);
FORCEPROP 1 LAST TOLERANCE 1%
J 0
(-445 850);
DISPLAY 0.638298 (-445 850);
FORCEPROP 1 LAST VALUE 10K
J 0
(-250 1075);
DISPLAY 0.638298 (-250 1075);
FORCEPROP 1 LAST PACK_TYPE 0402LF
J 0
(-450 650);
DISPLAY 0.638298 (-450 650);
FORCEPROP 2 LAST CDS_LIB pure_quanta
J 0
(-275 1125);
DISPLAY INVISIBLE (-275 1125);
FORCEPROP 1 LAST PATH I298
J 0
(-225 1300);
DISPLAY 0.978723 (-225 1300);
PAINT WHITE (-225 1300);
DISPLAY INVISIBLE (-225 1300);
FORCEPROP 1 LAST PART_NUMBER CS31002FB08
J 0
(-450 700);
DISPLAY 0.638298 (-450 700);
DISPLAY INVISIBLE (-450 700);
FORCEADD UNIVERSAL_POWER..1
R 2
(-275 1350);
FORCEPROP 3 LASTPIN (-275 1300) SIG_NAME P3V3_AUX\g
J 0
(-265 1310);
DISPLAY 0.659574 (-265 1310);
PAINT MONO (-265 1310);
DISPLAY INVISIBLE (-265 1310);
FORCEPROP 1 LAST HDL_POWER P3V3_AUX
J 1
(-275 1400);
DISPLAY 0.489362 (-275 1400);
PAINT GREEN (-275 1400);
FORCEPROP 2 LAST CDS_LIB pure_quanta_power
J 0
(-275 1350);
DISPLAY INVISIBLE (-275 1350);
FORCEPROP 1 LAST PATH I299
J 2
(-325 1375);
DISPLAY 0.872340 (-325 1375);
PAINT AQUA (-325 1375);
DISPLAY INVISIBLE (-325 1375);
FORCEADD Q_RES..1
(-6725 1525);
FORCEPROP 1 LAST LOCATION R283
J 0
(-6600 1525);
DISPLAY 0.489362 (-6600 1525);
PAINT SKYBLUE (-6600 1525);
FORCEPROP 0 LAST $SEC 1
J 0
(-6600 1575);
DISPLAY 0.680851 (-6600 1575);
PAINT MONO (-6600 1575);
DISPLAY INVISIBLE (-6600 1575);
FORCEPROP 0 LAST CDS_SEC 1
J 0
(-6600 1575);
DISPLAY 1.021277 (-6600 1575);
DISPLAY INVISIBLE (-6600 1575);
FORCEPROP 1 LASTPIN (-6825 1525) $PN 1
J 0
(-6813 1537);
DISPLAY 0.489362 (-6813 1537);
PAINT MONO (-6813 1537);
FORCEPROP 1 LASTPIN (-6625 1525) $PN 2
J 0
(-6663 1537);
DISPLAY 0.489362 (-6663 1537);
PAINT MONO (-6663 1537);
FORCEPROP 1 LAST VALUE 0
J 2
(-6850 1525);
DISPLAY 0.489362 (-6850 1525);
PAINT SKYBLUE (-6850 1525);
FORCEPROP 2 LAST CDS_LIB pure_quanta
J 2
(-6725 1525);
DISPLAY INVISIBLE (-6725 1525);
FORCEPROP 2 LAST BOM_COST MEM
J 2
(-6700 1675);
DISPLAY 0.744681 (-6700 1675);
PAINT WHITE (-6700 1675);
DISPLAY INVISIBLE (-6700 1675);
FORCEPROP 1 LAST WATTAGE 1/16W
J 2
(-6800 1450);
DISPLAY 0.489362 (-6800 1450);
PAINT SKYBLUE (-6800 1450);
DISPLAY INVISIBLE (-6800 1450);
FORCEPROP 1 LAST MATERIAL CHIP
J 2
(-6550 1500);
DISPLAY 0.489362 (-6550 1500);
PAINT SKYBLUE (-6550 1500);
DISPLAY INVISIBLE (-6550 1500);
FORCEPROP 1 LAST TOLERANCE 5%
J 0
(-6850 1500);
DISPLAY 0.489362 (-6850 1500);
PAINT SKYBLUE (-6850 1500);
DISPLAY INVISIBLE (-6850 1500);
FORCEPROP 1 LAST PACK_TYPE 0402LF
J 2
(-6550 1450);
DISPLAY 0.489362 (-6550 1450);
PAINT SKYBLUE (-6550 1450);
DISPLAY INVISIBLE (-6550 1450);
FORCEPROP 1 LAST PATH I30
J 0
(-6775 1675);
DISPLAY 0.978723 (-6775 1675);
PAINT WHITE (-6775 1675);
DISPLAY INVISIBLE (-6775 1675);
FORCEPROP 1 LAST PART_NUMBER CS00002JB13
J 2
(-6625 1575);
DISPLAY 0.489362 (-6625 1575);
PAINT SKYBLUE (-6625 1575);
DISPLAY INVISIBLE (-6625 1575);
FORCEADD Q_RES..1
(-6725 675);
FORCEPROP 1 LAST LOCATION R4557
J 0
(-6950 675);
DISPLAY 0.510638 (-6950 675);
FORCEPROP 2 LAST $SEC 1
J 0
(-6775 875);
DISPLAY 0.680851 (-6775 875);
PAINT MONO (-6775 875);
DISPLAY INVISIBLE (-6775 875);
FORCEPROP 2 LAST CDS_SEC 1
J 0
(-6775 875);
DISPLAY 1.021277 (-6775 875);
DISPLAY INVISIBLE (-6775 875);
FORCEPROP 1 LASTPIN (-6825 675) $PN 1
J 0
(-6813 687);
DISPLAY 0.638298 (-6813 687);
FORCEPROP 1 LASTPIN (-6625 675) $PN 2
J 0
(-6663 687);
DISPLAY 0.638298 (-6663 687);
FORCEPROP 1 LAST TOLERANCE 1%
J 0
(-6475 675);
DISPLAY 0.404255 (-6475 675);
FORCEPROP 1 LAST VALUE 33.2
J 2
(-6500 675);
DISPLAY 0.404255 (-6500 675);
FORCEPROP 1 LAST MATERIAL CHIP
J 0
(-6400 675);
DISPLAY 0.404255 (-6400 675);
DISPLAY INVISIBLE (-6400 675);
FORCEPROP 2 LAST CDS_LIB pure_quanta
J 0
(-6725 675);
PAINT MONO (-6725 675);
DISPLAY INVISIBLE (-6725 675);
FORCEPROP 1 LAST PACK_TYPE 0402LF
J 0
(-6875 800);
DISPLAY 0.638298 (-6875 800);
DISPLAY INVISIBLE (-6875 800);
FORCEPROP 1 LAST WATTAGE 1/16W
J 2
(-6525 800);
DISPLAY 0.638298 (-6525 800);
DISPLAY INVISIBLE (-6525 800);
FORCEPROP 1 LAST PATH I301
J 0
(-6775 825);
DISPLAY 0.978723 (-6775 825);
PAINT WHITE (-6775 825);
DISPLAY INVISIBLE (-6775 825);
FORCEPROP 1 LAST PART_NUMBER CS03322FB03
J 0
(-6875 750);
DISPLAY 0.638298 (-6875 750);
DISPLAY INVISIBLE (-6875 750);
FORCEADD OFFPAGE..1
(-7800 675);
FORCEPROP 2 LAST $XR0 242 
J 0
(-8052 675);
DISPLAY 0.638298 (-8052 675);
PAINT MONO (-8052 675);
FORCEPROP 2 LAST CDS_LIB standard
J 0
(-7800 675);
DISPLAY INVISIBLE (-7800 675);
FORCEPROP 1 LAST OFFPAGE TRUE
J 0
(-7475 550);
DISPLAY 0.872340 (-7475 550);
PAINT GREEN (-7475 550);
DISPLAY INVISIBLE (-7475 550);
FORCEPROP 1 LAST COMMENT_BODY TRUE
J 0
(-7675 575);
DISPLAY 0.872340 (-7675 575);
PAINT GREEN (-7675 575);
DISPLAY INVISIBLE (-7675 575);
FORCEPROP 2 LAST PATH I302
J 0
(-8075 725);
DISPLAY 0.680851 (-8075 725);
DISPLAY INVISIBLE (-8075 725);
FORCEADD Q_RES..1
(-3225 4125);
FORCEPROP 1 LAST LOCATION R195
J 0
(-3100 4125);
DISPLAY 0.489362 (-3100 4125);
PAINT SKYBLUE (-3100 4125);
FORCEPROP 0 LAST $SEC 1
J 2
(-3100 4175);
DISPLAY 0.680851 (-3100 4175);
PAINT MONO (-3100 4175);
DISPLAY INVISIBLE (-3100 4175);
FORCEPROP 0 LAST CDS_SEC 1
J 2
(-3100 4175);
DISPLAY 1.021277 (-3100 4175);
DISPLAY INVISIBLE (-3100 4175);
FORCEPROP 1 LASTPIN (-3325 4125) $PN 1
J 0
(-3313 4137);
DISPLAY 0.489362 (-3313 4137);
PAINT MONO (-3313 4137);
FORCEPROP 1 LASTPIN (-3125 4125) $PN 2
J 0
(-3163 4137);
DISPLAY 0.489362 (-3163 4137);
PAINT MONO (-3163 4137);
FORCEPROP 1 LAST VALUE 33
J 2
(-3350 4125);
DISPLAY 0.489362 (-3350 4125);
PAINT SKYBLUE (-3350 4125);
FORCEPROP 2 LAST CDS_LIB pure_quanta
J 2
(-3225 4125);
DISPLAY INVISIBLE (-3225 4125);
FORCEPROP 2 LAST BOM_COST MEM
J 2
(-3200 4275);
DISPLAY 0.744681 (-3200 4275);
PAINT WHITE (-3200 4275);
DISPLAY INVISIBLE (-3200 4275);
FORCEPROP 1 LAST WATTAGE 1/16W
J 2
(-3300 4050);
DISPLAY 0.489362 (-3300 4050);
PAINT SKYBLUE (-3300 4050);
DISPLAY INVISIBLE (-3300 4050);
FORCEPROP 1 LAST MATERIAL CHIP
J 2
(-3050 4100);
DISPLAY 0.489362 (-3050 4100);
PAINT SKYBLUE (-3050 4100);
DISPLAY INVISIBLE (-3050 4100);
FORCEPROP 1 LAST TOLERANCE 5%
J 0
(-3350 4100);
DISPLAY 0.489362 (-3350 4100);
PAINT SKYBLUE (-3350 4100);
DISPLAY INVISIBLE (-3350 4100);
FORCEPROP 1 LAST PACK_TYPE 0402LF
J 2
(-3050 4050);
DISPLAY 0.489362 (-3050 4050);
PAINT SKYBLUE (-3050 4050);
DISPLAY INVISIBLE (-3050 4050);
FORCEPROP 1 LAST PATH I303
J 0
(-3275 4275);
DISPLAY 0.978723 (-3275 4275);
PAINT WHITE (-3275 4275);
DISPLAY INVISIBLE (-3275 4275);
FORCEPROP 1 LAST PART_NUMBER CS03302JB10
J 2
(-3125 4175);
DISPLAY 0.489362 (-3125 4175);
PAINT SKYBLUE (-3125 4175);
DISPLAY INVISIBLE (-3125 4175);
FORCEADD OFFPAGE..5
(-7800 1025);
FORCEPROP 2 LAST $XR0 256 
J 0
(-8055 1025);
DISPLAY 0.638298 (-8055 1025);
PAINT MONO (-8055 1025);
FORCEPROP 2 LAST CDS_LIB standard
J 0
(-7800 1025);
DISPLAY INVISIBLE (-7800 1025);
FORCEPROP 1 LAST OFFPAGE TRUE
J 0
(-7475 900);
DISPLAY 0.872340 (-7475 900);
PAINT GREEN (-7475 900);
DISPLAY INVISIBLE (-7475 900);
FORCEPROP 1 LAST COMMENT_BODY TRUE
J 0
(-7700 950);
DISPLAY 0.872340 (-7700 950);
PAINT GREEN (-7700 950);
DISPLAY INVISIBLE (-7700 950);
FORCEPROP 2 LAST PATH I304
J 0
(-8050 1075);
DISPLAY 0.680851 (-8050 1075);
DISPLAY INVISIBLE (-8050 1075);
FORCEADD OFFPAGE..5
(-7800 775);
FORCEPROP 2 LAST $XR0 256 
J 0
(-8055 775);
DISPLAY 0.638298 (-8055 775);
PAINT MONO (-8055 775);
FORCEPROP 2 LAST CDS_LIB standard
J 0
(-7800 775);
DISPLAY INVISIBLE (-7800 775);
FORCEPROP 1 LAST OFFPAGE TRUE
J 0
(-7475 650);
DISPLAY 0.872340 (-7475 650);
PAINT GREEN (-7475 650);
DISPLAY INVISIBLE (-7475 650);
FORCEPROP 1 LAST COMMENT_BODY TRUE
J 0
(-7700 700);
DISPLAY 0.872340 (-7700 700);
PAINT GREEN (-7700 700);
DISPLAY INVISIBLE (-7700 700);
FORCEPROP 2 LAST PATH I305
J 0
(-7750 850);
DISPLAY 0.680851 (-7750 850);
DISPLAY INVISIBLE (-7750 850);
FORCEADD OFFPAGE..5
(-7800 725);
FORCEPROP 2 LAST $XR0 256 
J 0
(-8055 725);
DISPLAY 0.638298 (-8055 725);
PAINT MONO (-8055 725);
FORCEPROP 2 LAST CDS_LIB standard
J 0
(-7800 725);
DISPLAY INVISIBLE (-7800 725);
FORCEPROP 1 LAST OFFPAGE TRUE
J 0
(-7475 600);
DISPLAY 0.872340 (-7475 600);
PAINT GREEN (-7475 600);
DISPLAY INVISIBLE (-7475 600);
FORCEPROP 1 LAST COMMENT_BODY TRUE
J 0
(-7700 650);
DISPLAY 0.872340 (-7700 650);
PAINT GREEN (-7700 650);
DISPLAY INVISIBLE (-7700 650);
FORCEPROP 2 LAST PATH I306
J 0
(-7750 800);
DISPLAY 0.680851 (-7750 800);
DISPLAY INVISIBLE (-7750 800);
FORCEADD OFFPAGE..5
(-7800 875);
FORCEPROP 2 LAST $XR0 256 
J 0
(-8055 875);
DISPLAY 0.638298 (-8055 875);
PAINT MONO (-8055 875);
FORCEPROP 2 LAST CDS_LIB standard
J 0
(-7800 875);
DISPLAY INVISIBLE (-7800 875);
FORCEPROP 1 LAST OFFPAGE TRUE
J 0
(-7475 750);
DISPLAY 0.872340 (-7475 750);
PAINT GREEN (-7475 750);
DISPLAY INVISIBLE (-7475 750);
FORCEPROP 1 LAST COMMENT_BODY TRUE
J 0
(-7700 800);
DISPLAY 0.872340 (-7700 800);
PAINT GREEN (-7700 800);
DISPLAY INVISIBLE (-7700 800);
FORCEPROP 2 LAST PATH I308
J 0
(-7750 950);
DISPLAY 0.680851 (-7750 950);
DISPLAY INVISIBLE (-7750 950);
FORCEADD OFFPAGE..5
(-7800 1375);
FORCEPROP 2 LAST $XR0 257 
J 0
(-8055 1375);
DISPLAY 0.638298 (-8055 1375);
PAINT MONO (-8055 1375);
FORCEPROP 2 LAST CDS_LIB standard
J 0
(-7800 1375);
DISPLAY INVISIBLE (-7800 1375);
FORCEPROP 1 LAST OFFPAGE TRUE
J 0
(-7475 1250);
DISPLAY 0.872340 (-7475 1250);
PAINT GREEN (-7475 1250);
DISPLAY INVISIBLE (-7475 1250);
FORCEPROP 1 LAST COMMENT_BODY TRUE
J 0
(-7700 1300);
DISPLAY 0.872340 (-7700 1300);
PAINT GREEN (-7700 1300);
DISPLAY INVISIBLE (-7700 1300);
FORCEPROP 2 LAST PATH I309
J 0
(-7750 1450);
DISPLAY 0.680851 (-7750 1450);
DISPLAY INVISIBLE (-7750 1450);
FORCEADD Q_RES..1
(-6725 1575);
FORCEPROP 1 LAST LOCATION R282
J 0
(-6600 1575);
DISPLAY 0.489362 (-6600 1575);
PAINT SKYBLUE (-6600 1575);
FORCEPROP 0 LAST $SEC 1
J 2
(-6600 1625);
DISPLAY 0.680851 (-6600 1625);
PAINT MONO (-6600 1625);
DISPLAY INVISIBLE (-6600 1625);
FORCEPROP 0 LAST CDS_SEC 1
J 2
(-6600 1625);
DISPLAY 1.021277 (-6600 1625);
DISPLAY INVISIBLE (-6600 1625);
FORCEPROP 1 LASTPIN (-6825 1575) $PN 1
J 0
(-6813 1587);
DISPLAY 0.489362 (-6813 1587);
PAINT MONO (-6813 1587);
FORCEPROP 1 LASTPIN (-6625 1575) $PN 2
J 0
(-6663 1587);
DISPLAY 0.489362 (-6663 1587);
PAINT MONO (-6663 1587);
FORCEPROP 1 LAST VALUE 33
J 2
(-6850 1575);
DISPLAY 0.489362 (-6850 1575);
PAINT SKYBLUE (-6850 1575);
FORCEPROP 2 LAST CDS_LIB pure_quanta
J 2
(-6725 1575);
DISPLAY INVISIBLE (-6725 1575);
FORCEPROP 2 LAST BOM_COST MEM
J 2
(-6700 1725);
DISPLAY 0.744681 (-6700 1725);
PAINT WHITE (-6700 1725);
DISPLAY INVISIBLE (-6700 1725);
FORCEPROP 1 LAST WATTAGE 1/16W
J 2
(-6800 1500);
DISPLAY 0.489362 (-6800 1500);
PAINT SKYBLUE (-6800 1500);
DISPLAY INVISIBLE (-6800 1500);
FORCEPROP 1 LAST MATERIAL CHIP
J 2
(-6550 1550);
DISPLAY 0.489362 (-6550 1550);
PAINT SKYBLUE (-6550 1550);
DISPLAY INVISIBLE (-6550 1550);
FORCEPROP 1 LAST TOLERANCE 5%
J 0
(-6850 1550);
DISPLAY 0.489362 (-6850 1550);
PAINT SKYBLUE (-6850 1550);
DISPLAY INVISIBLE (-6850 1550);
FORCEPROP 1 LAST PACK_TYPE 0402LF
J 2
(-6550 1500);
DISPLAY 0.489362 (-6550 1500);
PAINT SKYBLUE (-6550 1500);
DISPLAY INVISIBLE (-6550 1500);
FORCEPROP 1 LAST PATH I31
J 0
(-6775 1725);
DISPLAY 0.978723 (-6775 1725);
PAINT WHITE (-6775 1725);
DISPLAY INVISIBLE (-6775 1725);
FORCEPROP 1 LAST PART_NUMBER CS03302JB10
J 2
(-6625 1625);
DISPLAY 0.489362 (-6625 1625);
PAINT SKYBLUE (-6625 1625);
DISPLAY INVISIBLE (-6625 1625);
FORCEADD OFFPAGE..2
(-800 2475);
FORCEPROP 2 LAST $XR1 85 
J 0
(-521 2475);
DISPLAY 0.638298 (-521 2475);
PAINT MONO (-521 2475);
FORCEPROP 2 LAST $XR0 83 
J 0
(-611 2475);
DISPLAY 0.638298 (-611 2475);
PAINT MONO (-611 2475);
FORCEPROP 2 LAST CDS_LIB standard
J 2
(-800 2475);
DISPLAY INVISIBLE (-800 2475);
FORCEPROP 1 LAST OFFPAGE TRUE
J 0
(-475 2350);
DISPLAY 0.872340 (-475 2350);
DISPLAY INVISIBLE (-475 2350);
FORCEPROP 1 LAST COMMENT_BODY TRUE
J 0
(-845 2380);
DISPLAY 0.872340 (-845 2380);
PAINT GREEN (-845 2380);
DISPLAY INVISIBLE (-845 2380);
FORCEPROP 2 LAST PATH I310
J 0
(-625 2550);
DISPLAY 0.680851 (-625 2550);
DISPLAY INVISIBLE (-625 2550);
FORCEADD Q_RES..1
(-6725 1475);
FORCEPROP 1 LAST LOCATION R2939
J 0
(-6950 1475);
DISPLAY 0.510638 (-6950 1475);
FORCEPROP 2 LAST $SEC 1
J 0
(-6775 1675);
DISPLAY 0.680851 (-6775 1675);
PAINT MONO (-6775 1675);
DISPLAY INVISIBLE (-6775 1675);
FORCEPROP 2 LAST CDS_SEC 1
J 0
(-6775 1675);
DISPLAY 1.021277 (-6775 1675);
DISPLAY INVISIBLE (-6775 1675);
FORCEPROP 1 LASTPIN (-6825 1475) $PN 1
J 0
(-6813 1487);
DISPLAY 0.638298 (-6813 1487);
FORCEPROP 1 LASTPIN (-6625 1475) $PN 2
J 0
(-6663 1487);
DISPLAY 0.638298 (-6663 1487);
FORCEPROP 1 LAST MATERIAL CHIP
J 0
(-6400 1475);
DISPLAY 0.404255 (-6400 1475);
FORCEPROP 1 LAST TOLERANCE 1%
J 0
(-6475 1475);
DISPLAY 0.404255 (-6475 1475);
FORCEPROP 1 LAST VALUE 33.2
J 2
(-6500 1475);
DISPLAY 0.404255 (-6500 1475);
FORCEPROP 1 LAST WATTAGE 1/16W
J 2
(-6525 1600);
DISPLAY 0.638298 (-6525 1600);
DISPLAY INVISIBLE (-6525 1600);
FORCEPROP 1 LAST PACK_TYPE 0402LF
J 0
(-6875 1600);
DISPLAY 0.638298 (-6875 1600);
DISPLAY INVISIBLE (-6875 1600);
FORCEPROP 2 LAST CDS_LIB pure_quanta
J 0
(-6725 1475);
PAINT MONO (-6725 1475);
DISPLAY INVISIBLE (-6725 1475);
FORCEPROP 1 LAST PATH I311
J 0
(-6775 1625);
DISPLAY 0.978723 (-6775 1625);
PAINT WHITE (-6775 1625);
DISPLAY INVISIBLE (-6775 1625);
FORCEPROP 1 LAST PART_NUMBER CS03322FB03
J 0
(-6875 1550);
DISPLAY 0.638298 (-6875 1550);
DISPLAY INVISIBLE (-6875 1550);
FORCEADD OFFPAGE..2
R 2
(-7800 1475);
FORCEPROP 2 LAST $XR0 242 
J 0
(-8055 1475);
DISPLAY 0.638298 (-8055 1475);
PAINT MONO (-8055 1475);
FORCEPROP 2 LAST CDS_LIB standard
J 0
(-7800 1475);
DISPLAY INVISIBLE (-7800 1475);
FORCEPROP 1 LAST OFFPAGE TRUE
J 2
(-8125 1350);
DISPLAY 0.872340 (-8125 1350);
PAINT GREEN (-8125 1350);
DISPLAY INVISIBLE (-8125 1350);
FORCEPROP 1 LAST COMMENT_BODY TRUE
J 2
(-7755 1380);
DISPLAY 0.872340 (-7755 1380);
PAINT GREEN (-7755 1380);
DISPLAY INVISIBLE (-7755 1380);
FORCEPROP 2 LAST PATH I312
J 0
(-8050 1525);
DISPLAY 0.680851 (-8050 1525);
DISPLAY INVISIBLE (-8050 1525);
FORCEADD OFFPAGE..1
(-7800 1275);
FORCEPROP 2 LAST $XR1 255 
J 0
(-8172 1275);
DISPLAY 0.638298 (-8172 1275);
PAINT MONO (-8172 1275);
FORCEPROP 2 LAST $XR0 271 
J 0
(-8052 1275);
DISPLAY 0.638298 (-8052 1275);
PAINT MONO (-8052 1275);
FORCEPROP 2 LAST CDS_LIB standard
J 0
(-7800 1275);
DISPLAY INVISIBLE (-7800 1275);
FORCEPROP 1 LAST OFFPAGE TRUE
J 0
(-7475 1150);
DISPLAY 0.872340 (-7475 1150);
PAINT GREEN (-7475 1150);
DISPLAY INVISIBLE (-7475 1150);
FORCEPROP 1 LAST COMMENT_BODY TRUE
J 0
(-7675 1175);
DISPLAY 0.872340 (-7675 1175);
PAINT GREEN (-7675 1175);
DISPLAY INVISIBLE (-7675 1175);
FORCEPROP 2 LAST PATH I313
J 0
(-7750 1350);
DISPLAY 0.680851 (-7750 1350);
DISPLAY INVISIBLE (-7750 1350);
FORCEADD OFFPAGE..5
(-7800 825);
FORCEPROP 2 LAST $XR1 85 
J 0
(-8114 825);
DISPLAY 0.638298 (-8114 825);
PAINT MONO (-8114 825);
FORCEPROP 2 LAST $XR0 83 
J 0
(-8024 825);
DISPLAY 0.638298 (-8024 825);
PAINT MONO (-8024 825);
FORCEPROP 2 LAST CDS_LIB standard
J 0
(-7800 825);
DISPLAY INVISIBLE (-7800 825);
FORCEPROP 1 LAST OFFPAGE TRUE
J 0
(-7475 700);
DISPLAY 0.872340 (-7475 700);
PAINT GREEN (-7475 700);
DISPLAY INVISIBLE (-7475 700);
FORCEPROP 1 LAST COMMENT_BODY TRUE
J 0
(-7700 750);
DISPLAY 0.872340 (-7700 750);
PAINT GREEN (-7700 750);
DISPLAY INVISIBLE (-7700 750);
FORCEPROP 2 LAST PATH I314
J 0
(-7750 900);
DISPLAY 0.680851 (-7750 900);
DISPLAY INVISIBLE (-7750 900);
FORCEADD Q_RES..1
(-6725 2725);
FORCEPROP 1 LAST LOCATION R8000
J 0
(-6950 2725);
DISPLAY 0.510638 (-6950 2725);
PAINT SKYBLUE (-6950 2725);
FORCEPROP 0 LAST $SEC 1
J 0
(-6400 2750);
DISPLAY 0.680851 (-6400 2750);
PAINT MONO (-6400 2750);
DISPLAY INVISIBLE (-6400 2750);
FORCEPROP 0 LAST CDS_SEC 1
J 0
(-6400 2750);
DISPLAY 0.680851 (-6400 2750);
DISPLAY INVISIBLE (-6400 2750);
FORCEPROP 1 LASTPIN (-6825 2725) $PN 1
J 0
(-6813 2737);
DISPLAY 0.787234 (-6813 2737);
PAINT MONO (-6813 2737);
FORCEPROP 1 LASTPIN (-6625 2725) $PN 2
J 0
(-6663 2737);
DISPLAY 0.787234 (-6663 2737);
PAINT MONO (-6663 2737);
FORCEPROP 1 LAST MATERIAL CHIP
J 0
(-6400 2725);
DISPLAY 0.404255 (-6400 2725);
FORCEPROP 1 LAST TOLERANCE 1%
J 0
(-6475 2725);
DISPLAY 0.404255 (-6475 2725);
FORCEPROP 1 LAST VALUE 33.2
J 2
(-6500 2725);
DISPLAY 0.404255 (-6500 2725);
FORCEPROP 1 LAST WATTAGE 1/16W
J 2
(-6525 2850);
DISPLAY 0.638298 (-6525 2850);
DISPLAY INVISIBLE (-6525 2850);
FORCEPROP 1 LAST PACK_TYPE 0402LF
J 0
(-6875 2850);
DISPLAY 0.638298 (-6875 2850);
DISPLAY INVISIBLE (-6875 2850);
FORCEPROP 2 LAST CDS_LIB pure_quanta
J 0
(-6725 2725);
DISPLAY INVISIBLE (-6725 2725);
FORCEPROP 1 LAST PATH I315
J 0
(-6775 2875);
DISPLAY 0.978723 (-6775 2875);
PAINT WHITE (-6775 2875);
DISPLAY INVISIBLE (-6775 2875);
FORCEPROP 1 LAST PART_NUMBER CS03322FB03
J 0
(-6875 2800);
DISPLAY 0.638298 (-6875 2800);
DISPLAY INVISIBLE (-6875 2800);
FORCEADD OFFPAGE..1
(-7775 2725);
FORCEPROP 2 LAST $XR1 246 
J 0
(-8177 2725);
DISPLAY 0.638298 (-8177 2725);
PAINT MONO (-8177 2725);
FORCEPROP 2 LAST $XR0 123 
J 0
(-8057 2725);
DISPLAY 0.638298 (-8057 2725);
PAINT MONO (-8057 2725);
FORCEPROP 2 LAST CDS_LIB standard
J 0
(-7775 2725);
DISPLAY INVISIBLE (-7775 2725);
FORCEPROP 1 LAST OFFPAGE TRUE
J 0
(-7450 2600);
DISPLAY 0.872340 (-7450 2600);
PAINT GREEN (-7450 2600);
DISPLAY INVISIBLE (-7450 2600);
FORCEPROP 1 LAST COMMENT_BODY TRUE
J 0
(-7650 2625);
DISPLAY 0.872340 (-7650 2625);
PAINT GREEN (-7650 2625);
DISPLAY INVISIBLE (-7650 2625);
FORCEPROP 2 LAST PATH I316
J 0
(-7725 2800);
DISPLAY 0.680851 (-7725 2800);
DISPLAY INVISIBLE (-7725 2800);
FORCEADD OFFPAGE..2
(-2275 5575);
FORCEPROP 2 LAST $XR0 167 
J 0
(-2086 5575);
DISPLAY 0.638298 (-2086 5575);
PAINT MONO (-2086 5575);
FORCEPROP 2 LAST CDS_LIB standard
J 0
(-2275 5575);
DISPLAY INVISIBLE (-2275 5575);
FORCEPROP 1 LAST OFFPAGE TRUE
J 0
(-1950 5450);
DISPLAY 0.872340 (-1950 5450);
PAINT GREEN (-1950 5450);
DISPLAY INVISIBLE (-1950 5450);
FORCEPROP 1 LAST COMMENT_BODY TRUE
J 0
(-2320 5480);
DISPLAY 0.872340 (-2320 5480);
PAINT GREEN (-2320 5480);
DISPLAY INVISIBLE (-2320 5480);
FORCEPROP 2 LAST PATH I317
J 0
(-2075 5625);
DISPLAY 0.680851 (-2075 5625);
DISPLAY INVISIBLE (-2075 5625);
FORCEADD Q_RES..1
(-3225 5575);
FORCEPROP 1 LAST LOCATION R8021
J 0
(-3100 5575);
DISPLAY 0.489362 (-3100 5575);
PAINT SKYBLUE (-3100 5575);
FORCEPROP 2 LAST SEC 1
J 0
(-3275 5775);
DISPLAY 0.680851 (-3275 5775);
PAINT MONO (-3275 5775);
DISPLAY INVISIBLE (-3275 5775);
FORCEPROP 1 LASTPIN (-3325 5575) $PN 1
J 0
(-3313 5587);
DISPLAY 0.787234 (-3313 5587);
PAINT MONO (-3313 5587);
FORCEPROP 1 LASTPIN (-3125 5575) $PN 2
J 0
(-3163 5587);
DISPLAY 0.787234 (-3163 5587);
PAINT MONO (-3163 5587);
FORCEPROP 1 LAST VALUE 0
J 2
(-3350 5575);
DISPLAY 0.489362 (-3350 5575);
PAINT SKYBLUE (-3350 5575);
FORCEPROP 1 LAST PACK_TYPE 0402LF
J 2
(-3050 5500);
DISPLAY 0.489362 (-3050 5500);
PAINT SKYBLUE (-3050 5500);
DISPLAY INVISIBLE (-3050 5500);
FORCEPROP 2 LAST SEC_TYPE 0402LF
J 0
(-3275 5775);
DISPLAY 0.680851 (-3275 5775);
DISPLAY INVISIBLE (-3275 5775);
FORCEPROP 1 LAST TOLERANCE 5%
J 0
(-3350 5550);
DISPLAY 0.489362 (-3350 5550);
PAINT SKYBLUE (-3350 5550);
DISPLAY INVISIBLE (-3350 5550);
FORCEPROP 1 LAST MATERIAL CHIP
J 2
(-3050 5550);
DISPLAY 0.489362 (-3050 5550);
PAINT SKYBLUE (-3050 5550);
DISPLAY INVISIBLE (-3050 5550);
FORCEPROP 1 LAST WATTAGE 1/16W
J 2
(-3300 5500);
DISPLAY 0.489362 (-3300 5500);
PAINT SKYBLUE (-3300 5500);
DISPLAY INVISIBLE (-3300 5500);
FORCEPROP 2 LAST BOM_COST MEM
J 2
(-3200 5725);
DISPLAY 0.744681 (-3200 5725);
PAINT WHITE (-3200 5725);
DISPLAY INVISIBLE (-3200 5725);
FORCEPROP 2 LAST CDS_LIB pure_quanta
J 0
(-3225 5575);
DISPLAY INVISIBLE (-3225 5575);
FORCEPROP 1 LAST PATH I318
J 0
(-3275 5725);
DISPLAY 0.978723 (-3275 5725);
PAINT WHITE (-3275 5725);
DISPLAY INVISIBLE (-3275 5725);
FORCEPROP 1 LAST PART_NUMBER CS00002JB13
J 2
(-3125 5625);
DISPLAY 0.489362 (-3125 5625);
PAINT SKYBLUE (-3125 5625);
DISPLAY INVISIBLE (-3125 5625);
FORCEADD Q_RES..1
(-3225 5875);
FORCEPROP 1 LAST LOCATION R8032
J 0
(-3100 5875);
DISPLAY 0.489362 (-3100 5875);
PAINT SKYBLUE (-3100 5875);
FORCEPROP 0 LAST $SEC 1
J 0
(-3100 5900);
DISPLAY 0.680851 (-3100 5900);
PAINT MONO (-3100 5900);
DISPLAY INVISIBLE (-3100 5900);
FORCEPROP 0 LAST CDS_SEC 1
J 0
(-3100 5900);
DISPLAY 0.680851 (-3100 5900);
DISPLAY INVISIBLE (-3100 5900);
FORCEPROP 1 LASTPIN (-3325 5875) $PN 1
J 0
(-3313 5887);
DISPLAY 0.787234 (-3313 5887);
PAINT MONO (-3313 5887);
FORCEPROP 1 LASTPIN (-3125 5875) $PN 2
J 0
(-3163 5887);
DISPLAY 0.787234 (-3163 5887);
PAINT MONO (-3163 5887);
FORCEPROP 1 LAST VALUE 0
J 2
(-3350 5875);
DISPLAY 0.489362 (-3350 5875);
PAINT SKYBLUE (-3350 5875);
FORCEPROP 2 LAST CDS_LIB pure_quanta
J 0
(-3225 5875);
DISPLAY INVISIBLE (-3225 5875);
FORCEPROP 1 LAST PACK_TYPE 0402LF
J 2
(-3050 5800);
DISPLAY 0.489362 (-3050 5800);
PAINT SKYBLUE (-3050 5800);
DISPLAY INVISIBLE (-3050 5800);
FORCEPROP 1 LAST TOLERANCE 5%
J 0
(-3350 5850);
DISPLAY 0.489362 (-3350 5850);
PAINT SKYBLUE (-3350 5850);
DISPLAY INVISIBLE (-3350 5850);
FORCEPROP 1 LAST MATERIAL CHIP
J 2
(-3050 5850);
DISPLAY 0.489362 (-3050 5850);
PAINT SKYBLUE (-3050 5850);
DISPLAY INVISIBLE (-3050 5850);
FORCEPROP 1 LAST WATTAGE 1/16W
J 2
(-3300 5800);
DISPLAY 0.489362 (-3300 5800);
PAINT SKYBLUE (-3300 5800);
DISPLAY INVISIBLE (-3300 5800);
FORCEPROP 2 LAST BOM_COST MEM
J 2
(-3200 6025);
DISPLAY 0.744681 (-3200 6025);
PAINT WHITE (-3200 6025);
DISPLAY INVISIBLE (-3200 6025);
FORCEPROP 1 LAST PATH I319
J 0
(-3275 6025);
DISPLAY 0.978723 (-3275 6025);
PAINT WHITE (-3275 6025);
DISPLAY INVISIBLE (-3275 6025);
FORCEPROP 1 LAST PART_NUMBER CS00002JB13
J 2
(-3125 5925);
DISPLAY 0.489362 (-3125 5925);
PAINT SKYBLUE (-3125 5925);
DISPLAY INVISIBLE (-3125 5925);
FORCEADD Q_RES..1
(-6725 1625);
FORCEPROP 1 LAST LOCATION R218
J 0
(-6600 1625);
DISPLAY 0.489362 (-6600 1625);
PAINT SKYBLUE (-6600 1625);
FORCEPROP 0 LAST $SEC 1
J 2
(-6600 1675);
DISPLAY 0.680851 (-6600 1675);
PAINT MONO (-6600 1675);
DISPLAY INVISIBLE (-6600 1675);
FORCEPROP 0 LAST CDS_SEC 1
J 2
(-6600 1675);
DISPLAY 1.021277 (-6600 1675);
DISPLAY INVISIBLE (-6600 1675);
FORCEPROP 1 LASTPIN (-6825 1625) $PN 1
J 0
(-6813 1637);
DISPLAY 0.489362 (-6813 1637);
PAINT MONO (-6813 1637);
FORCEPROP 1 LASTPIN (-6625 1625) $PN 2
J 0
(-6663 1637);
DISPLAY 0.489362 (-6663 1637);
PAINT MONO (-6663 1637);
FORCEPROP 1 LAST VALUE 33
J 2
(-6850 1625);
DISPLAY 0.489362 (-6850 1625);
PAINT SKYBLUE (-6850 1625);
FORCEPROP 2 LAST CDS_LIB pure_quanta
J 2
(-6725 1625);
DISPLAY INVISIBLE (-6725 1625);
FORCEPROP 2 LAST BOM_COST MEM
J 2
(-6700 1775);
DISPLAY 0.744681 (-6700 1775);
PAINT WHITE (-6700 1775);
DISPLAY INVISIBLE (-6700 1775);
FORCEPROP 1 LAST WATTAGE 1/16W
J 2
(-6800 1550);
DISPLAY 0.489362 (-6800 1550);
PAINT SKYBLUE (-6800 1550);
DISPLAY INVISIBLE (-6800 1550);
FORCEPROP 1 LAST MATERIAL CHIP
J 2
(-6550 1600);
DISPLAY 0.489362 (-6550 1600);
PAINT SKYBLUE (-6550 1600);
DISPLAY INVISIBLE (-6550 1600);
FORCEPROP 1 LAST TOLERANCE 5%
J 0
(-6850 1600);
DISPLAY 0.489362 (-6850 1600);
PAINT SKYBLUE (-6850 1600);
DISPLAY INVISIBLE (-6850 1600);
FORCEPROP 1 LAST PACK_TYPE 0402LF
J 2
(-6550 1550);
DISPLAY 0.489362 (-6550 1550);
PAINT SKYBLUE (-6550 1550);
DISPLAY INVISIBLE (-6550 1550);
FORCEPROP 1 LAST PATH I32
J 0
(-6775 1775);
DISPLAY 0.978723 (-6775 1775);
PAINT WHITE (-6775 1775);
DISPLAY INVISIBLE (-6775 1775);
FORCEPROP 1 LAST PART_NUMBER CS03302JB10
J 2
(-6625 1675);
DISPLAY 0.489362 (-6625 1675);
PAINT SKYBLUE (-6625 1675);
DISPLAY INVISIBLE (-6625 1675);
FORCEADD OFFPAGE..2
(-2300 5875);
FORCEPROP 2 LAST $XR1 153 
J 0
(-2021 5875);
DISPLAY 0.638298 (-2021 5875);
PAINT MONO (-2021 5875);
FORCEPROP 2 LAST $XR0 83 
J 0
(-2111 5875);
DISPLAY 0.638298 (-2111 5875);
PAINT MONO (-2111 5875);
FORCEPROP 2 LAST CDS_LIB standard
J 0
(-2300 5875);
DISPLAY INVISIBLE (-2300 5875);
FORCEPROP 1 LAST OFFPAGE TRUE
J 0
(-1975 5750);
DISPLAY 0.872340 (-1975 5750);
PAINT GREEN (-1975 5750);
DISPLAY INVISIBLE (-1975 5750);
FORCEPROP 1 LAST COMMENT_BODY TRUE
J 0
(-2345 5780);
DISPLAY 0.872340 (-2345 5780);
PAINT GREEN (-2345 5780);
DISPLAY INVISIBLE (-2345 5780);
FORCEPROP 2 LAST PATH I320
J 0
(-2125 5950);
DISPLAY 0.680851 (-2125 5950);
DISPLAY INVISIBLE (-2125 5950);
FORCEADD OFFPAGE..1
R 2
(-800 1025);
FORCEPROP 2 LAST $XR0 243 
J 0
(-614 1025);
DISPLAY 0.638298 (-614 1025);
PAINT MONO (-614 1025);
FORCEPROP 2 LAST CDS_LIB standard
J 0
(-800 1025);
DISPLAY INVISIBLE (-800 1025);
FORCEPROP 1 LAST OFFPAGE TRUE
J 2
(-1125 900);
DISPLAY 0.872340 (-1125 900);
PAINT GREEN (-1125 900);
DISPLAY INVISIBLE (-1125 900);
FORCEPROP 1 LAST COMMENT_BODY TRUE
J 2
(-925 925);
DISPLAY 0.872340 (-925 925);
PAINT GREEN (-925 925);
DISPLAY INVISIBLE (-925 925);
FORCEPROP 2 LAST PATH I321
J 0
(-625 1100);
DISPLAY 0.680851 (-625 1100);
DISPLAY INVISIBLE (-625 1100);
FORCEADD Q_RES..1
(-6425 5775);
FORCEPROP 1 LAST LOCATION R6710
J 0
(-6300 5775);
DISPLAY 0.489362 (-6300 5775);
PAINT SKYBLUE (-6300 5775);
FORCEPROP 0 LAST $SEC 1
J 0
(-6300 5800);
DISPLAY 0.680851 (-6300 5800);
PAINT MONO (-6300 5800);
DISPLAY INVISIBLE (-6300 5800);
FORCEPROP 0 LAST CDS_SEC 1
J 0
(-6300 5800);
DISPLAY 0.680851 (-6300 5800);
DISPLAY INVISIBLE (-6300 5800);
FORCEPROP 1 LASTPIN (-6525 5775) $PN 1
J 0
(-6513 5787);
DISPLAY 0.787234 (-6513 5787);
PAINT MONO (-6513 5787);
FORCEPROP 1 LASTPIN (-6325 5775) $PN 2
J 0
(-6363 5787);
DISPLAY 0.787234 (-6363 5787);
PAINT MONO (-6363 5787);
FORCEPROP 1 LAST VALUE 0
J 2
(-6550 5775);
DISPLAY 0.489362 (-6550 5775);
PAINT SKYBLUE (-6550 5775);
FORCEPROP 2 LAST CDS_LIB pure_quanta
J 0
(-6425 5775);
DISPLAY INVISIBLE (-6425 5775);
FORCEPROP 1 LAST PACK_TYPE 0402LF
J 2
(-6250 5700);
DISPLAY 0.489362 (-6250 5700);
PAINT SKYBLUE (-6250 5700);
DISPLAY INVISIBLE (-6250 5700);
FORCEPROP 1 LAST TOLERANCE 5%
J 0
(-6550 5750);
DISPLAY 0.489362 (-6550 5750);
PAINT SKYBLUE (-6550 5750);
DISPLAY INVISIBLE (-6550 5750);
FORCEPROP 1 LAST MATERIAL CHIP
J 2
(-6250 5750);
DISPLAY 0.489362 (-6250 5750);
PAINT SKYBLUE (-6250 5750);
DISPLAY INVISIBLE (-6250 5750);
FORCEPROP 1 LAST WATTAGE 1/16W
J 2
(-6500 5700);
DISPLAY 0.489362 (-6500 5700);
PAINT SKYBLUE (-6500 5700);
DISPLAY INVISIBLE (-6500 5700);
FORCEPROP 2 LAST BOM_COST MEM
J 2
(-6400 5925);
DISPLAY 0.744681 (-6400 5925);
PAINT WHITE (-6400 5925);
DISPLAY INVISIBLE (-6400 5925);
FORCEPROP 1 LAST PATH I322
J 0
(-6475 5925);
DISPLAY 0.978723 (-6475 5925);
PAINT WHITE (-6475 5925);
DISPLAY INVISIBLE (-6475 5925);
FORCEPROP 1 LAST PART_NUMBER CS00002JB13
J 2
(-6325 5825);
DISPLAY 0.489362 (-6325 5825);
PAINT SKYBLUE (-6325 5825);
DISPLAY INVISIBLE (-6325 5825);
FORCEADD OFFPAGE..2
R 2
(-7375 5775);
FORCEPROP 2 LAST $XR0 321 
J 0
(-7630 5775);
DISPLAY 0.638298 (-7630 5775);
PAINT MONO (-7630 5775);
FORCEPROP 2 LAST CDS_LIB standard
J 0
(-7375 5775);
DISPLAY INVISIBLE (-7375 5775);
FORCEPROP 1 LAST OFFPAGE TRUE
J 2
(-7700 5650);
DISPLAY 0.872340 (-7700 5650);
DISPLAY INVISIBLE (-7700 5650);
FORCEPROP 1 LAST COMMENT_BODY TRUE
J 2
(-7330 5680);
DISPLAY 0.872340 (-7330 5680);
PAINT GREEN (-7330 5680);
DISPLAY INVISIBLE (-7330 5680);
FORCEPROP 2 LAST PATH I323
J 0
(-7325 5850);
DISPLAY 0.680851 (-7325 5850);
DISPLAY INVISIBLE (-7325 5850);
FORCEADD Q_RES..1
(-6425 5725);
FORCEPROP 1 LAST LOCATION R6711
J 0
(-6300 5725);
DISPLAY 0.489362 (-6300 5725);
PAINT SKYBLUE (-6300 5725);
FORCEPROP 0 LAST $SEC 1
J 0
(-6300 5750);
DISPLAY 0.680851 (-6300 5750);
PAINT MONO (-6300 5750);
DISPLAY INVISIBLE (-6300 5750);
FORCEPROP 0 LAST CDS_SEC 1
J 0
(-6300 5750);
DISPLAY 0.680851 (-6300 5750);
DISPLAY INVISIBLE (-6300 5750);
FORCEPROP 1 LASTPIN (-6525 5725) $PN 1
J 0
(-6513 5737);
DISPLAY 0.787234 (-6513 5737);
PAINT MONO (-6513 5737);
FORCEPROP 1 LASTPIN (-6325 5725) $PN 2
J 0
(-6363 5737);
DISPLAY 0.787234 (-6363 5737);
PAINT MONO (-6363 5737);
FORCEPROP 1 LAST VALUE 0
J 2
(-6550 5725);
DISPLAY 0.489362 (-6550 5725);
PAINT SKYBLUE (-6550 5725);
FORCEPROP 2 LAST CDS_LIB pure_quanta
J 0
(-6425 5725);
DISPLAY INVISIBLE (-6425 5725);
FORCEPROP 1 LAST PACK_TYPE 0402LF
J 2
(-6250 5650);
DISPLAY 0.489362 (-6250 5650);
PAINT SKYBLUE (-6250 5650);
DISPLAY INVISIBLE (-6250 5650);
FORCEPROP 1 LAST TOLERANCE 5%
J 0
(-6550 5700);
DISPLAY 0.489362 (-6550 5700);
PAINT SKYBLUE (-6550 5700);
DISPLAY INVISIBLE (-6550 5700);
FORCEPROP 1 LAST MATERIAL CHIP
J 2
(-6250 5700);
DISPLAY 0.489362 (-6250 5700);
PAINT SKYBLUE (-6250 5700);
DISPLAY INVISIBLE (-6250 5700);
FORCEPROP 1 LAST WATTAGE 1/16W
J 2
(-6500 5650);
DISPLAY 0.489362 (-6500 5650);
PAINT SKYBLUE (-6500 5650);
DISPLAY INVISIBLE (-6500 5650);
FORCEPROP 2 LAST BOM_COST MEM
J 2
(-6400 5875);
DISPLAY 0.744681 (-6400 5875);
PAINT WHITE (-6400 5875);
DISPLAY INVISIBLE (-6400 5875);
FORCEPROP 1 LAST PATH I324
J 0
(-6475 5875);
DISPLAY 0.978723 (-6475 5875);
PAINT WHITE (-6475 5875);
DISPLAY INVISIBLE (-6475 5875);
FORCEPROP 1 LAST PART_NUMBER CS00002JB13
J 2
(-6325 5775);
DISPLAY 0.489362 (-6325 5775);
PAINT SKYBLUE (-6325 5775);
DISPLAY INVISIBLE (-6325 5775);
FORCEADD OFFPAGE..2
R 2
(-7375 5725);
FORCEPROP 2 LAST $XR0 321 
J 0
(-7630 5725);
DISPLAY 0.638298 (-7630 5725);
PAINT MONO (-7630 5725);
FORCEPROP 2 LAST CDS_LIB standard
J 0
(-7375 5725);
DISPLAY INVISIBLE (-7375 5725);
FORCEPROP 1 LAST OFFPAGE TRUE
J 2
(-7700 5600);
DISPLAY 0.872340 (-7700 5600);
DISPLAY INVISIBLE (-7700 5600);
FORCEPROP 1 LAST COMMENT_BODY TRUE
J 2
(-7330 5630);
DISPLAY 0.872340 (-7330 5630);
PAINT GREEN (-7330 5630);
DISPLAY INVISIBLE (-7330 5630);
FORCEPROP 2 LAST PATH I325
J 0
(-7325 5800);
DISPLAY 0.680851 (-7325 5800);
DISPLAY INVISIBLE (-7325 5800);
FORCEADD Q_RES..1
(-6425 5275);
FORCEPROP 1 LAST LOCATION R6740
J 0
(-6300 5275);
DISPLAY 0.489362 (-6300 5275);
PAINT SKYBLUE (-6300 5275);
FORCEPROP 0 LAST $SEC 1
J 0
(-6300 5300);
DISPLAY 0.680851 (-6300 5300);
PAINT MONO (-6300 5300);
DISPLAY INVISIBLE (-6300 5300);
FORCEPROP 0 LAST CDS_SEC 1
J 0
(-6300 5300);
DISPLAY 0.680851 (-6300 5300);
DISPLAY INVISIBLE (-6300 5300);
FORCEPROP 1 LASTPIN (-6525 5275) $PN 1
J 0
(-6513 5287);
DISPLAY 0.787234 (-6513 5287);
PAINT MONO (-6513 5287);
FORCEPROP 1 LASTPIN (-6325 5275) $PN 2
J 0
(-6363 5287);
DISPLAY 0.787234 (-6363 5287);
PAINT MONO (-6363 5287);
FORCEPROP 1 LAST VALUE 0
J 2
(-6550 5275);
DISPLAY 0.489362 (-6550 5275);
PAINT SKYBLUE (-6550 5275);
FORCEPROP 2 LAST CDS_LIB pure_quanta
J 0
(-6425 5275);
DISPLAY INVISIBLE (-6425 5275);
FORCEPROP 1 LAST PACK_TYPE 0402LF
J 2
(-6250 5200);
DISPLAY 0.489362 (-6250 5200);
PAINT SKYBLUE (-6250 5200);
DISPLAY INVISIBLE (-6250 5200);
FORCEPROP 1 LAST TOLERANCE 5%
J 0
(-6550 5250);
DISPLAY 0.489362 (-6550 5250);
PAINT SKYBLUE (-6550 5250);
DISPLAY INVISIBLE (-6550 5250);
FORCEPROP 1 LAST MATERIAL CHIP
J 2
(-6250 5250);
DISPLAY 0.489362 (-6250 5250);
PAINT SKYBLUE (-6250 5250);
DISPLAY INVISIBLE (-6250 5250);
FORCEPROP 1 LAST WATTAGE 1/16W
J 2
(-6500 5200);
DISPLAY 0.489362 (-6500 5200);
PAINT SKYBLUE (-6500 5200);
DISPLAY INVISIBLE (-6500 5200);
FORCEPROP 2 LAST BOM_COST MEM
J 2
(-6400 5425);
DISPLAY 0.744681 (-6400 5425);
PAINT WHITE (-6400 5425);
DISPLAY INVISIBLE (-6400 5425);
FORCEPROP 1 LAST PATH I326
J 0
(-6475 5425);
DISPLAY 0.978723 (-6475 5425);
PAINT WHITE (-6475 5425);
DISPLAY INVISIBLE (-6475 5425);
FORCEPROP 1 LAST PART_NUMBER CS00002JB13
J 2
(-6325 5325);
DISPLAY 0.489362 (-6325 5325);
PAINT SKYBLUE (-6325 5325);
DISPLAY INVISIBLE (-6325 5325);
FORCEADD Q_RES..1
(-6425 5225);
FORCEPROP 1 LAST LOCATION R6741
J 0
(-6300 5225);
DISPLAY 0.489362 (-6300 5225);
PAINT SKYBLUE (-6300 5225);
FORCEPROP 0 LAST $SEC 1
J 0
(-6300 5250);
DISPLAY 0.680851 (-6300 5250);
PAINT MONO (-6300 5250);
DISPLAY INVISIBLE (-6300 5250);
FORCEPROP 0 LAST CDS_SEC 1
J 0
(-6300 5250);
DISPLAY 0.680851 (-6300 5250);
DISPLAY INVISIBLE (-6300 5250);
FORCEPROP 1 LASTPIN (-6525 5225) $PN 1
J 0
(-6513 5237);
DISPLAY 0.787234 (-6513 5237);
PAINT MONO (-6513 5237);
FORCEPROP 1 LASTPIN (-6325 5225) $PN 2
J 0
(-6363 5237);
DISPLAY 0.787234 (-6363 5237);
PAINT MONO (-6363 5237);
FORCEPROP 1 LAST VALUE 0
J 2
(-6550 5225);
DISPLAY 0.489362 (-6550 5225);
PAINT SKYBLUE (-6550 5225);
FORCEPROP 1 LAST PACK_TYPE 0402LF
J 2
(-6250 5150);
DISPLAY 0.489362 (-6250 5150);
PAINT SKYBLUE (-6250 5150);
DISPLAY INVISIBLE (-6250 5150);
FORCEPROP 1 LAST TOLERANCE 5%
J 0
(-6550 5200);
DISPLAY 0.489362 (-6550 5200);
PAINT SKYBLUE (-6550 5200);
DISPLAY INVISIBLE (-6550 5200);
FORCEPROP 1 LAST MATERIAL CHIP
J 2
(-6250 5200);
DISPLAY 0.489362 (-6250 5200);
PAINT SKYBLUE (-6250 5200);
DISPLAY INVISIBLE (-6250 5200);
FORCEPROP 1 LAST WATTAGE 1/16W
J 2
(-6500 5150);
DISPLAY 0.489362 (-6500 5150);
PAINT SKYBLUE (-6500 5150);
DISPLAY INVISIBLE (-6500 5150);
FORCEPROP 2 LAST BOM_COST MEM
J 2
(-6400 5375);
DISPLAY 0.744681 (-6400 5375);
PAINT WHITE (-6400 5375);
DISPLAY INVISIBLE (-6400 5375);
FORCEPROP 2 LAST CDS_LIB pure_quanta
J 0
(-6425 5225);
DISPLAY INVISIBLE (-6425 5225);
FORCEPROP 1 LAST PATH I327
J 0
(-6475 5375);
DISPLAY 0.978723 (-6475 5375);
PAINT WHITE (-6475 5375);
DISPLAY INVISIBLE (-6475 5375);
FORCEPROP 1 LAST PART_NUMBER CS00002JB13
J 2
(-6325 5275);
DISPLAY 0.489362 (-6325 5275);
PAINT SKYBLUE (-6325 5275);
DISPLAY INVISIBLE (-6325 5275);
FORCEADD OFFPAGE..2
R 2
(-7375 5275);
FORCEPROP 2 LAST $XR0 332 
J 0
(-7630 5275);
DISPLAY 0.638298 (-7630 5275);
PAINT MONO (-7630 5275);
FORCEPROP 2 LAST CDS_LIB standard
J 0
(-7375 5275);
DISPLAY INVISIBLE (-7375 5275);
FORCEPROP 1 LAST OFFPAGE TRUE
J 2
(-7700 5150);
DISPLAY 0.872340 (-7700 5150);
PAINT GREEN (-7700 5150);
DISPLAY INVISIBLE (-7700 5150);
FORCEPROP 1 LAST COMMENT_BODY TRUE
J 2
(-7330 5180);
DISPLAY 0.872340 (-7330 5180);
PAINT GREEN (-7330 5180);
DISPLAY INVISIBLE (-7330 5180);
FORCEPROP 2 LAST PATH I328
J 0
(-7325 5350);
DISPLAY 0.680851 (-7325 5350);
DISPLAY INVISIBLE (-7325 5350);
FORCEADD OFFPAGE..2
R 2
(-7375 5225);
FORCEPROP 2 LAST $XR0 332 
J 0
(-7630 5225);
DISPLAY 0.638298 (-7630 5225);
PAINT MONO (-7630 5225);
FORCEPROP 2 LAST CDS_LIB standard
J 0
(-7375 5225);
DISPLAY INVISIBLE (-7375 5225);
FORCEPROP 1 LAST OFFPAGE TRUE
J 2
(-7700 5100);
DISPLAY 0.872340 (-7700 5100);
PAINT GREEN (-7700 5100);
DISPLAY INVISIBLE (-7700 5100);
FORCEPROP 1 LAST COMMENT_BODY TRUE
J 2
(-7330 5130);
DISPLAY 0.872340 (-7330 5130);
PAINT GREEN (-7330 5130);
DISPLAY INVISIBLE (-7330 5130);
FORCEPROP 2 LAST PATH I329
J 0
(-7325 5300);
DISPLAY 0.680851 (-7325 5300);
DISPLAY INVISIBLE (-7325 5300);
FORCEADD Q_RES..1
(-6725 1775);
FORCEPROP 1 LAST LOCATION R176
J 0
(-6600 1775);
DISPLAY 0.489362 (-6600 1775);
PAINT SKYBLUE (-6600 1775);
FORCEPROP 0 LAST $SEC 1
J 2
(-6600 1825);
DISPLAY 0.680851 (-6600 1825);
PAINT MONO (-6600 1825);
DISPLAY INVISIBLE (-6600 1825);
FORCEPROP 0 LAST CDS_SEC 1
J 2
(-6600 1825);
DISPLAY 1.021277 (-6600 1825);
DISPLAY INVISIBLE (-6600 1825);
FORCEPROP 1 LASTPIN (-6825 1775) $PN 1
J 0
(-6813 1787);
DISPLAY 0.489362 (-6813 1787);
PAINT MONO (-6813 1787);
FORCEPROP 1 LASTPIN (-6625 1775) $PN 2
J 0
(-6663 1787);
DISPLAY 0.489362 (-6663 1787);
PAINT MONO (-6663 1787);
FORCEPROP 1 LAST VALUE 33
J 2
(-6850 1775);
DISPLAY 0.489362 (-6850 1775);
PAINT SKYBLUE (-6850 1775);
FORCEPROP 2 LAST BOM_COST MEM
J 2
(-6700 1925);
DISPLAY 0.744681 (-6700 1925);
PAINT WHITE (-6700 1925);
DISPLAY INVISIBLE (-6700 1925);
FORCEPROP 2 LAST CDS_LIB pure_quanta
J 2
(-6725 1775);
DISPLAY INVISIBLE (-6725 1775);
FORCEPROP 1 LAST WATTAGE 1/16W
J 2
(-6800 1700);
DISPLAY 0.489362 (-6800 1700);
PAINT SKYBLUE (-6800 1700);
DISPLAY INVISIBLE (-6800 1700);
FORCEPROP 1 LAST MATERIAL CHIP
J 2
(-6550 1750);
DISPLAY 0.489362 (-6550 1750);
PAINT SKYBLUE (-6550 1750);
DISPLAY INVISIBLE (-6550 1750);
FORCEPROP 1 LAST TOLERANCE 5%
J 0
(-6850 1750);
DISPLAY 0.489362 (-6850 1750);
PAINT SKYBLUE (-6850 1750);
DISPLAY INVISIBLE (-6850 1750);
FORCEPROP 1 LAST PACK_TYPE 0402LF
J 2
(-6550 1700);
DISPLAY 0.489362 (-6550 1700);
PAINT SKYBLUE (-6550 1700);
DISPLAY INVISIBLE (-6550 1700);
FORCEPROP 1 LAST PATH I33
J 0
(-6775 1925);
DISPLAY 0.978723 (-6775 1925);
PAINT WHITE (-6775 1925);
DISPLAY INVISIBLE (-6775 1925);
FORCEPROP 1 LAST PART_NUMBER CS03302JB10
J 2
(-6625 1825);
DISPLAY 0.489362 (-6625 1825);
PAINT SKYBLUE (-6625 1825);
DISPLAY INVISIBLE (-6625 1825);
FORCEADD Q_RES..1
(-3225 3775);
FORCEPROP 1 LAST LOCATION R6777
J 0
(-3100 3775);
DISPLAY 0.489362 (-3100 3775);
PAINT SKYBLUE (-3100 3775);
FORCEPROP 0 LAST $SEC 1
J 0
(-3100 3800);
DISPLAY 0.680851 (-3100 3800);
PAINT MONO (-3100 3800);
DISPLAY INVISIBLE (-3100 3800);
FORCEPROP 0 LAST CDS_SEC 1
J 0
(-3100 3800);
DISPLAY 0.680851 (-3100 3800);
DISPLAY INVISIBLE (-3100 3800);
FORCEPROP 1 LASTPIN (-3325 3775) $PN 1
J 0
(-3313 3787);
DISPLAY 0.787234 (-3313 3787);
PAINT MONO (-3313 3787);
FORCEPROP 1 LASTPIN (-3125 3775) $PN 2
J 0
(-3163 3787);
DISPLAY 0.787234 (-3163 3787);
PAINT MONO (-3163 3787);
FORCEPROP 1 LAST VALUE 0
J 2
(-3350 3775);
DISPLAY 0.489362 (-3350 3775);
PAINT SKYBLUE (-3350 3775);
FORCEPROP 1 LAST PACK_TYPE 0402LF
J 2
(-3050 3700);
DISPLAY 0.489362 (-3050 3700);
PAINT SKYBLUE (-3050 3700);
DISPLAY INVISIBLE (-3050 3700);
FORCEPROP 1 LAST TOLERANCE 5%
J 0
(-3350 3750);
DISPLAY 0.489362 (-3350 3750);
PAINT SKYBLUE (-3350 3750);
DISPLAY INVISIBLE (-3350 3750);
FORCEPROP 1 LAST MATERIAL CHIP
J 2
(-3050 3750);
DISPLAY 0.489362 (-3050 3750);
PAINT SKYBLUE (-3050 3750);
DISPLAY INVISIBLE (-3050 3750);
FORCEPROP 1 LAST WATTAGE 1/16W
J 2
(-3300 3700);
DISPLAY 0.489362 (-3300 3700);
PAINT SKYBLUE (-3300 3700);
DISPLAY INVISIBLE (-3300 3700);
FORCEPROP 2 LAST BOM_COST MEM
J 2
(-3200 3925);
DISPLAY 0.744681 (-3200 3925);
PAINT WHITE (-3200 3925);
DISPLAY INVISIBLE (-3200 3925);
FORCEPROP 2 LAST CDS_LIB pure_quanta
J 0
(-3225 3775);
DISPLAY INVISIBLE (-3225 3775);
FORCEPROP 1 LAST PATH I330
J 0
(-3275 3925);
DISPLAY 0.978723 (-3275 3925);
PAINT WHITE (-3275 3925);
DISPLAY INVISIBLE (-3275 3925);
FORCEPROP 1 LAST PART_NUMBER CS00002JB13
J 2
(-3125 3825);
DISPLAY 0.489362 (-3125 3825);
PAINT SKYBLUE (-3125 3825);
DISPLAY INVISIBLE (-3125 3825);
FORCEADD OFFPAGE..2
(-2300 3775);
FORCEPROP 2 LAST $XR0 184 
J 0
(-2111 3775);
DISPLAY 0.638298 (-2111 3775);
PAINT MONO (-2111 3775);
FORCEPROP 2 LAST CDS_LIB standard
J 0
(-2300 3775);
DISPLAY INVISIBLE (-2300 3775);
FORCEPROP 1 LAST OFFPAGE TRUE
J 0
(-1975 3650);
DISPLAY 0.872340 (-1975 3650);
PAINT GREEN (-1975 3650);
DISPLAY INVISIBLE (-1975 3650);
FORCEPROP 1 LAST COMMENT_BODY TRUE
J 0
(-2345 3680);
DISPLAY 0.872340 (-2345 3680);
PAINT GREEN (-2345 3680);
DISPLAY INVISIBLE (-2345 3680);
FORCEPROP 2 LAST PATH I331
J 0
(-2125 3850);
DISPLAY 0.680851 (-2125 3850);
DISPLAY INVISIBLE (-2125 3850);
FORCEADD Q_RES..1
(-3225 3925);
FORCEPROP 1 LAST LOCATION R6781
J 0
(-3100 3925);
DISPLAY 0.489362 (-3100 3925);
PAINT SKYBLUE (-3100 3925);
FORCEPROP 0 LAST $SEC 1
J 0
(-3100 3950);
DISPLAY 0.680851 (-3100 3950);
PAINT MONO (-3100 3950);
DISPLAY INVISIBLE (-3100 3950);
FORCEPROP 0 LAST CDS_SEC 1
J 0
(-3100 3950);
DISPLAY 0.680851 (-3100 3950);
DISPLAY INVISIBLE (-3100 3950);
FORCEPROP 1 LASTPIN (-3325 3925) $PN 1
J 0
(-3313 3937);
DISPLAY 0.787234 (-3313 3937);
PAINT MONO (-3313 3937);
FORCEPROP 1 LASTPIN (-3125 3925) $PN 2
J 0
(-3163 3937);
DISPLAY 0.787234 (-3163 3937);
PAINT MONO (-3163 3937);
FORCEPROP 1 LAST VALUE 0
J 2
(-3350 3925);
DISPLAY 0.489362 (-3350 3925);
PAINT SKYBLUE (-3350 3925);
FORCEPROP 2 LAST CDS_LIB pure_quanta
J 0
(-3225 3925);
DISPLAY INVISIBLE (-3225 3925);
FORCEPROP 2 LAST BOM_COST MEM
J 2
(-3200 4075);
DISPLAY 0.744681 (-3200 4075);
PAINT WHITE (-3200 4075);
DISPLAY INVISIBLE (-3200 4075);
FORCEPROP 1 LAST WATTAGE 1/16W
J 2
(-3300 3850);
DISPLAY 0.489362 (-3300 3850);
PAINT SKYBLUE (-3300 3850);
DISPLAY INVISIBLE (-3300 3850);
FORCEPROP 1 LAST MATERIAL CHIP
J 2
(-3050 3900);
DISPLAY 0.489362 (-3050 3900);
PAINT SKYBLUE (-3050 3900);
DISPLAY INVISIBLE (-3050 3900);
FORCEPROP 1 LAST TOLERANCE 5%
J 0
(-3350 3900);
DISPLAY 0.489362 (-3350 3900);
PAINT SKYBLUE (-3350 3900);
DISPLAY INVISIBLE (-3350 3900);
FORCEPROP 1 LAST PACK_TYPE 0402LF
J 2
(-3050 3850);
DISPLAY 0.489362 (-3050 3850);
PAINT SKYBLUE (-3050 3850);
DISPLAY INVISIBLE (-3050 3850);
FORCEPROP 1 LAST PATH I332
J 0
(-3275 4075);
DISPLAY 0.978723 (-3275 4075);
PAINT WHITE (-3275 4075);
DISPLAY INVISIBLE (-3275 4075);
FORCEPROP 1 LAST PART_NUMBER CS00002JB13
J 2
(-3125 3975);
DISPLAY 0.489362 (-3125 3975);
PAINT SKYBLUE (-3125 3975);
DISPLAY INVISIBLE (-3125 3975);
FORCEADD OFFPAGE..2
(-2275 3925);
FORCEPROP 2 LAST $XR1 186 
J 0
(-1966 3925);
DISPLAY 0.638298 (-1966 3925);
PAINT MONO (-1966 3925);
FORCEPROP 2 LAST $XR0 185 
J 0
(-2086 3925);
DISPLAY 0.638298 (-2086 3925);
PAINT MONO (-2086 3925);
FORCEPROP 2 LAST CDS_LIB standard
J 0
(-2275 3925);
DISPLAY INVISIBLE (-2275 3925);
FORCEPROP 1 LAST OFFPAGE TRUE
J 0
(-1950 3800);
DISPLAY 0.872340 (-1950 3800);
PAINT GREEN (-1950 3800);
DISPLAY INVISIBLE (-1950 3800);
FORCEPROP 1 LAST COMMENT_BODY TRUE
J 0
(-2320 3830);
DISPLAY 0.872340 (-2320 3830);
PAINT GREEN (-2320 3830);
DISPLAY INVISIBLE (-2320 3830);
FORCEPROP 2 LAST PATH I333
J 0
(-2100 4000);
DISPLAY 0.680851 (-2100 4000);
DISPLAY INVISIBLE (-2100 4000);
FORCEADD Q_RES..1
(-6425 4425);
FORCEPROP 1 LAST LOCATION R6792
J 0
(-6300 4425);
DISPLAY 0.489362 (-6300 4425);
PAINT SKYBLUE (-6300 4425);
FORCEPROP 0 LAST $SEC 1
J 0
(-6300 4450);
DISPLAY 0.680851 (-6300 4450);
PAINT MONO (-6300 4450);
DISPLAY INVISIBLE (-6300 4450);
FORCEPROP 0 LAST CDS_SEC 1
J 0
(-6300 4450);
DISPLAY 0.680851 (-6300 4450);
DISPLAY INVISIBLE (-6300 4450);
FORCEPROP 1 LASTPIN (-6525 4425) $PN 1
J 0
(-6513 4437);
DISPLAY 0.787234 (-6513 4437);
PAINT MONO (-6513 4437);
FORCEPROP 1 LASTPIN (-6325 4425) $PN 2
J 0
(-6363 4437);
DISPLAY 0.787234 (-6363 4437);
PAINT MONO (-6363 4437);
FORCEPROP 1 LAST VALUE 0
J 2
(-6550 4425);
DISPLAY 0.489362 (-6550 4425);
PAINT SKYBLUE (-6550 4425);
FORCEPROP 2 LAST BOM_COST MEM
J 2
(-6400 4575);
DISPLAY 0.744681 (-6400 4575);
PAINT WHITE (-6400 4575);
DISPLAY INVISIBLE (-6400 4575);
FORCEPROP 1 LAST WATTAGE 1/16W
J 2
(-6500 4350);
DISPLAY 0.489362 (-6500 4350);
PAINT SKYBLUE (-6500 4350);
DISPLAY INVISIBLE (-6500 4350);
FORCEPROP 1 LAST MATERIAL CHIP
J 2
(-6250 4400);
DISPLAY 0.489362 (-6250 4400);
PAINT SKYBLUE (-6250 4400);
DISPLAY INVISIBLE (-6250 4400);
FORCEPROP 1 LAST TOLERANCE 5%
J 0
(-6550 4400);
DISPLAY 0.489362 (-6550 4400);
PAINT SKYBLUE (-6550 4400);
DISPLAY INVISIBLE (-6550 4400);
FORCEPROP 1 LAST PACK_TYPE 0402LF
J 2
(-6250 4350);
DISPLAY 0.489362 (-6250 4350);
PAINT SKYBLUE (-6250 4350);
DISPLAY INVISIBLE (-6250 4350);
FORCEPROP 2 LAST CDS_LIB pure_quanta
J 0
(-6425 4425);
DISPLAY INVISIBLE (-6425 4425);
FORCEPROP 1 LAST PATH I334
J 0
(-6475 4575);
DISPLAY 0.978723 (-6475 4575);
PAINT WHITE (-6475 4575);
DISPLAY INVISIBLE (-6475 4575);
FORCEPROP 1 LAST PART_NUMBER CS00002JB13
J 2
(-6325 4475);
DISPLAY 0.489362 (-6325 4475);
PAINT SKYBLUE (-6325 4475);
DISPLAY INVISIBLE (-6325 4475);
FORCEADD Q_RES..1
(-6425 4375);
FORCEPROP 1 LAST LOCATION R6793
J 0
(-6300 4375);
DISPLAY 0.489362 (-6300 4375);
PAINT SKYBLUE (-6300 4375);
FORCEPROP 0 LAST $SEC 1
J 0
(-6300 4400);
DISPLAY 0.680851 (-6300 4400);
PAINT MONO (-6300 4400);
DISPLAY INVISIBLE (-6300 4400);
FORCEPROP 0 LAST CDS_SEC 1
J 0
(-6300 4400);
DISPLAY 0.680851 (-6300 4400);
DISPLAY INVISIBLE (-6300 4400);
FORCEPROP 1 LASTPIN (-6525 4375) $PN 1
J 0
(-6513 4387);
DISPLAY 0.787234 (-6513 4387);
PAINT MONO (-6513 4387);
FORCEPROP 1 LASTPIN (-6325 4375) $PN 2
J 0
(-6363 4387);
DISPLAY 0.787234 (-6363 4387);
PAINT MONO (-6363 4387);
FORCEPROP 1 LAST VALUE 0
J 2
(-6550 4375);
DISPLAY 0.489362 (-6550 4375);
PAINT SKYBLUE (-6550 4375);
FORCEPROP 1 LAST PACK_TYPE 0402LF
J 2
(-6250 4300);
DISPLAY 0.489362 (-6250 4300);
PAINT SKYBLUE (-6250 4300);
DISPLAY INVISIBLE (-6250 4300);
FORCEPROP 1 LAST TOLERANCE 5%
J 0
(-6550 4350);
DISPLAY 0.489362 (-6550 4350);
PAINT SKYBLUE (-6550 4350);
DISPLAY INVISIBLE (-6550 4350);
FORCEPROP 1 LAST MATERIAL CHIP
J 2
(-6250 4350);
DISPLAY 0.489362 (-6250 4350);
PAINT SKYBLUE (-6250 4350);
DISPLAY INVISIBLE (-6250 4350);
FORCEPROP 1 LAST WATTAGE 1/16W
J 2
(-6500 4300);
DISPLAY 0.489362 (-6500 4300);
PAINT SKYBLUE (-6500 4300);
DISPLAY INVISIBLE (-6500 4300);
FORCEPROP 2 LAST BOM_COST MEM
J 2
(-6400 4525);
DISPLAY 0.744681 (-6400 4525);
PAINT WHITE (-6400 4525);
DISPLAY INVISIBLE (-6400 4525);
FORCEPROP 2 LAST CDS_LIB pure_quanta
J 0
(-6425 4375);
DISPLAY INVISIBLE (-6425 4375);
FORCEPROP 1 LAST PATH I335
J 0
(-6475 4525);
DISPLAY 0.978723 (-6475 4525);
PAINT WHITE (-6475 4525);
DISPLAY INVISIBLE (-6475 4525);
FORCEPROP 1 LAST PART_NUMBER CS00002JB13
J 2
(-6325 4425);
DISPLAY 0.489362 (-6325 4425);
PAINT SKYBLUE (-6325 4425);
DISPLAY INVISIBLE (-6325 4425);
FORCEADD OFFPAGE..2
R 2
(-7350 4425);
FORCEPROP 2 LAST $XR0 343 
J 0
(-7605 4425);
DISPLAY 0.638298 (-7605 4425);
PAINT MONO (-7605 4425);
FORCEPROP 2 LAST CDS_LIB standard
J 0
(-7350 4425);
DISPLAY INVISIBLE (-7350 4425);
FORCEPROP 1 LAST OFFPAGE TRUE
J 2
(-7675 4300);
DISPLAY 0.872340 (-7675 4300);
PAINT GREEN (-7675 4300);
DISPLAY INVISIBLE (-7675 4300);
FORCEPROP 1 LAST COMMENT_BODY TRUE
J 2
(-7305 4330);
DISPLAY 0.872340 (-7305 4330);
PAINT GREEN (-7305 4330);
DISPLAY INVISIBLE (-7305 4330);
FORCEPROP 2 LAST PATH I336
J 0
(-7300 4500);
DISPLAY 0.680851 (-7300 4500);
DISPLAY INVISIBLE (-7300 4500);
FORCEADD OFFPAGE..2
R 2
(-7350 4375);
FORCEPROP 2 LAST $XR0 343 
J 0
(-7605 4375);
DISPLAY 0.638298 (-7605 4375);
PAINT MONO (-7605 4375);
FORCEPROP 2 LAST CDS_LIB standard
J 0
(-7350 4375);
DISPLAY INVISIBLE (-7350 4375);
FORCEPROP 1 LAST OFFPAGE TRUE
J 2
(-7675 4250);
DISPLAY 0.872340 (-7675 4250);
PAINT GREEN (-7675 4250);
DISPLAY INVISIBLE (-7675 4250);
FORCEPROP 1 LAST COMMENT_BODY TRUE
J 2
(-7305 4280);
DISPLAY 0.872340 (-7305 4280);
PAINT GREEN (-7305 4280);
DISPLAY INVISIBLE (-7305 4280);
FORCEPROP 2 LAST PATH I337
J 0
(-7300 4450);
DISPLAY 0.680851 (-7300 4450);
DISPLAY INVISIBLE (-7300 4450);
FORCEADD Q_RES..1
(-6425 4075);
FORCEPROP 1 LAST LOCATION R6798
J 0
(-6300 4075);
DISPLAY 0.489362 (-6300 4075);
PAINT SKYBLUE (-6300 4075);
FORCEPROP 0 LAST $SEC 1
J 0
(-6300 4100);
DISPLAY 0.680851 (-6300 4100);
PAINT MONO (-6300 4100);
DISPLAY INVISIBLE (-6300 4100);
FORCEPROP 0 LAST CDS_SEC 1
J 0
(-6300 4100);
DISPLAY 0.680851 (-6300 4100);
DISPLAY INVISIBLE (-6300 4100);
FORCEPROP 1 LASTPIN (-6525 4075) $PN 1
J 0
(-6513 4087);
DISPLAY 0.787234 (-6513 4087);
PAINT MONO (-6513 4087);
FORCEPROP 1 LASTPIN (-6325 4075) $PN 2
J 0
(-6363 4087);
DISPLAY 0.787234 (-6363 4087);
PAINT MONO (-6363 4087);
FORCEPROP 1 LAST VALUE 0
J 2
(-6550 4075);
DISPLAY 0.489362 (-6550 4075);
PAINT SKYBLUE (-6550 4075);
FORCEPROP 2 LAST CDS_LIB pure_quanta
J 0
(-6425 4075);
DISPLAY INVISIBLE (-6425 4075);
FORCEPROP 2 LAST BOM_COST MEM
J 2
(-6400 4225);
DISPLAY 0.744681 (-6400 4225);
PAINT WHITE (-6400 4225);
DISPLAY INVISIBLE (-6400 4225);
FORCEPROP 1 LAST WATTAGE 1/16W
J 2
(-6500 4000);
DISPLAY 0.489362 (-6500 4000);
PAINT SKYBLUE (-6500 4000);
DISPLAY INVISIBLE (-6500 4000);
FORCEPROP 1 LAST MATERIAL CHIP
J 2
(-6250 4050);
DISPLAY 0.489362 (-6250 4050);
PAINT SKYBLUE (-6250 4050);
DISPLAY INVISIBLE (-6250 4050);
FORCEPROP 1 LAST TOLERANCE 5%
J 0
(-6550 4050);
DISPLAY 0.489362 (-6550 4050);
PAINT SKYBLUE (-6550 4050);
DISPLAY INVISIBLE (-6550 4050);
FORCEPROP 1 LAST PACK_TYPE 0402LF
J 2
(-6250 4000);
DISPLAY 0.489362 (-6250 4000);
PAINT SKYBLUE (-6250 4000);
DISPLAY INVISIBLE (-6250 4000);
FORCEPROP 1 LAST PATH I338
J 0
(-6475 4225);
DISPLAY 0.978723 (-6475 4225);
PAINT WHITE (-6475 4225);
DISPLAY INVISIBLE (-6475 4225);
FORCEPROP 1 LAST PART_NUMBER CS00002JB13
J 2
(-6325 4125);
DISPLAY 0.489362 (-6325 4125);
PAINT SKYBLUE (-6325 4125);
DISPLAY INVISIBLE (-6325 4125);
FORCEADD Q_RES..1
(-6425 4025);
FORCEPROP 1 LAST LOCATION R6799
J 0
(-6300 4025);
DISPLAY 0.489362 (-6300 4025);
PAINT SKYBLUE (-6300 4025);
FORCEPROP 0 LAST $SEC 1
J 0
(-6300 4050);
DISPLAY 0.680851 (-6300 4050);
PAINT MONO (-6300 4050);
DISPLAY INVISIBLE (-6300 4050);
FORCEPROP 0 LAST CDS_SEC 1
J 0
(-6300 4050);
DISPLAY 0.680851 (-6300 4050);
DISPLAY INVISIBLE (-6300 4050);
FORCEPROP 1 LASTPIN (-6525 4025) $PN 1
J 0
(-6513 4037);
DISPLAY 0.787234 (-6513 4037);
PAINT MONO (-6513 4037);
FORCEPROP 1 LASTPIN (-6325 4025) $PN 2
J 0
(-6363 4037);
DISPLAY 0.787234 (-6363 4037);
PAINT MONO (-6363 4037);
FORCEPROP 1 LAST VALUE 0
J 2
(-6550 4025);
DISPLAY 0.489362 (-6550 4025);
PAINT SKYBLUE (-6550 4025);
FORCEPROP 1 LAST PACK_TYPE 0402LF
J 2
(-6250 3950);
DISPLAY 0.489362 (-6250 3950);
PAINT SKYBLUE (-6250 3950);
DISPLAY INVISIBLE (-6250 3950);
FORCEPROP 1 LAST TOLERANCE 5%
J 0
(-6550 4000);
DISPLAY 0.489362 (-6550 4000);
PAINT SKYBLUE (-6550 4000);
DISPLAY INVISIBLE (-6550 4000);
FORCEPROP 1 LAST MATERIAL CHIP
J 2
(-6250 4000);
DISPLAY 0.489362 (-6250 4000);
PAINT SKYBLUE (-6250 4000);
DISPLAY INVISIBLE (-6250 4000);
FORCEPROP 1 LAST WATTAGE 1/16W
J 2
(-6500 3950);
DISPLAY 0.489362 (-6500 3950);
PAINT SKYBLUE (-6500 3950);
DISPLAY INVISIBLE (-6500 3950);
FORCEPROP 2 LAST BOM_COST MEM
J 2
(-6400 4175);
DISPLAY 0.744681 (-6400 4175);
PAINT WHITE (-6400 4175);
DISPLAY INVISIBLE (-6400 4175);
FORCEPROP 2 LAST CDS_LIB pure_quanta
J 0
(-6425 4025);
DISPLAY INVISIBLE (-6425 4025);
FORCEPROP 1 LAST PATH I339
J 0
(-6475 4175);
DISPLAY 0.978723 (-6475 4175);
PAINT WHITE (-6475 4175);
DISPLAY INVISIBLE (-6475 4175);
FORCEPROP 1 LAST PART_NUMBER CS00002JB13
J 2
(-6325 4075);
DISPLAY 0.489362 (-6325 4075);
PAINT SKYBLUE (-6325 4075);
DISPLAY INVISIBLE (-6325 4075);
FORCEADD Q_RES..1
(-6725 1825);
FORCEPROP 1 LAST LOCATION R6047
J 0
(-6600 1825);
DISPLAY 0.489362 (-6600 1825);
PAINT SKYBLUE (-6600 1825);
FORCEPROP 0 LAST $SEC 1
J 0
(-6600 1875);
DISPLAY 0.680851 (-6600 1875);
PAINT MONO (-6600 1875);
DISPLAY INVISIBLE (-6600 1875);
FORCEPROP 0 LAST CDS_SEC 1
J 0
(-6600 1875);
DISPLAY 1.021277 (-6600 1875);
DISPLAY INVISIBLE (-6600 1875);
FORCEPROP 1 LASTPIN (-6825 1825) $PN 1
J 0
(-6813 1837);
DISPLAY 0.489362 (-6813 1837);
PAINT MONO (-6813 1837);
FORCEPROP 1 LASTPIN (-6625 1825) $PN 2
J 0
(-6663 1837);
DISPLAY 0.489362 (-6663 1837);
PAINT MONO (-6663 1837);
FORCEPROP 1 LAST VALUE 0
J 2
(-6850 1825);
DISPLAY 0.489362 (-6850 1825);
PAINT SKYBLUE (-6850 1825);
FORCEPROP 1 LAST PACK_TYPE 0402LF
J 2
(-6550 1750);
DISPLAY 0.489362 (-6550 1750);
PAINT SKYBLUE (-6550 1750);
DISPLAY INVISIBLE (-6550 1750);
FORCEPROP 1 LAST TOLERANCE 5%
J 0
(-6850 1800);
DISPLAY 0.489362 (-6850 1800);
PAINT SKYBLUE (-6850 1800);
DISPLAY INVISIBLE (-6850 1800);
FORCEPROP 1 LAST MATERIAL CHIP
J 2
(-6550 1800);
DISPLAY 0.489362 (-6550 1800);
PAINT SKYBLUE (-6550 1800);
DISPLAY INVISIBLE (-6550 1800);
FORCEPROP 1 LAST WATTAGE 1/16W
J 2
(-6800 1750);
DISPLAY 0.489362 (-6800 1750);
PAINT SKYBLUE (-6800 1750);
DISPLAY INVISIBLE (-6800 1750);
FORCEPROP 2 LAST BOM_COST MEM
J 2
(-6700 1975);
DISPLAY 0.744681 (-6700 1975);
PAINT WHITE (-6700 1975);
DISPLAY INVISIBLE (-6700 1975);
FORCEPROP 2 LAST CDS_LIB pure_quanta
J 2
(-6725 1825);
DISPLAY INVISIBLE (-6725 1825);
FORCEPROP 1 LAST PATH I34
J 0
(-6775 1975);
DISPLAY 0.978723 (-6775 1975);
PAINT WHITE (-6775 1975);
DISPLAY INVISIBLE (-6775 1975);
FORCEPROP 1 LAST PART_NUMBER CS00002JB13
J 2
(-6625 1875);
DISPLAY 0.489362 (-6625 1875);
PAINT SKYBLUE (-6625 1875);
DISPLAY INVISIBLE (-6625 1875);
FORCEADD OFFPAGE..2
R 2
(-7350 4075);
FORCEPROP 2 LAST $XR0 354 
J 0
(-7605 4075);
DISPLAY 0.638298 (-7605 4075);
PAINT MONO (-7605 4075);
FORCEPROP 2 LAST CDS_LIB standard
J 0
(-7350 4075);
DISPLAY INVISIBLE (-7350 4075);
FORCEPROP 1 LAST OFFPAGE TRUE
J 2
(-7675 3950);
DISPLAY 0.872340 (-7675 3950);
PAINT GREEN (-7675 3950);
DISPLAY INVISIBLE (-7675 3950);
FORCEPROP 1 LAST COMMENT_BODY TRUE
J 2
(-7305 3980);
DISPLAY 0.872340 (-7305 3980);
PAINT GREEN (-7305 3980);
DISPLAY INVISIBLE (-7305 3980);
FORCEPROP 2 LAST PATH I340
J 0
(-7300 4150);
DISPLAY 0.680851 (-7300 4150);
DISPLAY INVISIBLE (-7300 4150);
FORCEADD OFFPAGE..2
R 2
(-7350 4025);
FORCEPROP 2 LAST $XR0 354 
J 0
(-7605 4025);
DISPLAY 0.638298 (-7605 4025);
PAINT MONO (-7605 4025);
FORCEPROP 2 LAST CDS_LIB standard
J 0
(-7350 4025);
DISPLAY INVISIBLE (-7350 4025);
FORCEPROP 1 LAST OFFPAGE TRUE
J 2
(-7675 3900);
DISPLAY 0.872340 (-7675 3900);
PAINT GREEN (-7675 3900);
DISPLAY INVISIBLE (-7675 3900);
FORCEPROP 1 LAST COMMENT_BODY TRUE
J 2
(-7305 3930);
DISPLAY 0.872340 (-7305 3930);
PAINT GREEN (-7305 3930);
DISPLAY INVISIBLE (-7305 3930);
FORCEPROP 2 LAST PATH I341
J 0
(-7300 4100);
DISPLAY 0.680851 (-7300 4100);
DISPLAY INVISIBLE (-7300 4100);
FORCEADD Q_RES..1
(-6425 3975);
FORCEPROP 1 LAST LOCATION R6804
J 0
(-6300 3975);
DISPLAY 0.489362 (-6300 3975);
PAINT SKYBLUE (-6300 3975);
FORCEPROP 0 LAST $SEC 1
J 0
(-6300 4000);
DISPLAY 0.680851 (-6300 4000);
PAINT MONO (-6300 4000);
DISPLAY INVISIBLE (-6300 4000);
FORCEPROP 0 LAST CDS_SEC 1
J 0
(-6300 4000);
DISPLAY 0.680851 (-6300 4000);
DISPLAY INVISIBLE (-6300 4000);
FORCEPROP 1 LASTPIN (-6525 3975) $PN 1
J 0
(-6513 3987);
DISPLAY 0.787234 (-6513 3987);
PAINT MONO (-6513 3987);
FORCEPROP 1 LASTPIN (-6325 3975) $PN 2
J 0
(-6363 3987);
DISPLAY 0.787234 (-6363 3987);
PAINT MONO (-6363 3987);
FORCEPROP 1 LAST VALUE 0
J 2
(-6550 3975);
DISPLAY 0.489362 (-6550 3975);
PAINT SKYBLUE (-6550 3975);
FORCEPROP 2 LAST CDS_LIB pure_quanta
J 0
(-6425 3975);
DISPLAY INVISIBLE (-6425 3975);
FORCEPROP 1 LAST PACK_TYPE 0402LF
J 2
(-6250 3900);
DISPLAY 0.489362 (-6250 3900);
PAINT SKYBLUE (-6250 3900);
DISPLAY INVISIBLE (-6250 3900);
FORCEPROP 1 LAST TOLERANCE 5%
J 0
(-6550 3950);
DISPLAY 0.489362 (-6550 3950);
PAINT SKYBLUE (-6550 3950);
DISPLAY INVISIBLE (-6550 3950);
FORCEPROP 1 LAST MATERIAL CHIP
J 2
(-6250 3950);
DISPLAY 0.489362 (-6250 3950);
PAINT SKYBLUE (-6250 3950);
DISPLAY INVISIBLE (-6250 3950);
FORCEPROP 1 LAST WATTAGE 1/16W
J 2
(-6500 3900);
DISPLAY 0.489362 (-6500 3900);
PAINT SKYBLUE (-6500 3900);
DISPLAY INVISIBLE (-6500 3900);
FORCEPROP 2 LAST BOM_COST MEM
J 2
(-6400 4125);
DISPLAY 0.744681 (-6400 4125);
PAINT WHITE (-6400 4125);
DISPLAY INVISIBLE (-6400 4125);
FORCEPROP 1 LAST PATH I342
J 0
(-6475 4125);
DISPLAY 0.978723 (-6475 4125);
PAINT WHITE (-6475 4125);
DISPLAY INVISIBLE (-6475 4125);
FORCEPROP 1 LAST PART_NUMBER CS00002JB13
J 2
(-6325 4025);
DISPLAY 0.489362 (-6325 4025);
PAINT SKYBLUE (-6325 4025);
DISPLAY INVISIBLE (-6325 4025);
FORCEADD Q_RES..1
(-6425 3925);
FORCEPROP 1 LAST LOCATION R6805
J 0
(-6300 3925);
DISPLAY 0.489362 (-6300 3925);
PAINT SKYBLUE (-6300 3925);
FORCEPROP 0 LAST $SEC 1
J 0
(-6300 3950);
DISPLAY 0.680851 (-6300 3950);
PAINT MONO (-6300 3950);
DISPLAY INVISIBLE (-6300 3950);
FORCEPROP 0 LAST CDS_SEC 1
J 0
(-6300 3950);
DISPLAY 0.680851 (-6300 3950);
DISPLAY INVISIBLE (-6300 3950);
FORCEPROP 1 LASTPIN (-6525 3925) $PN 1
J 0
(-6513 3937);
DISPLAY 0.787234 (-6513 3937);
PAINT MONO (-6513 3937);
FORCEPROP 1 LASTPIN (-6325 3925) $PN 2
J 0
(-6363 3937);
DISPLAY 0.787234 (-6363 3937);
PAINT MONO (-6363 3937);
FORCEPROP 1 LAST VALUE 0
J 2
(-6550 3925);
DISPLAY 0.489362 (-6550 3925);
PAINT SKYBLUE (-6550 3925);
FORCEPROP 2 LAST BOM_COST MEM
J 2
(-6400 4075);
DISPLAY 0.744681 (-6400 4075);
PAINT WHITE (-6400 4075);
DISPLAY INVISIBLE (-6400 4075);
FORCEPROP 1 LAST WATTAGE 1/16W
J 2
(-6500 3850);
DISPLAY 0.489362 (-6500 3850);
PAINT SKYBLUE (-6500 3850);
DISPLAY INVISIBLE (-6500 3850);
FORCEPROP 1 LAST MATERIAL CHIP
J 2
(-6250 3900);
DISPLAY 0.489362 (-6250 3900);
PAINT SKYBLUE (-6250 3900);
DISPLAY INVISIBLE (-6250 3900);
FORCEPROP 1 LAST TOLERANCE 5%
J 0
(-6550 3900);
DISPLAY 0.489362 (-6550 3900);
PAINT SKYBLUE (-6550 3900);
DISPLAY INVISIBLE (-6550 3900);
FORCEPROP 1 LAST PACK_TYPE 0402LF
J 2
(-6250 3850);
DISPLAY 0.489362 (-6250 3850);
PAINT SKYBLUE (-6250 3850);
DISPLAY INVISIBLE (-6250 3850);
FORCEPROP 2 LAST CDS_LIB pure_quanta
J 0
(-6425 3925);
DISPLAY INVISIBLE (-6425 3925);
FORCEPROP 1 LAST PATH I343
J 0
(-6475 4075);
DISPLAY 0.978723 (-6475 4075);
PAINT WHITE (-6475 4075);
DISPLAY INVISIBLE (-6475 4075);
FORCEPROP 1 LAST PART_NUMBER CS00002JB13
J 2
(-6325 3975);
DISPLAY 0.489362 (-6325 3975);
PAINT SKYBLUE (-6325 3975);
DISPLAY INVISIBLE (-6325 3975);
FORCEADD Q_RES..1
(-6425 3875);
FORCEPROP 1 LAST LOCATION R6806
J 0
(-6300 3875);
DISPLAY 0.489362 (-6300 3875);
PAINT SKYBLUE (-6300 3875);
FORCEPROP 0 LAST $SEC 1
J 0
(-6300 3900);
DISPLAY 0.680851 (-6300 3900);
PAINT MONO (-6300 3900);
DISPLAY INVISIBLE (-6300 3900);
FORCEPROP 0 LAST CDS_SEC 1
J 0
(-6300 3900);
DISPLAY 0.680851 (-6300 3900);
DISPLAY INVISIBLE (-6300 3900);
FORCEPROP 1 LASTPIN (-6525 3875) $PN 1
J 0
(-6513 3887);
DISPLAY 0.787234 (-6513 3887);
PAINT MONO (-6513 3887);
FORCEPROP 1 LASTPIN (-6325 3875) $PN 2
J 0
(-6363 3887);
DISPLAY 0.787234 (-6363 3887);
PAINT MONO (-6363 3887);
FORCEPROP 1 LAST VALUE 0
J 2
(-6550 3875);
DISPLAY 0.489362 (-6550 3875);
PAINT SKYBLUE (-6550 3875);
FORCEPROP 2 LAST CDS_LIB pure_quanta
J 0
(-6425 3875);
DISPLAY INVISIBLE (-6425 3875);
FORCEPROP 2 LAST BOM_COST MEM
J 2
(-6400 4025);
DISPLAY 0.744681 (-6400 4025);
PAINT WHITE (-6400 4025);
DISPLAY INVISIBLE (-6400 4025);
FORCEPROP 1 LAST WATTAGE 1/16W
J 2
(-6500 3800);
DISPLAY 0.489362 (-6500 3800);
PAINT SKYBLUE (-6500 3800);
DISPLAY INVISIBLE (-6500 3800);
FORCEPROP 1 LAST MATERIAL CHIP
J 2
(-6250 3850);
DISPLAY 0.489362 (-6250 3850);
PAINT SKYBLUE (-6250 3850);
DISPLAY INVISIBLE (-6250 3850);
FORCEPROP 1 LAST TOLERANCE 5%
J 0
(-6550 3850);
DISPLAY 0.489362 (-6550 3850);
PAINT SKYBLUE (-6550 3850);
DISPLAY INVISIBLE (-6550 3850);
FORCEPROP 1 LAST PACK_TYPE 0402LF
J 2
(-6250 3800);
DISPLAY 0.489362 (-6250 3800);
PAINT SKYBLUE (-6250 3800);
DISPLAY INVISIBLE (-6250 3800);
FORCEPROP 1 LAST PATH I344
J 0
(-6475 4025);
DISPLAY 0.978723 (-6475 4025);
PAINT WHITE (-6475 4025);
DISPLAY INVISIBLE (-6475 4025);
FORCEPROP 1 LAST PART_NUMBER CS00002JB13
J 2
(-6325 3925);
DISPLAY 0.489362 (-6325 3925);
PAINT SKYBLUE (-6325 3925);
DISPLAY INVISIBLE (-6325 3925);
FORCEADD Q_RES..1
(-6425 3825);
FORCEPROP 1 LAST LOCATION R6807
J 0
(-6300 3825);
DISPLAY 0.489362 (-6300 3825);
PAINT SKYBLUE (-6300 3825);
FORCEPROP 0 LAST $SEC 1
J 0
(-6300 3850);
DISPLAY 0.680851 (-6300 3850);
PAINT MONO (-6300 3850);
DISPLAY INVISIBLE (-6300 3850);
FORCEPROP 0 LAST CDS_SEC 1
J 0
(-6300 3850);
DISPLAY 0.680851 (-6300 3850);
DISPLAY INVISIBLE (-6300 3850);
FORCEPROP 1 LASTPIN (-6525 3825) $PN 1
J 0
(-6513 3837);
DISPLAY 0.787234 (-6513 3837);
PAINT MONO (-6513 3837);
FORCEPROP 1 LASTPIN (-6325 3825) $PN 2
J 0
(-6363 3837);
DISPLAY 0.787234 (-6363 3837);
PAINT MONO (-6363 3837);
FORCEPROP 1 LAST VALUE 0
J 2
(-6550 3825);
DISPLAY 0.489362 (-6550 3825);
PAINT SKYBLUE (-6550 3825);
FORCEPROP 2 LAST CDS_LIB pure_quanta
J 0
(-6425 3825);
DISPLAY INVISIBLE (-6425 3825);
FORCEPROP 1 LAST PACK_TYPE 0402LF
J 2
(-6250 3750);
DISPLAY 0.489362 (-6250 3750);
PAINT SKYBLUE (-6250 3750);
DISPLAY INVISIBLE (-6250 3750);
FORCEPROP 1 LAST TOLERANCE 5%
J 0
(-6550 3800);
DISPLAY 0.489362 (-6550 3800);
PAINT SKYBLUE (-6550 3800);
DISPLAY INVISIBLE (-6550 3800);
FORCEPROP 1 LAST MATERIAL CHIP
J 2
(-6250 3800);
DISPLAY 0.489362 (-6250 3800);
PAINT SKYBLUE (-6250 3800);
DISPLAY INVISIBLE (-6250 3800);
FORCEPROP 1 LAST WATTAGE 1/16W
J 2
(-6500 3750);
DISPLAY 0.489362 (-6500 3750);
PAINT SKYBLUE (-6500 3750);
DISPLAY INVISIBLE (-6500 3750);
FORCEPROP 2 LAST BOM_COST MEM
J 2
(-6400 3975);
DISPLAY 0.744681 (-6400 3975);
PAINT WHITE (-6400 3975);
DISPLAY INVISIBLE (-6400 3975);
FORCEPROP 1 LAST PATH I345
J 0
(-6475 3975);
DISPLAY 0.978723 (-6475 3975);
PAINT WHITE (-6475 3975);
DISPLAY INVISIBLE (-6475 3975);
FORCEPROP 1 LAST PART_NUMBER CS00002JB13
J 2
(-6325 3875);
DISPLAY 0.489362 (-6325 3875);
PAINT SKYBLUE (-6325 3875);
DISPLAY INVISIBLE (-6325 3875);
FORCEADD OFFPAGE..2
R 2
(-7350 3975);
FORCEPROP 2 LAST $XR0 277 
J 0
(-7605 3975);
DISPLAY 0.638298 (-7605 3975);
PAINT MONO (-7605 3975);
FORCEPROP 2 LAST CDS_LIB standard
J 0
(-7350 3975);
DISPLAY INVISIBLE (-7350 3975);
FORCEPROP 1 LAST OFFPAGE TRUE
J 2
(-7675 3850);
DISPLAY 0.872340 (-7675 3850);
PAINT GREEN (-7675 3850);
DISPLAY INVISIBLE (-7675 3850);
FORCEPROP 1 LAST COMMENT_BODY TRUE
J 2
(-7305 3880);
DISPLAY 0.872340 (-7305 3880);
PAINT GREEN (-7305 3880);
DISPLAY INVISIBLE (-7305 3880);
FORCEPROP 2 LAST PATH I346
J 0
(-7300 4050);
DISPLAY 0.680851 (-7300 4050);
DISPLAY INVISIBLE (-7300 4050);
FORCEADD OFFPAGE..2
R 2
(-7350 3925);
FORCEPROP 2 LAST $XR0 277 
J 0
(-7605 3925);
DISPLAY 0.638298 (-7605 3925);
PAINT MONO (-7605 3925);
FORCEPROP 2 LAST CDS_LIB standard
J 0
(-7350 3925);
DISPLAY INVISIBLE (-7350 3925);
FORCEPROP 1 LAST OFFPAGE TRUE
J 2
(-7675 3800);
DISPLAY 0.872340 (-7675 3800);
PAINT GREEN (-7675 3800);
DISPLAY INVISIBLE (-7675 3800);
FORCEPROP 1 LAST COMMENT_BODY TRUE
J 2
(-7305 3830);
DISPLAY 0.872340 (-7305 3830);
PAINT GREEN (-7305 3830);
DISPLAY INVISIBLE (-7305 3830);
FORCEPROP 2 LAST PATH I347
J 0
(-7300 4000);
DISPLAY 0.680851 (-7300 4000);
DISPLAY INVISIBLE (-7300 4000);
FORCEADD OFFPAGE..2
R 2
(-7350 3875);
FORCEPROP 2 LAST $XR0 288 
J 0
(-7605 3875);
DISPLAY 0.638298 (-7605 3875);
PAINT MONO (-7605 3875);
FORCEPROP 2 LAST CDS_LIB standard
J 0
(-7350 3875);
DISPLAY INVISIBLE (-7350 3875);
FORCEPROP 1 LAST OFFPAGE TRUE
J 2
(-7675 3750);
DISPLAY 0.872340 (-7675 3750);
PAINT GREEN (-7675 3750);
DISPLAY INVISIBLE (-7675 3750);
FORCEPROP 1 LAST COMMENT_BODY TRUE
J 2
(-7305 3780);
DISPLAY 0.872340 (-7305 3780);
PAINT GREEN (-7305 3780);
DISPLAY INVISIBLE (-7305 3780);
FORCEPROP 2 LAST PATH I348
J 0
(-7300 3950);
DISPLAY 0.680851 (-7300 3950);
DISPLAY INVISIBLE (-7300 3950);
FORCEADD OFFPAGE..2
R 2
(-7350 3825);
FORCEPROP 2 LAST $XR0 288 
J 0
(-7605 3825);
DISPLAY 0.638298 (-7605 3825);
PAINT MONO (-7605 3825);
FORCEPROP 2 LAST CDS_LIB standard
J 0
(-7350 3825);
DISPLAY INVISIBLE (-7350 3825);
FORCEPROP 1 LAST OFFPAGE TRUE
J 2
(-7675 3700);
DISPLAY 0.872340 (-7675 3700);
PAINT GREEN (-7675 3700);
DISPLAY INVISIBLE (-7675 3700);
FORCEPROP 1 LAST COMMENT_BODY TRUE
J 2
(-7305 3730);
DISPLAY 0.872340 (-7305 3730);
PAINT GREEN (-7305 3730);
DISPLAY INVISIBLE (-7305 3730);
FORCEPROP 2 LAST PATH I349
J 0
(-7300 3900);
DISPLAY 0.680851 (-7300 3900);
DISPLAY INVISIBLE (-7300 3900);
FORCEADD Q_RES..1
(-6725 2025);
FORCEPROP 1 LAST LOCATION R5099
J 0
(-6600 2025);
DISPLAY 0.489362 (-6600 2025);
PAINT SKYBLUE (-6600 2025);
FORCEPROP 0 LAST $SEC 1
J 0
(-6600 2075);
DISPLAY 0.680851 (-6600 2075);
PAINT MONO (-6600 2075);
DISPLAY INVISIBLE (-6600 2075);
FORCEPROP 0 LAST CDS_SEC 1
J 0
(-6600 2075);
DISPLAY 1.021277 (-6600 2075);
DISPLAY INVISIBLE (-6600 2075);
FORCEPROP 1 LASTPIN (-6825 2025) $PN 1
J 0
(-6813 2037);
DISPLAY 0.489362 (-6813 2037);
PAINT MONO (-6813 2037);
FORCEPROP 1 LASTPIN (-6625 2025) $PN 2
J 0
(-6663 2037);
DISPLAY 0.489362 (-6663 2037);
PAINT MONO (-6663 2037);
FORCEPROP 1 LAST VALUE 0
J 2
(-6850 2025);
DISPLAY 0.489362 (-6850 2025);
PAINT SKYBLUE (-6850 2025);
FORCEPROP 2 LAST CDS_LIB pure_quanta
J 2
(-6725 2025);
DISPLAY INVISIBLE (-6725 2025);
FORCEPROP 2 LAST BOM_COST MEM
J 2
(-6700 2175);
DISPLAY 0.744681 (-6700 2175);
PAINT WHITE (-6700 2175);
DISPLAY INVISIBLE (-6700 2175);
FORCEPROP 1 LAST WATTAGE 1/16W
J 2
(-6800 1950);
DISPLAY 0.489362 (-6800 1950);
PAINT SKYBLUE (-6800 1950);
DISPLAY INVISIBLE (-6800 1950);
FORCEPROP 1 LAST MATERIAL CHIP
J 2
(-6550 2000);
DISPLAY 0.489362 (-6550 2000);
PAINT SKYBLUE (-6550 2000);
DISPLAY INVISIBLE (-6550 2000);
FORCEPROP 1 LAST TOLERANCE 5%
J 0
(-6850 2000);
DISPLAY 0.489362 (-6850 2000);
PAINT SKYBLUE (-6850 2000);
DISPLAY INVISIBLE (-6850 2000);
FORCEPROP 1 LAST PACK_TYPE 0402LF
J 2
(-6550 1950);
DISPLAY 0.489362 (-6550 1950);
PAINT SKYBLUE (-6550 1950);
DISPLAY INVISIBLE (-6550 1950);
FORCEPROP 1 LAST PATH I35
J 0
(-6775 2175);
DISPLAY 0.978723 (-6775 2175);
PAINT WHITE (-6775 2175);
DISPLAY INVISIBLE (-6775 2175);
FORCEPROP 1 LAST PART_NUMBER CS00002JB13
J 2
(-6625 2075);
DISPLAY 0.489362 (-6625 2075);
PAINT SKYBLUE (-6625 2075);
DISPLAY INVISIBLE (-6625 2075);
FORCEADD Q_RES..1
(-3225 5825);
FORCEPROP 1 LAST LOCATION R6823
J 0
(-3100 5825);
DISPLAY 0.489362 (-3100 5825);
PAINT SKYBLUE (-3100 5825);
FORCEPROP 0 LAST $SEC 1
J 0
(-3100 5850);
DISPLAY 0.680851 (-3100 5850);
PAINT MONO (-3100 5850);
DISPLAY INVISIBLE (-3100 5850);
FORCEPROP 0 LAST CDS_SEC 1
J 0
(-3100 5850);
DISPLAY 0.680851 (-3100 5850);
DISPLAY INVISIBLE (-3100 5850);
FORCEPROP 1 LASTPIN (-3325 5825) $PN 1
J 0
(-3313 5837);
DISPLAY 0.787234 (-3313 5837);
PAINT MONO (-3313 5837);
FORCEPROP 1 LASTPIN (-3125 5825) $PN 2
J 0
(-3163 5837);
DISPLAY 0.787234 (-3163 5837);
PAINT MONO (-3163 5837);
FORCEPROP 1 LAST VALUE 0
J 2
(-3350 5825);
DISPLAY 0.489362 (-3350 5825);
PAINT SKYBLUE (-3350 5825);
FORCEPROP 2 LAST CDS_LIB pure_quanta
J 0
(-3225 5825);
DISPLAY INVISIBLE (-3225 5825);
FORCEPROP 2 LAST BOM_COST MEM
J 2
(-3200 5975);
DISPLAY 0.744681 (-3200 5975);
PAINT WHITE (-3200 5975);
DISPLAY INVISIBLE (-3200 5975);
FORCEPROP 1 LAST WATTAGE 1/16W
J 2
(-3300 5750);
DISPLAY 0.489362 (-3300 5750);
PAINT SKYBLUE (-3300 5750);
DISPLAY INVISIBLE (-3300 5750);
FORCEPROP 1 LAST MATERIAL CHIP
J 2
(-3050 5800);
DISPLAY 0.489362 (-3050 5800);
PAINT SKYBLUE (-3050 5800);
DISPLAY INVISIBLE (-3050 5800);
FORCEPROP 1 LAST TOLERANCE 5%
J 0
(-3350 5800);
DISPLAY 0.489362 (-3350 5800);
PAINT SKYBLUE (-3350 5800);
DISPLAY INVISIBLE (-3350 5800);
FORCEPROP 1 LAST PACK_TYPE 0402LF
J 2
(-3050 5750);
DISPLAY 0.489362 (-3050 5750);
PAINT SKYBLUE (-3050 5750);
DISPLAY INVISIBLE (-3050 5750);
FORCEPROP 1 LAST PATH I350
J 0
(-3275 5975);
DISPLAY 0.978723 (-3275 5975);
PAINT WHITE (-3275 5975);
DISPLAY INVISIBLE (-3275 5975);
FORCEPROP 1 LAST PART_NUMBER CS00002JB13
J 2
(-3125 5875);
DISPLAY 0.489362 (-3125 5875);
PAINT SKYBLUE (-3125 5875);
DISPLAY INVISIBLE (-3125 5875);
FORCEADD Q_RES..1
(-3225 4875);
FORCEPROP 1 LAST LOCATION R6824
J 0
(-3100 4875);
DISPLAY 0.489362 (-3100 4875);
PAINT SKYBLUE (-3100 4875);
FORCEPROP 0 LAST $SEC 1
J 0
(-3100 4900);
DISPLAY 0.680851 (-3100 4900);
PAINT MONO (-3100 4900);
DISPLAY INVISIBLE (-3100 4900);
FORCEPROP 0 LAST CDS_SEC 1
J 0
(-3100 4900);
DISPLAY 0.680851 (-3100 4900);
DISPLAY INVISIBLE (-3100 4900);
FORCEPROP 1 LASTPIN (-3325 4875) $PN 1
J 0
(-3313 4887);
DISPLAY 0.787234 (-3313 4887);
PAINT MONO (-3313 4887);
FORCEPROP 1 LASTPIN (-3125 4875) $PN 2
J 0
(-3163 4887);
DISPLAY 0.787234 (-3163 4887);
PAINT MONO (-3163 4887);
FORCEPROP 1 LAST VALUE 0
J 2
(-3350 4875);
DISPLAY 0.489362 (-3350 4875);
PAINT SKYBLUE (-3350 4875);
FORCEPROP 2 LAST CDS_LIB pure_quanta
J 0
(-3225 4875);
DISPLAY INVISIBLE (-3225 4875);
FORCEPROP 1 LAST PACK_TYPE 0402LF
J 2
(-3050 4800);
DISPLAY 0.489362 (-3050 4800);
PAINT SKYBLUE (-3050 4800);
DISPLAY INVISIBLE (-3050 4800);
FORCEPROP 1 LAST TOLERANCE 5%
J 0
(-3350 4850);
DISPLAY 0.489362 (-3350 4850);
PAINT SKYBLUE (-3350 4850);
DISPLAY INVISIBLE (-3350 4850);
FORCEPROP 1 LAST MATERIAL CHIP
J 2
(-3050 4850);
DISPLAY 0.489362 (-3050 4850);
PAINT SKYBLUE (-3050 4850);
DISPLAY INVISIBLE (-3050 4850);
FORCEPROP 1 LAST WATTAGE 1/16W
J 2
(-3300 4800);
DISPLAY 0.489362 (-3300 4800);
PAINT SKYBLUE (-3300 4800);
DISPLAY INVISIBLE (-3300 4800);
FORCEPROP 2 LAST BOM_COST MEM
J 2
(-3200 5025);
DISPLAY 0.744681 (-3200 5025);
PAINT WHITE (-3200 5025);
DISPLAY INVISIBLE (-3200 5025);
FORCEPROP 1 LAST PATH I351
J 0
(-3275 5025);
DISPLAY 0.978723 (-3275 5025);
PAINT WHITE (-3275 5025);
DISPLAY INVISIBLE (-3275 5025);
FORCEPROP 1 LAST PART_NUMBER CS00002JB13
J 2
(-3125 4925);
DISPLAY 0.489362 (-3125 4925);
PAINT SKYBLUE (-3125 4925);
DISPLAY INVISIBLE (-3125 4925);
FORCEADD Q_RES..1
(-3225 4525);
FORCEPROP 1 LAST LOCATION R6825
J 0
(-3100 4525);
DISPLAY 0.489362 (-3100 4525);
PAINT SKYBLUE (-3100 4525);
FORCEPROP 0 LAST $SEC 1
J 0
(-3100 4550);
DISPLAY 0.680851 (-3100 4550);
PAINT MONO (-3100 4550);
DISPLAY INVISIBLE (-3100 4550);
FORCEPROP 0 LAST CDS_SEC 1
J 0
(-3100 4550);
DISPLAY 0.680851 (-3100 4550);
DISPLAY INVISIBLE (-3100 4550);
FORCEPROP 1 LASTPIN (-3325 4525) $PN 1
J 0
(-3313 4537);
DISPLAY 0.787234 (-3313 4537);
PAINT MONO (-3313 4537);
FORCEPROP 1 LASTPIN (-3125 4525) $PN 2
J 0
(-3163 4537);
DISPLAY 0.787234 (-3163 4537);
PAINT MONO (-3163 4537);
FORCEPROP 1 LAST VALUE 0
J 2
(-3350 4525);
DISPLAY 0.489362 (-3350 4525);
PAINT SKYBLUE (-3350 4525);
FORCEPROP 1 LAST PACK_TYPE 0402LF
J 2
(-3050 4450);
DISPLAY 0.489362 (-3050 4450);
PAINT SKYBLUE (-3050 4450);
DISPLAY INVISIBLE (-3050 4450);
FORCEPROP 1 LAST TOLERANCE 5%
J 0
(-3350 4500);
DISPLAY 0.489362 (-3350 4500);
PAINT SKYBLUE (-3350 4500);
DISPLAY INVISIBLE (-3350 4500);
FORCEPROP 1 LAST MATERIAL CHIP
J 2
(-3050 4500);
DISPLAY 0.489362 (-3050 4500);
PAINT SKYBLUE (-3050 4500);
DISPLAY INVISIBLE (-3050 4500);
FORCEPROP 1 LAST WATTAGE 1/16W
J 2
(-3300 4450);
DISPLAY 0.489362 (-3300 4450);
PAINT SKYBLUE (-3300 4450);
DISPLAY INVISIBLE (-3300 4450);
FORCEPROP 2 LAST BOM_COST MEM
J 2
(-3200 4675);
DISPLAY 0.744681 (-3200 4675);
PAINT WHITE (-3200 4675);
DISPLAY INVISIBLE (-3200 4675);
FORCEPROP 2 LAST CDS_LIB pure_quanta
J 0
(-3225 4525);
DISPLAY INVISIBLE (-3225 4525);
FORCEPROP 1 LAST PATH I352
J 0
(-3275 4675);
DISPLAY 0.978723 (-3275 4675);
PAINT WHITE (-3275 4675);
DISPLAY INVISIBLE (-3275 4675);
FORCEPROP 1 LAST PART_NUMBER CS00002JB13
J 2
(-3125 4575);
DISPLAY 0.489362 (-3125 4575);
PAINT SKYBLUE (-3125 4575);
DISPLAY INVISIBLE (-3125 4575);
FORCEADD Q_RES..1
(-3225 4425);
FORCEPROP 1 LAST LOCATION R6826
J 0
(-3100 4425);
DISPLAY 0.489362 (-3100 4425);
PAINT SKYBLUE (-3100 4425);
FORCEPROP 0 LAST $SEC 1
J 0
(-3100 4450);
DISPLAY 0.680851 (-3100 4450);
PAINT MONO (-3100 4450);
DISPLAY INVISIBLE (-3100 4450);
FORCEPROP 0 LAST CDS_SEC 1
J 0
(-3100 4450);
DISPLAY 0.680851 (-3100 4450);
DISPLAY INVISIBLE (-3100 4450);
FORCEPROP 1 LASTPIN (-3325 4425) $PN 1
J 0
(-3313 4437);
DISPLAY 0.787234 (-3313 4437);
PAINT MONO (-3313 4437);
FORCEPROP 1 LASTPIN (-3125 4425) $PN 2
J 0
(-3163 4437);
DISPLAY 0.787234 (-3163 4437);
PAINT MONO (-3163 4437);
FORCEPROP 1 LAST VALUE 0
J 2
(-3350 4425);
DISPLAY 0.489362 (-3350 4425);
PAINT SKYBLUE (-3350 4425);
FORCEPROP 1 LAST PACK_TYPE 0402LF
J 2
(-3050 4350);
DISPLAY 0.489362 (-3050 4350);
PAINT SKYBLUE (-3050 4350);
DISPLAY INVISIBLE (-3050 4350);
FORCEPROP 1 LAST TOLERANCE 5%
J 0
(-3350 4400);
DISPLAY 0.489362 (-3350 4400);
PAINT SKYBLUE (-3350 4400);
DISPLAY INVISIBLE (-3350 4400);
FORCEPROP 1 LAST MATERIAL CHIP
J 2
(-3050 4400);
DISPLAY 0.489362 (-3050 4400);
PAINT SKYBLUE (-3050 4400);
DISPLAY INVISIBLE (-3050 4400);
FORCEPROP 1 LAST WATTAGE 1/16W
J 2
(-3300 4350);
DISPLAY 0.489362 (-3300 4350);
PAINT SKYBLUE (-3300 4350);
DISPLAY INVISIBLE (-3300 4350);
FORCEPROP 2 LAST BOM_COST MEM
J 2
(-3200 4575);
DISPLAY 0.744681 (-3200 4575);
PAINT WHITE (-3200 4575);
DISPLAY INVISIBLE (-3200 4575);
FORCEPROP 2 LAST CDS_LIB pure_quanta
J 0
(-3225 4425);
DISPLAY INVISIBLE (-3225 4425);
FORCEPROP 1 LAST PATH I353
J 0
(-3275 4575);
DISPLAY 0.978723 (-3275 4575);
PAINT WHITE (-3275 4575);
DISPLAY INVISIBLE (-3275 4575);
FORCEPROP 1 LAST PART_NUMBER CS00002JB13
J 2
(-3125 4475);
DISPLAY 0.489362 (-3125 4475);
PAINT SKYBLUE (-3125 4475);
DISPLAY INVISIBLE (-3125 4475);
FORCEADD OFFPAGE..2
(-2300 5825);
FORCEPROP 2 LAST $XR0 299 
J 0
(-2111 5825);
DISPLAY 0.638298 (-2111 5825);
PAINT MONO (-2111 5825);
FORCEPROP 2 LAST CDS_LIB standard
J 0
(-2300 5825);
DISPLAY INVISIBLE (-2300 5825);
FORCEPROP 1 LAST OFFPAGE TRUE
J 0
(-1975 5700);
DISPLAY 0.872340 (-1975 5700);
PAINT GREEN (-1975 5700);
DISPLAY INVISIBLE (-1975 5700);
FORCEPROP 1 LAST COMMENT_BODY TRUE
J 0
(-2345 5730);
DISPLAY 0.872340 (-2345 5730);
PAINT GREEN (-2345 5730);
DISPLAY INVISIBLE (-2345 5730);
FORCEPROP 2 LAST PATH I354
J 0
(-2125 5900);
DISPLAY 0.680851 (-2125 5900);
DISPLAY INVISIBLE (-2125 5900);
FORCEADD OFFPAGE..2
(-2275 4875);
FORCEPROP 2 LAST $XR0 299 
J 0
(-2086 4875);
DISPLAY 0.638298 (-2086 4875);
PAINT MONO (-2086 4875);
FORCEPROP 2 LAST CDS_LIB standard
J 0
(-2275 4875);
DISPLAY INVISIBLE (-2275 4875);
FORCEPROP 1 LAST OFFPAGE TRUE
J 0
(-1950 4750);
DISPLAY 0.872340 (-1950 4750);
PAINT GREEN (-1950 4750);
DISPLAY INVISIBLE (-1950 4750);
FORCEPROP 1 LAST COMMENT_BODY TRUE
J 0
(-2320 4780);
DISPLAY 0.872340 (-2320 4780);
PAINT GREEN (-2320 4780);
DISPLAY INVISIBLE (-2320 4780);
FORCEPROP 2 LAST PATH I355
J 0
(-2100 4950);
DISPLAY 0.680851 (-2100 4950);
DISPLAY INVISIBLE (-2100 4950);
FORCEADD OFFPAGE..2
(-2300 4525);
FORCEPROP 2 LAST $XR0 310 
J 0
(-2111 4525);
DISPLAY 0.638298 (-2111 4525);
PAINT MONO (-2111 4525);
FORCEPROP 2 LAST CDS_LIB standard
J 0
(-2300 4525);
DISPLAY INVISIBLE (-2300 4525);
FORCEPROP 1 LAST OFFPAGE TRUE
J 0
(-1975 4400);
DISPLAY 0.872340 (-1975 4400);
PAINT GREEN (-1975 4400);
DISPLAY INVISIBLE (-1975 4400);
FORCEPROP 1 LAST COMMENT_BODY TRUE
J 0
(-2345 4430);
DISPLAY 0.872340 (-2345 4430);
PAINT GREEN (-2345 4430);
DISPLAY INVISIBLE (-2345 4430);
FORCEPROP 2 LAST PATH I356
J 0
(-2125 4600);
DISPLAY 0.680851 (-2125 4600);
DISPLAY INVISIBLE (-2125 4600);
FORCEADD OFFPAGE..2
(-2300 4425);
FORCEPROP 2 LAST $XR0 310 
J 0
(-2111 4425);
DISPLAY 0.638298 (-2111 4425);
PAINT MONO (-2111 4425);
FORCEPROP 2 LAST CDS_LIB standard
J 0
(-2300 4425);
DISPLAY INVISIBLE (-2300 4425);
FORCEPROP 1 LAST OFFPAGE TRUE
J 0
(-1975 4300);
DISPLAY 0.872340 (-1975 4300);
PAINT GREEN (-1975 4300);
DISPLAY INVISIBLE (-1975 4300);
FORCEPROP 1 LAST COMMENT_BODY TRUE
J 0
(-2345 4330);
DISPLAY 0.872340 (-2345 4330);
PAINT GREEN (-2345 4330);
DISPLAY INVISIBLE (-2345 4330);
FORCEPROP 2 LAST PATH I357
J 0
(-2125 4500);
DISPLAY 0.680851 (-2125 4500);
DISPLAY INVISIBLE (-2125 4500);
FORCEADD OFFPAGE..1
(-7800 1975);
FORCEPROP 2 LAST $XR0 361 
J 0
(-8052 1975);
DISPLAY 0.638298 (-8052 1975);
PAINT MONO (-8052 1975);
FORCEPROP 2 LAST CDS_LIB standard
J 0
(-7800 1975);
DISPLAY INVISIBLE (-7800 1975);
FORCEPROP 1 LAST OFFPAGE TRUE
J 0
(-7475 1850);
DISPLAY 0.872340 (-7475 1850);
PAINT GREEN (-7475 1850);
DISPLAY INVISIBLE (-7475 1850);
FORCEPROP 1 LAST COMMENT_BODY TRUE
J 0
(-7675 1875);
DISPLAY 0.872340 (-7675 1875);
PAINT GREEN (-7675 1875);
DISPLAY INVISIBLE (-7675 1875);
FORCEPROP 2 LAST PATH I358
J 0
(-7750 2050);
DISPLAY 0.680851 (-7750 2050);
DISPLAY INVISIBLE (-7750 2050);
FORCEADD OFFPAGE..1
(-7800 1925);
FORCEPROP 2 LAST $XR0 362 
J 0
(-8052 1925);
DISPLAY 0.638298 (-8052 1925);
PAINT MONO (-8052 1925);
FORCEPROP 2 LAST CDS_LIB standard
J 0
(-7800 1925);
DISPLAY INVISIBLE (-7800 1925);
FORCEPROP 1 LAST OFFPAGE TRUE
J 0
(-7475 1800);
DISPLAY 0.872340 (-7475 1800);
PAINT GREEN (-7475 1800);
DISPLAY INVISIBLE (-7475 1800);
FORCEPROP 1 LAST COMMENT_BODY TRUE
J 0
(-7675 1825);
DISPLAY 0.872340 (-7675 1825);
PAINT GREEN (-7675 1825);
DISPLAY INVISIBLE (-7675 1825);
FORCEPROP 2 LAST PATH I359
J 0
(-7750 2000);
DISPLAY 0.680851 (-7750 2000);
DISPLAY INVISIBLE (-7750 2000);
FORCEADD Q_RES..1
(-6725 1875);
FORCEPROP 1 LAST LOCATION R224
J 0
(-6600 1875);
DISPLAY 0.489362 (-6600 1875);
PAINT SKYBLUE (-6600 1875);
FORCEPROP 0 LAST $SEC 1
J 2
(-6600 1925);
DISPLAY 0.680851 (-6600 1925);
PAINT MONO (-6600 1925);
DISPLAY INVISIBLE (-6600 1925);
FORCEPROP 0 LAST CDS_SEC 1
J 2
(-6600 1925);
DISPLAY 1.021277 (-6600 1925);
DISPLAY INVISIBLE (-6600 1925);
FORCEPROP 1 LASTPIN (-6825 1875) $PN 1
J 0
(-6813 1887);
DISPLAY 0.489362 (-6813 1887);
PAINT MONO (-6813 1887);
FORCEPROP 1 LASTPIN (-6625 1875) $PN 2
J 0
(-6663 1887);
DISPLAY 0.489362 (-6663 1887);
PAINT MONO (-6663 1887);
FORCEPROP 1 LAST VALUE 33
J 2
(-6850 1875);
DISPLAY 0.489362 (-6850 1875);
PAINT SKYBLUE (-6850 1875);
FORCEPROP 2 LAST BOM_COST MEM
J 2
(-6700 2025);
DISPLAY 0.744681 (-6700 2025);
PAINT WHITE (-6700 2025);
DISPLAY INVISIBLE (-6700 2025);
FORCEPROP 2 LAST CDS_LIB pure_quanta
J 2
(-6725 1875);
DISPLAY INVISIBLE (-6725 1875);
FORCEPROP 1 LAST WATTAGE 1/16W
J 2
(-6800 1800);
DISPLAY 0.489362 (-6800 1800);
PAINT SKYBLUE (-6800 1800);
DISPLAY INVISIBLE (-6800 1800);
FORCEPROP 1 LAST MATERIAL CHIP
J 2
(-6550 1850);
DISPLAY 0.489362 (-6550 1850);
PAINT SKYBLUE (-6550 1850);
DISPLAY INVISIBLE (-6550 1850);
FORCEPROP 1 LAST TOLERANCE 5%
J 0
(-6850 1850);
DISPLAY 0.489362 (-6850 1850);
PAINT SKYBLUE (-6850 1850);
DISPLAY INVISIBLE (-6850 1850);
FORCEPROP 1 LAST PACK_TYPE 0402LF
J 2
(-6550 1800);
DISPLAY 0.489362 (-6550 1800);
PAINT SKYBLUE (-6550 1800);
DISPLAY INVISIBLE (-6550 1800);
FORCEPROP 1 LAST PATH I36
J 0
(-6775 2025);
DISPLAY 0.978723 (-6775 2025);
PAINT WHITE (-6775 2025);
DISPLAY INVISIBLE (-6775 2025);
FORCEPROP 1 LAST PART_NUMBER CS03302JB10
J 2
(-6625 1925);
DISPLAY 0.489362 (-6625 1925);
PAINT SKYBLUE (-6625 1925);
DISPLAY INVISIBLE (-6625 1925);
FORCEADD Q_RES..1
(-6425 5875);
FORCEPROP 1 LAST LOCATION R6852
J 0
(-6300 5875);
DISPLAY 0.489362 (-6300 5875);
PAINT SKYBLUE (-6300 5875);
FORCEPROP 0 LAST $SEC 1
J 0
(-6300 5900);
DISPLAY 0.680851 (-6300 5900);
PAINT MONO (-6300 5900);
DISPLAY INVISIBLE (-6300 5900);
FORCEPROP 0 LAST CDS_SEC 1
J 0
(-6300 5900);
DISPLAY 0.680851 (-6300 5900);
DISPLAY INVISIBLE (-6300 5900);
FORCEPROP 1 LASTPIN (-6525 5875) $PN 1
J 0
(-6513 5887);
DISPLAY 0.787234 (-6513 5887);
PAINT MONO (-6513 5887);
FORCEPROP 1 LASTPIN (-6325 5875) $PN 2
J 0
(-6363 5887);
DISPLAY 0.787234 (-6363 5887);
PAINT MONO (-6363 5887);
FORCEPROP 1 LAST VALUE 0
J 2
(-6550 5875);
DISPLAY 0.489362 (-6550 5875);
PAINT SKYBLUE (-6550 5875);
FORCEPROP 2 LAST CDS_LIB pure_quanta
J 0
(-6425 5875);
DISPLAY INVISIBLE (-6425 5875);
FORCEPROP 1 LAST PACK_TYPE 0402LF
J 2
(-6250 5800);
DISPLAY 0.489362 (-6250 5800);
PAINT SKYBLUE (-6250 5800);
DISPLAY INVISIBLE (-6250 5800);
FORCEPROP 1 LAST TOLERANCE 5%
J 0
(-6550 5850);
DISPLAY 0.489362 (-6550 5850);
PAINT SKYBLUE (-6550 5850);
DISPLAY INVISIBLE (-6550 5850);
FORCEPROP 1 LAST MATERIAL CHIP
J 2
(-6250 5850);
DISPLAY 0.489362 (-6250 5850);
PAINT SKYBLUE (-6250 5850);
DISPLAY INVISIBLE (-6250 5850);
FORCEPROP 1 LAST WATTAGE 1/16W
J 2
(-6500 5800);
DISPLAY 0.489362 (-6500 5800);
PAINT SKYBLUE (-6500 5800);
DISPLAY INVISIBLE (-6500 5800);
FORCEPROP 2 LAST BOM_COST MEM
J 2
(-6400 6025);
DISPLAY 0.744681 (-6400 6025);
PAINT WHITE (-6400 6025);
DISPLAY INVISIBLE (-6400 6025);
FORCEPROP 1 LAST PATH I360
J 0
(-6475 6025);
DISPLAY 0.978723 (-6475 6025);
PAINT WHITE (-6475 6025);
DISPLAY INVISIBLE (-6475 6025);
FORCEPROP 1 LAST PART_NUMBER CS00002JB13
J 2
(-6325 5925);
DISPLAY 0.489362 (-6325 5925);
PAINT SKYBLUE (-6325 5925);
DISPLAY INVISIBLE (-6325 5925);
FORCEADD OFFPAGE..4
R 2
(-7350 5875);
FORCEPROP 2 LAST $XR0 363 
J 0
(-7602 5875);
DISPLAY 0.638298 (-7602 5875);
PAINT MONO (-7602 5875);
FORCEPROP 2 LAST CDS_LIB standard
J 0
(-7350 5875);
DISPLAY INVISIBLE (-7350 5875);
FORCEPROP 1 LAST OFFPAGE TRUE
J 2
(-7675 5750);
DISPLAY 0.872340 (-7675 5750);
PAINT GREEN (-7675 5750);
DISPLAY INVISIBLE (-7675 5750);
FORCEPROP 1 LAST COMMENT_BODY TRUE
J 2
(-7325 5775);
DISPLAY 0.872340 (-7325 5775);
PAINT GREEN (-7325 5775);
DISPLAY INVISIBLE (-7325 5775);
FORCEPROP 2 LAST PATH I361
J 0
(-7300 5950);
DISPLAY 0.680851 (-7300 5950);
DISPLAY INVISIBLE (-7300 5950);
FORCEADD Q_RES..1
(-6425 5625);
FORCEPROP 1 LAST LOCATION R6853
J 0
(-6300 5625);
DISPLAY 0.489362 (-6300 5625);
PAINT SKYBLUE (-6300 5625);
FORCEPROP 0 LAST $SEC 1
J 0
(-6300 5650);
DISPLAY 0.680851 (-6300 5650);
PAINT MONO (-6300 5650);
DISPLAY INVISIBLE (-6300 5650);
FORCEPROP 0 LAST CDS_SEC 1
J 0
(-6300 5650);
DISPLAY 0.680851 (-6300 5650);
DISPLAY INVISIBLE (-6300 5650);
FORCEPROP 1 LASTPIN (-6525 5625) $PN 1
J 0
(-6513 5637);
DISPLAY 0.787234 (-6513 5637);
PAINT MONO (-6513 5637);
FORCEPROP 1 LASTPIN (-6325 5625) $PN 2
J 0
(-6363 5637);
DISPLAY 0.787234 (-6363 5637);
PAINT MONO (-6363 5637);
FORCEPROP 1 LAST VALUE 0
J 2
(-6550 5625);
DISPLAY 0.489362 (-6550 5625);
PAINT SKYBLUE (-6550 5625);
FORCEPROP 1 LAST PACK_TYPE 0402LF
J 2
(-6250 5550);
DISPLAY 0.489362 (-6250 5550);
PAINT SKYBLUE (-6250 5550);
DISPLAY INVISIBLE (-6250 5550);
FORCEPROP 1 LAST TOLERANCE 5%
J 0
(-6550 5600);
DISPLAY 0.489362 (-6550 5600);
PAINT SKYBLUE (-6550 5600);
DISPLAY INVISIBLE (-6550 5600);
FORCEPROP 1 LAST MATERIAL CHIP
J 2
(-6250 5600);
DISPLAY 0.489362 (-6250 5600);
PAINT SKYBLUE (-6250 5600);
DISPLAY INVISIBLE (-6250 5600);
FORCEPROP 1 LAST WATTAGE 1/16W
J 2
(-6500 5550);
DISPLAY 0.489362 (-6500 5550);
PAINT SKYBLUE (-6500 5550);
DISPLAY INVISIBLE (-6500 5550);
FORCEPROP 2 LAST BOM_COST MEM
J 2
(-6400 5775);
DISPLAY 0.744681 (-6400 5775);
PAINT WHITE (-6400 5775);
DISPLAY INVISIBLE (-6400 5775);
FORCEPROP 2 LAST CDS_LIB pure_quanta
J 0
(-6425 5625);
DISPLAY INVISIBLE (-6425 5625);
FORCEPROP 1 LAST PATH I362
J 0
(-6475 5775);
DISPLAY 0.978723 (-6475 5775);
PAINT WHITE (-6475 5775);
DISPLAY INVISIBLE (-6475 5775);
FORCEPROP 1 LAST PART_NUMBER CS00002JB13
J 2
(-6325 5675);
DISPLAY 0.489362 (-6325 5675);
PAINT SKYBLUE (-6325 5675);
DISPLAY INVISIBLE (-6325 5675);
FORCEADD OFFPAGE..4
R 2
(-7350 5625);
FORCEPROP 2 LAST $XR0 365 
J 0
(-7602 5625);
DISPLAY 0.638298 (-7602 5625);
PAINT MONO (-7602 5625);
FORCEPROP 2 LAST CDS_LIB standard
J 0
(-7350 5625);
DISPLAY INVISIBLE (-7350 5625);
FORCEPROP 1 LAST OFFPAGE TRUE
J 2
(-7675 5500);
DISPLAY 0.872340 (-7675 5500);
PAINT GREEN (-7675 5500);
DISPLAY INVISIBLE (-7675 5500);
FORCEPROP 1 LAST COMMENT_BODY TRUE
J 2
(-7325 5525);
DISPLAY 0.872340 (-7325 5525);
PAINT GREEN (-7325 5525);
DISPLAY INVISIBLE (-7325 5525);
FORCEPROP 2 LAST PATH I363
J 0
(-7300 5700);
DISPLAY 0.680851 (-7300 5700);
DISPLAY INVISIBLE (-7300 5700);
FORCEADD Q_RES..1
(-6725 1125);
FORCEPROP 1 LAST LOCATION R6854
J 0
(-6600 1125);
DISPLAY 0.489362 (-6600 1125);
PAINT SKYBLUE (-6600 1125);
FORCEPROP 0 LAST $SEC 1
J 0
(-6600 1150);
DISPLAY 0.680851 (-6600 1150);
PAINT MONO (-6600 1150);
DISPLAY INVISIBLE (-6600 1150);
FORCEPROP 0 LAST CDS_SEC 1
J 0
(-6600 1150);
DISPLAY 0.680851 (-6600 1150);
DISPLAY INVISIBLE (-6600 1150);
FORCEPROP 1 LASTPIN (-6825 1125) $PN 1
J 0
(-6813 1137);
DISPLAY 0.787234 (-6813 1137);
PAINT MONO (-6813 1137);
FORCEPROP 1 LASTPIN (-6625 1125) $PN 2
J 0
(-6663 1137);
DISPLAY 0.787234 (-6663 1137);
PAINT MONO (-6663 1137);
FORCEPROP 1 LAST VALUE 33
J 2
(-6850 1125);
DISPLAY 0.489362 (-6850 1125);
PAINT SKYBLUE (-6850 1125);
FORCEPROP 2 LAST BOM_COST MEM
J 2
(-6700 1275);
DISPLAY 0.744681 (-6700 1275);
PAINT WHITE (-6700 1275);
DISPLAY INVISIBLE (-6700 1275);
FORCEPROP 1 LAST WATTAGE 1/16W
J 2
(-6800 1050);
DISPLAY 0.489362 (-6800 1050);
PAINT SKYBLUE (-6800 1050);
DISPLAY INVISIBLE (-6800 1050);
FORCEPROP 1 LAST MATERIAL CHIP
J 2
(-6550 1100);
DISPLAY 0.489362 (-6550 1100);
PAINT SKYBLUE (-6550 1100);
DISPLAY INVISIBLE (-6550 1100);
FORCEPROP 1 LAST TOLERANCE 5%
J 0
(-6850 1100);
DISPLAY 0.489362 (-6850 1100);
PAINT SKYBLUE (-6850 1100);
DISPLAY INVISIBLE (-6850 1100);
FORCEPROP 1 LAST PACK_TYPE 0402LF
J 2
(-6550 1050);
DISPLAY 0.489362 (-6550 1050);
PAINT SKYBLUE (-6550 1050);
DISPLAY INVISIBLE (-6550 1050);
FORCEPROP 2 LAST CDS_LIB pure_quanta
J 0
(-6725 1125);
DISPLAY INVISIBLE (-6725 1125);
FORCEPROP 1 LAST PATH I364
J 0
(-6775 1275);
DISPLAY 0.978723 (-6775 1275);
PAINT WHITE (-6775 1275);
DISPLAY INVISIBLE (-6775 1275);
FORCEPROP 1 LAST PART_NUMBER CS03302JB10
J 2
(-6625 1175);
DISPLAY 0.489362 (-6625 1175);
PAINT SKYBLUE (-6625 1175);
DISPLAY INVISIBLE (-6625 1175);
FORCEADD OFFPAGE..5
(-7800 1125);
FORCEPROP 2 LAST $XR0 363 
J 0
(-8055 1125);
DISPLAY 0.638298 (-8055 1125);
PAINT MONO (-8055 1125);
FORCEPROP 2 LAST CDS_LIB standard
J 0
(-7800 1125);
DISPLAY INVISIBLE (-7800 1125);
FORCEPROP 1 LAST OFFPAGE TRUE
J 0
(-7475 1000);
DISPLAY 0.872340 (-7475 1000);
PAINT GREEN (-7475 1000);
DISPLAY INVISIBLE (-7475 1000);
FORCEPROP 1 LAST COMMENT_BODY TRUE
J 0
(-7700 1050);
DISPLAY 0.872340 (-7700 1050);
PAINT GREEN (-7700 1050);
DISPLAY INVISIBLE (-7700 1050);
FORCEPROP 2 LAST PATH I365
J 0
(-7750 1200);
DISPLAY 0.680851 (-7750 1200);
DISPLAY INVISIBLE (-7750 1200);
FORCEADD Q_RES..1
(-2275 925);
FORCEPROP 1 LAST LOCATION R6855
J 0
(-2150 925);
DISPLAY 0.489362 (-2150 925);
PAINT SKYBLUE (-2150 925);
FORCEPROP 0 LAST $SEC 1
J 0
(-2150 950);
DISPLAY 0.680851 (-2150 950);
PAINT MONO (-2150 950);
DISPLAY INVISIBLE (-2150 950);
FORCEPROP 0 LAST CDS_SEC 1
J 0
(-2150 950);
DISPLAY 0.680851 (-2150 950);
DISPLAY INVISIBLE (-2150 950);
FORCEPROP 1 LASTPIN (-2375 925) $PN 1
J 0
(-2363 937);
DISPLAY 0.787234 (-2363 937);
PAINT MONO (-2363 937);
FORCEPROP 1 LASTPIN (-2175 925) $PN 2
J 0
(-2213 937);
DISPLAY 0.787234 (-2213 937);
PAINT MONO (-2213 937);
FORCEPROP 1 LAST VALUE 33
J 2
(-2400 925);
DISPLAY 0.489362 (-2400 925);
PAINT SKYBLUE (-2400 925);
FORCEPROP 2 LAST CDS_LIB pure_quanta
J 0
(-2275 925);
DISPLAY INVISIBLE (-2275 925);
FORCEPROP 2 LAST BOM_COST MEM
J 2
(-2250 1075);
DISPLAY 0.744681 (-2250 1075);
PAINT WHITE (-2250 1075);
DISPLAY INVISIBLE (-2250 1075);
FORCEPROP 1 LAST WATTAGE 1/16W
J 2
(-2350 850);
DISPLAY 0.489362 (-2350 850);
PAINT SKYBLUE (-2350 850);
DISPLAY INVISIBLE (-2350 850);
FORCEPROP 1 LAST MATERIAL CHIP
J 2
(-2100 900);
DISPLAY 0.489362 (-2100 900);
PAINT SKYBLUE (-2100 900);
DISPLAY INVISIBLE (-2100 900);
FORCEPROP 1 LAST TOLERANCE 5%
J 0
(-2400 900);
DISPLAY 0.489362 (-2400 900);
PAINT SKYBLUE (-2400 900);
DISPLAY INVISIBLE (-2400 900);
FORCEPROP 1 LAST PACK_TYPE 0402LF
J 2
(-2100 850);
DISPLAY 0.489362 (-2100 850);
PAINT SKYBLUE (-2100 850);
DISPLAY INVISIBLE (-2100 850);
FORCEPROP 1 LAST PATH I366
J 0
(-2325 1075);
DISPLAY 0.978723 (-2325 1075);
PAINT WHITE (-2325 1075);
DISPLAY INVISIBLE (-2325 1075);
FORCEPROP 1 LAST PART_NUMBER CS03302JB10
J 2
(-2175 975);
DISPLAY 0.489362 (-2175 975);
PAINT SKYBLUE (-2175 975);
DISPLAY INVISIBLE (-2175 975);
FORCEADD OFFPAGE..2
(-775 925);
FORCEPROP 2 LAST $XR0 365 
J 0
(-586 925);
DISPLAY 0.638298 (-586 925);
PAINT MONO (-586 925);
FORCEPROP 2 LAST CDS_LIB standard
J 0
(-775 925);
DISPLAY INVISIBLE (-775 925);
FORCEPROP 1 LAST OFFPAGE TRUE
J 0
(-450 800);
DISPLAY 0.872340 (-450 800);
PAINT GREEN (-450 800);
DISPLAY INVISIBLE (-450 800);
FORCEPROP 1 LAST COMMENT_BODY TRUE
J 0
(-820 830);
DISPLAY 0.872340 (-820 830);
PAINT GREEN (-820 830);
DISPLAY INVISIBLE (-820 830);
FORCEPROP 2 LAST PATH I367
J 0
(-600 1000);
DISPLAY 0.680851 (-600 1000);
DISPLAY INVISIBLE (-600 1000);
FORCEADD OFFPAGE..1
(-7800 2125);
FORCEPROP 2 LAST $XR0 224 
J 0
(-8052 2125);
DISPLAY 0.638298 (-8052 2125);
PAINT MONO (-8052 2125);
FORCEPROP 2 LAST CDS_LIB standard
J 0
(-7800 2125);
DISPLAY INVISIBLE (-7800 2125);
FORCEPROP 1 LAST OFFPAGE TRUE
J 0
(-7475 2000);
DISPLAY 0.872340 (-7475 2000);
PAINT GREEN (-7475 2000);
DISPLAY INVISIBLE (-7475 2000);
FORCEPROP 1 LAST COMMENT_BODY TRUE
J 0
(-7675 2025);
DISPLAY 0.872340 (-7675 2025);
PAINT GREEN (-7675 2025);
DISPLAY INVISIBLE (-7675 2025);
FORCEPROP 2 LAST PATH I37
J 0
(-8075 2175);
DISPLAY 0.680851 (-8075 2175);
DISPLAY INVISIBLE (-8075 2175);
FORCEADD OFFPAGE..1
(-7800 2325);
FORCEPROP 2 LAST $XR0 192 
J 0
(-8052 2325);
DISPLAY 0.638298 (-8052 2325);
PAINT MONO (-8052 2325);
FORCEPROP 2 LAST CDS_LIB standard
J 0
(-7800 2325);
DISPLAY INVISIBLE (-7800 2325);
FORCEPROP 1 LAST OFFPAGE TRUE
J 0
(-7475 2200);
DISPLAY 0.872340 (-7475 2200);
PAINT GREEN (-7475 2200);
DISPLAY INVISIBLE (-7475 2200);
FORCEPROP 1 LAST COMMENT_BODY TRUE
J 0
(-7675 2225);
DISPLAY 0.872340 (-7675 2225);
PAINT GREEN (-7675 2225);
DISPLAY INVISIBLE (-7675 2225);
FORCEPROP 2 LAST PATH I40
J 0
(-8075 2375);
DISPLAY 0.680851 (-8075 2375);
DISPLAY INVISIBLE (-8075 2375);
FORCEADD OFFPAGE..1
(-7800 2375);
FORCEPROP 2 LAST $XR0 226 
J 0
(-8052 2375);
DISPLAY 0.638298 (-8052 2375);
PAINT MONO (-8052 2375);
FORCEPROP 2 LAST CDS_LIB standard
J 0
(-7800 2375);
DISPLAY INVISIBLE (-7800 2375);
FORCEPROP 1 LAST OFFPAGE TRUE
J 0
(-7475 2250);
DISPLAY 0.872340 (-7475 2250);
PAINT GREEN (-7475 2250);
DISPLAY INVISIBLE (-7475 2250);
FORCEPROP 1 LAST COMMENT_BODY TRUE
J 0
(-7675 2275);
DISPLAY 0.872340 (-7675 2275);
PAINT GREEN (-7675 2275);
DISPLAY INVISIBLE (-7675 2275);
FORCEPROP 2 LAST PATH I41
J 0
(-8075 2425);
DISPLAY 0.680851 (-8075 2425);
DISPLAY INVISIBLE (-8075 2425);
FORCEADD OFFPAGE..1
(-7800 2425);
FORCEPROP 2 LAST $XR0 152 
J 0
(-8052 2425);
DISPLAY 0.638298 (-8052 2425);
PAINT MONO (-8052 2425);
FORCEPROP 2 LAST CDS_LIB standard
J 0
(-7800 2425);
DISPLAY INVISIBLE (-7800 2425);
FORCEPROP 1 LAST OFFPAGE TRUE
J 0
(-7475 2300);
DISPLAY 0.872340 (-7475 2300);
PAINT GREEN (-7475 2300);
DISPLAY INVISIBLE (-7475 2300);
FORCEPROP 1 LAST COMMENT_BODY TRUE
J 0
(-7675 2325);
DISPLAY 0.872340 (-7675 2325);
PAINT GREEN (-7675 2325);
DISPLAY INVISIBLE (-7675 2325);
FORCEPROP 2 LAST PATH I42
J 0
(-8075 2475);
DISPLAY 0.680851 (-8075 2475);
DISPLAY INVISIBLE (-8075 2475);
FORCEADD OFFPAGE..1
(-7800 2475);
FORCEPROP 2 LAST $XR0 210 
J 0
(-8052 2475);
DISPLAY 0.638298 (-8052 2475);
PAINT MONO (-8052 2475);
FORCEPROP 2 LAST CDS_LIB standard
J 0
(-7800 2475);
DISPLAY INVISIBLE (-7800 2475);
FORCEPROP 1 LAST OFFPAGE TRUE
J 0
(-7475 2350);
DISPLAY 0.872340 (-7475 2350);
PAINT GREEN (-7475 2350);
DISPLAY INVISIBLE (-7475 2350);
FORCEPROP 1 LAST COMMENT_BODY TRUE
J 0
(-7675 2375);
DISPLAY 0.872340 (-7675 2375);
PAINT GREEN (-7675 2375);
DISPLAY INVISIBLE (-7675 2375);
FORCEPROP 2 LAST PATH I43
J 0
(-8075 2525);
DISPLAY 0.680851 (-8075 2525);
DISPLAY INVISIBLE (-8075 2525);
FORCEADD OFFPAGE..5
(-7800 2175);
FORCEPROP 2 LAST $XR0 224 
J 0
(-8055 2175);
DISPLAY 0.638298 (-8055 2175);
PAINT MONO (-8055 2175);
FORCEPROP 2 LAST CDS_LIB standard
J 0
(-7800 2175);
DISPLAY INVISIBLE (-7800 2175);
FORCEPROP 1 LAST OFFPAGE TRUE
J 0
(-7475 2050);
DISPLAY 0.872340 (-7475 2050);
PAINT GREEN (-7475 2050);
DISPLAY INVISIBLE (-7475 2050);
FORCEPROP 1 LAST COMMENT_BODY TRUE
J 0
(-7700 2100);
DISPLAY 0.872340 (-7700 2100);
PAINT GREEN (-7700 2100);
DISPLAY INVISIBLE (-7700 2100);
FORCEPROP 2 LAST PATH I46
J 0
(-8075 2225);
DISPLAY 0.680851 (-8075 2225);
DISPLAY INVISIBLE (-8075 2225);
FORCEADD OFFPAGE..1
(-7800 2625);
FORCEPROP 2 LAST $XR0 217 
J 0
(-8052 2625);
DISPLAY 0.638298 (-8052 2625);
PAINT MONO (-8052 2625);
FORCEPROP 2 LAST CDS_LIB standard
J 0
(-7800 2625);
DISPLAY INVISIBLE (-7800 2625);
FORCEPROP 1 LAST OFFPAGE TRUE
J 0
(-7475 2500);
DISPLAY 0.872340 (-7475 2500);
PAINT GREEN (-7475 2500);
DISPLAY INVISIBLE (-7475 2500);
FORCEPROP 1 LAST COMMENT_BODY TRUE
J 0
(-7675 2525);
DISPLAY 0.872340 (-7675 2525);
PAINT GREEN (-7675 2525);
DISPLAY INVISIBLE (-7675 2525);
FORCEPROP 2 LAST PATH I47
J 0
(-8075 2675);
DISPLAY 0.680851 (-8075 2675);
DISPLAY INVISIBLE (-8075 2675);
FORCEADD OFFPAGE..1
(-7800 2875);
FORCEPROP 2 LAST $XR0 207 
J 0
(-8052 2875);
DISPLAY 0.638298 (-8052 2875);
PAINT MONO (-8052 2875);
FORCEPROP 2 LAST CDS_LIB standard
J 0
(-7800 2875);
DISPLAY INVISIBLE (-7800 2875);
FORCEPROP 1 LAST OFFPAGE TRUE
J 0
(-7475 2750);
DISPLAY 0.872340 (-7475 2750);
PAINT GREEN (-7475 2750);
DISPLAY INVISIBLE (-7475 2750);
FORCEPROP 1 LAST COMMENT_BODY TRUE
J 0
(-7675 2775);
DISPLAY 0.872340 (-7675 2775);
PAINT GREEN (-7675 2775);
DISPLAY INVISIBLE (-7675 2775);
FORCEPROP 2 LAST PATH I49
J 0
(-8075 2925);
DISPLAY 0.680851 (-8075 2925);
DISPLAY INVISIBLE (-8075 2925);
FORCEADD OFFPAGE..5
(-7800 575);
FORCEPROP 2 LAST $XR2 147 
J 0
(-8264 575);
DISPLAY 0.638298 (-8264 575);
PAINT MONO (-8264 575);
FORCEPROP 2 LAST $XR1 146 
J 0
(-8144 575);
DISPLAY 0.638298 (-8144 575);
PAINT MONO (-8144 575);
FORCEPROP 2 LAST $XR0 83 
J 0
(-8024 575);
DISPLAY 0.638298 (-8024 575);
PAINT MONO (-8024 575);
FORCEPROP 2 LAST CDS_LIB standard
J 0
(-7800 575);
DISPLAY INVISIBLE (-7800 575);
FORCEPROP 1 LAST OFFPAGE TRUE
J 0
(-7475 450);
DISPLAY 0.872340 (-7475 450);
PAINT GREEN (-7475 450);
DISPLAY INVISIBLE (-7475 450);
FORCEPROP 1 LAST COMMENT_BODY TRUE
J 0
(-7700 500);
DISPLAY 0.872340 (-7700 500);
PAINT GREEN (-7700 500);
DISPLAY INVISIBLE (-7700 500);
FORCEPROP 2 LAST PATH I5
J 0
(-8000 625);
DISPLAY 0.680851 (-8000 625);
DISPLAY INVISIBLE (-8000 625);
FORCEADD OFFPAGE..4
R 2
(-7800 2925);
FORCEPROP 2 LAST $XR1 193 
J 0
(-8141 2925);
DISPLAY 0.638298 (-8141 2925);
PAINT MONO (-8141 2925);
FORCEPROP 2 LAST $XR0 83 
J 0
(-8021 2925);
DISPLAY 0.638298 (-8021 2925);
PAINT MONO (-8021 2925);
FORCEPROP 2 LAST CDS_LIB standard
J 0
(-7800 2925);
DISPLAY INVISIBLE (-7800 2925);
FORCEPROP 1 LAST OFFPAGE TRUE
J 2
(-8125 2800);
DISPLAY 0.872340 (-8125 2800);
PAINT GREEN (-8125 2800);
DISPLAY INVISIBLE (-8125 2800);
FORCEPROP 1 LAST COMMENT_BODY TRUE
J 2
(-7775 2825);
DISPLAY 0.872340 (-7775 2825);
PAINT GREEN (-7775 2825);
DISPLAY INVISIBLE (-7775 2825);
FORCEPROP 2 LAST PATH I50
J 0
(-8050 2975);
DISPLAY 0.680851 (-8050 2975);
DISPLAY INVISIBLE (-8050 2975);
FORCEADD OFFPAGE..4
R 2
(-7800 2975);
FORCEPROP 2 LAST $XR0 134 
J 0
(-8052 2975);
DISPLAY 0.638298 (-8052 2975);
PAINT MONO (-8052 2975);
FORCEPROP 2 LAST CDS_LIB standard
J 0
(-7800 2975);
DISPLAY INVISIBLE (-7800 2975);
FORCEPROP 1 LAST OFFPAGE TRUE
J 2
(-8125 2850);
DISPLAY 0.872340 (-8125 2850);
PAINT GREEN (-8125 2850);
DISPLAY INVISIBLE (-8125 2850);
FORCEPROP 1 LAST COMMENT_BODY TRUE
J 2
(-7775 2875);
DISPLAY 0.872340 (-7775 2875);
PAINT GREEN (-7775 2875);
DISPLAY INVISIBLE (-7775 2875);
FORCEPROP 2 LAST PATH I51
J 0
(-8075 3025);
DISPLAY 0.680851 (-8075 3025);
DISPLAY INVISIBLE (-8075 3025);
FORCEADD OFFPAGE..1
(-7800 3025);
FORCEPROP 2 LAST $XR0 200 
J 0
(-8052 3025);
DISPLAY 0.638298 (-8052 3025);
PAINT MONO (-8052 3025);
FORCEPROP 2 LAST CDS_LIB standard
J 0
(-7800 3025);
DISPLAY INVISIBLE (-7800 3025);
FORCEPROP 1 LAST OFFPAGE TRUE
J 0
(-7475 2900);
DISPLAY 0.872340 (-7475 2900);
PAINT GREEN (-7475 2900);
DISPLAY INVISIBLE (-7475 2900);
FORCEPROP 1 LAST COMMENT_BODY TRUE
J 0
(-7675 2925);
DISPLAY 0.872340 (-7675 2925);
PAINT GREEN (-7675 2925);
DISPLAY INVISIBLE (-7675 2925);
FORCEPROP 2 LAST PATH I52
J 0
(-8075 3075);
DISPLAY 0.680851 (-8075 3075);
DISPLAY INVISIBLE (-8075 3075);
FORCEADD OFFPAGE..5
(-7800 2825);
FORCEPROP 2 LAST $XR0 210 
J 0
(-8055 2825);
DISPLAY 0.638298 (-8055 2825);
PAINT MONO (-8055 2825);
FORCEPROP 2 LAST CDS_LIB standard
J 0
(-7800 2825);
DISPLAY INVISIBLE (-7800 2825);
FORCEPROP 1 LAST OFFPAGE TRUE
J 0
(-7475 2700);
DISPLAY 0.872340 (-7475 2700);
PAINT GREEN (-7475 2700);
DISPLAY INVISIBLE (-7475 2700);
FORCEPROP 1 LAST COMMENT_BODY TRUE
J 0
(-7700 2750);
DISPLAY 0.872340 (-7700 2750);
PAINT GREEN (-7700 2750);
DISPLAY INVISIBLE (-7700 2750);
FORCEPROP 2 LAST PATH I53
J 0
(-8050 2875);
DISPLAY 0.680851 (-8050 2875);
DISPLAY INVISIBLE (-8050 2875);
FORCEADD OFFPAGE..5
(-7800 2675);
FORCEPROP 2 LAST $XR0 164 
J 0
(-8055 2675);
DISPLAY 0.638298 (-8055 2675);
PAINT MONO (-8055 2675);
FORCEPROP 2 LAST CDS_LIB standard
J 0
(-7800 2675);
DISPLAY INVISIBLE (-7800 2675);
FORCEPROP 1 LAST OFFPAGE TRUE
J 0
(-7475 2550);
DISPLAY 0.872340 (-7475 2550);
PAINT GREEN (-7475 2550);
DISPLAY INVISIBLE (-7475 2550);
FORCEPROP 1 LAST COMMENT_BODY TRUE
J 0
(-7700 2600);
DISPLAY 0.872340 (-7700 2600);
PAINT GREEN (-7700 2600);
DISPLAY INVISIBLE (-7700 2600);
FORCEPROP 2 LAST PATH I54
J 0
(-8050 2725);
DISPLAY 0.680851 (-8050 2725);
DISPLAY INVISIBLE (-8050 2725);
FORCEADD OFFPAGE..5
(-7800 3075);
FORCEPROP 2 LAST $XR0 200 
J 0
(-8055 3075);
DISPLAY 0.638298 (-8055 3075);
PAINT MONO (-8055 3075);
FORCEPROP 2 LAST CDS_LIB standard
J 0
(-7800 3075);
DISPLAY INVISIBLE (-7800 3075);
FORCEPROP 1 LAST OFFPAGE TRUE
J 0
(-7475 2950);
DISPLAY 0.872340 (-7475 2950);
PAINT GREEN (-7475 2950);
DISPLAY INVISIBLE (-7475 2950);
FORCEPROP 1 LAST COMMENT_BODY TRUE
J 0
(-7700 3000);
DISPLAY 0.872340 (-7700 3000);
PAINT GREEN (-7700 3000);
DISPLAY INVISIBLE (-7700 3000);
FORCEPROP 2 LAST PATH I55
J 0
(-8050 3125);
DISPLAY 0.680851 (-8050 3125);
DISPLAY INVISIBLE (-8050 3125);
FORCEADD OFFPAGE..4
R 2
(-7350 4125);
FORCEPROP 2 LAST $XR0 55 
J 0
(-7571 4125);
DISPLAY 0.638298 (-7571 4125);
PAINT MONO (-7571 4125);
FORCEPROP 2 LAST CDS_LIB standard
J 0
(-7350 4125);
DISPLAY INVISIBLE (-7350 4125);
FORCEPROP 1 LAST OFFPAGE TRUE
J 2
(-7675 4000);
DISPLAY 0.872340 (-7675 4000);
PAINT GREEN (-7675 4000);
DISPLAY INVISIBLE (-7675 4000);
FORCEPROP 1 LAST COMMENT_BODY TRUE
J 2
(-7325 4025);
DISPLAY 0.872340 (-7325 4025);
PAINT GREEN (-7325 4025);
DISPLAY INVISIBLE (-7325 4025);
FORCEPROP 2 LAST PATH I56
J 0
(-7550 4175);
DISPLAY 0.680851 (-7550 4175);
DISPLAY INVISIBLE (-7550 4175);
FORCEADD Q_RES..1
(-6725 2075);
FORCEPROP 1 LAST LOCATION R289
J 0
(-6600 2075);
DISPLAY 0.489362 (-6600 2075);
PAINT SKYBLUE (-6600 2075);
FORCEPROP 0 LAST $SEC 1
J 2
(-6600 2125);
DISPLAY 0.680851 (-6600 2125);
PAINT MONO (-6600 2125);
DISPLAY INVISIBLE (-6600 2125);
FORCEPROP 0 LAST CDS_SEC 1
J 2
(-6600 2125);
DISPLAY 1.021277 (-6600 2125);
DISPLAY INVISIBLE (-6600 2125);
FORCEPROP 1 LASTPIN (-6825 2075) $PN 1
J 0
(-6813 2087);
DISPLAY 0.489362 (-6813 2087);
PAINT MONO (-6813 2087);
FORCEPROP 1 LASTPIN (-6625 2075) $PN 2
J 0
(-6663 2087);
DISPLAY 0.489362 (-6663 2087);
PAINT MONO (-6663 2087);
FORCEPROP 1 LAST VALUE 33
J 2
(-6850 2075);
DISPLAY 0.489362 (-6850 2075);
PAINT SKYBLUE (-6850 2075);
FORCEPROP 1 LAST PACK_TYPE 0402LF
J 2
(-6550 2000);
DISPLAY 0.489362 (-6550 2000);
PAINT SKYBLUE (-6550 2000);
DISPLAY INVISIBLE (-6550 2000);
FORCEPROP 1 LAST TOLERANCE 5%
J 0
(-6850 2050);
DISPLAY 0.489362 (-6850 2050);
PAINT SKYBLUE (-6850 2050);
DISPLAY INVISIBLE (-6850 2050);
FORCEPROP 1 LAST MATERIAL CHIP
J 2
(-6550 2050);
DISPLAY 0.489362 (-6550 2050);
PAINT SKYBLUE (-6550 2050);
DISPLAY INVISIBLE (-6550 2050);
FORCEPROP 1 LAST WATTAGE 1/16W
J 2
(-6800 2000);
DISPLAY 0.489362 (-6800 2000);
PAINT SKYBLUE (-6800 2000);
DISPLAY INVISIBLE (-6800 2000);
FORCEPROP 2 LAST BOM_COST MEM
J 2
(-6700 2225);
DISPLAY 0.744681 (-6700 2225);
PAINT WHITE (-6700 2225);
DISPLAY INVISIBLE (-6700 2225);
FORCEPROP 2 LAST CDS_LIB pure_quanta
J 2
(-6725 2075);
DISPLAY INVISIBLE (-6725 2075);
FORCEPROP 1 LAST PATH I57
J 0
(-6775 2225);
DISPLAY 0.978723 (-6775 2225);
PAINT WHITE (-6775 2225);
DISPLAY INVISIBLE (-6775 2225);
FORCEPROP 1 LAST PART_NUMBER CS03302JB10
J 2
(-6625 2125);
DISPLAY 0.489362 (-6625 2125);
PAINT SKYBLUE (-6625 2125);
DISPLAY INVISIBLE (-6625 2125);
FORCEADD Q_RES..1
(-6725 2175);
FORCEPROP 1 LAST LOCATION R279
J 0
(-6600 2175);
DISPLAY 0.489362 (-6600 2175);
PAINT SKYBLUE (-6600 2175);
FORCEPROP 0 LAST $SEC 1
J 2
(-6600 2225);
DISPLAY 0.680851 (-6600 2225);
PAINT MONO (-6600 2225);
DISPLAY INVISIBLE (-6600 2225);
FORCEPROP 0 LAST CDS_SEC 1
J 2
(-6600 2225);
DISPLAY 1.021277 (-6600 2225);
DISPLAY INVISIBLE (-6600 2225);
FORCEPROP 1 LASTPIN (-6825 2175) $PN 1
J 0
(-6813 2187);
DISPLAY 0.489362 (-6813 2187);
PAINT MONO (-6813 2187);
FORCEPROP 1 LASTPIN (-6625 2175) $PN 2
J 0
(-6663 2187);
DISPLAY 0.489362 (-6663 2187);
PAINT MONO (-6663 2187);
FORCEPROP 1 LAST VALUE 33
J 2
(-6850 2175);
DISPLAY 0.489362 (-6850 2175);
PAINT SKYBLUE (-6850 2175);
FORCEPROP 1 LAST PACK_TYPE 0402LF
J 2
(-6550 2100);
DISPLAY 0.489362 (-6550 2100);
PAINT SKYBLUE (-6550 2100);
DISPLAY INVISIBLE (-6550 2100);
FORCEPROP 1 LAST TOLERANCE 5%
J 0
(-6850 2150);
DISPLAY 0.489362 (-6850 2150);
PAINT SKYBLUE (-6850 2150);
DISPLAY INVISIBLE (-6850 2150);
FORCEPROP 1 LAST MATERIAL CHIP
J 2
(-6550 2150);
DISPLAY 0.489362 (-6550 2150);
PAINT SKYBLUE (-6550 2150);
DISPLAY INVISIBLE (-6550 2150);
FORCEPROP 1 LAST WATTAGE 1/16W
J 2
(-6800 2100);
DISPLAY 0.489362 (-6800 2100);
PAINT SKYBLUE (-6800 2100);
DISPLAY INVISIBLE (-6800 2100);
FORCEPROP 2 LAST BOM_COST MEM
J 2
(-6700 2325);
DISPLAY 0.744681 (-6700 2325);
PAINT WHITE (-6700 2325);
DISPLAY INVISIBLE (-6700 2325);
FORCEPROP 2 LAST CDS_LIB pure_quanta
J 2
(-6725 2175);
DISPLAY INVISIBLE (-6725 2175);
FORCEPROP 1 LAST PATH I58
J 0
(-6775 2325);
DISPLAY 0.978723 (-6775 2325);
PAINT WHITE (-6775 2325);
DISPLAY INVISIBLE (-6775 2325);
FORCEPROP 1 LAST PART_NUMBER CS03302JB10
J 2
(-6625 2225);
DISPLAY 0.489362 (-6625 2225);
PAINT SKYBLUE (-6625 2225);
DISPLAY INVISIBLE (-6625 2225);
FORCEADD Q_RES..1
(-6725 2125);
FORCEPROP 1 LAST LOCATION R280
J 0
(-6600 2125);
DISPLAY 0.489362 (-6600 2125);
PAINT SKYBLUE (-6600 2125);
FORCEPROP 0 LAST $SEC 1
J 0
(-6600 2175);
DISPLAY 0.680851 (-6600 2175);
PAINT MONO (-6600 2175);
DISPLAY INVISIBLE (-6600 2175);
FORCEPROP 0 LAST CDS_SEC 1
J 0
(-6600 2175);
DISPLAY 1.021277 (-6600 2175);
DISPLAY INVISIBLE (-6600 2175);
FORCEPROP 1 LASTPIN (-6825 2125) $PN 1
J 0
(-6813 2137);
DISPLAY 0.489362 (-6813 2137);
PAINT MONO (-6813 2137);
FORCEPROP 1 LASTPIN (-6625 2125) $PN 2
J 0
(-6663 2137);
DISPLAY 0.489362 (-6663 2137);
PAINT MONO (-6663 2137);
FORCEPROP 1 LAST VALUE 0
J 2
(-6850 2125);
DISPLAY 0.489362 (-6850 2125);
PAINT SKYBLUE (-6850 2125);
FORCEPROP 2 LAST CDS_LIB pure_quanta
J 2
(-6725 2125);
DISPLAY INVISIBLE (-6725 2125);
FORCEPROP 1 LAST PACK_TYPE 0402LF
J 2
(-6550 2050);
DISPLAY 0.489362 (-6550 2050);
PAINT SKYBLUE (-6550 2050);
DISPLAY INVISIBLE (-6550 2050);
FORCEPROP 1 LAST TOLERANCE 5%
J 0
(-6850 2100);
DISPLAY 0.489362 (-6850 2100);
PAINT SKYBLUE (-6850 2100);
DISPLAY INVISIBLE (-6850 2100);
FORCEPROP 1 LAST MATERIAL CHIP
J 2
(-6550 2100);
DISPLAY 0.489362 (-6550 2100);
PAINT SKYBLUE (-6550 2100);
DISPLAY INVISIBLE (-6550 2100);
FORCEPROP 1 LAST WATTAGE 1/16W
J 2
(-6800 2050);
DISPLAY 0.489362 (-6800 2050);
PAINT SKYBLUE (-6800 2050);
DISPLAY INVISIBLE (-6800 2050);
FORCEPROP 2 LAST BOM_COST MEM
J 2
(-6700 2275);
DISPLAY 0.744681 (-6700 2275);
PAINT WHITE (-6700 2275);
DISPLAY INVISIBLE (-6700 2275);
FORCEPROP 1 LAST PATH I59
J 0
(-6775 2275);
DISPLAY 0.978723 (-6775 2275);
PAINT WHITE (-6775 2275);
DISPLAY INVISIBLE (-6775 2275);
FORCEPROP 1 LAST PART_NUMBER CS00002JB13
J 2
(-6625 2175);
DISPLAY 0.489362 (-6625 2175);
PAINT SKYBLUE (-6625 2175);
DISPLAY INVISIBLE (-6625 2175);
FORCEADD OFFPAGE..1
(-7800 1425);
FORCEPROP 2 LAST $XR1 147 
J 0
(-8172 1425);
DISPLAY 0.638298 (-8172 1425);
PAINT MONO (-8172 1425);
FORCEPROP 2 LAST $XR0 146 
J 0
(-8052 1425);
DISPLAY 0.638298 (-8052 1425);
PAINT MONO (-8052 1425);
FORCEPROP 2 LAST CDS_LIB standard
J 0
(-7800 1425);
DISPLAY INVISIBLE (-7800 1425);
FORCEPROP 1 LAST OFFPAGE TRUE
J 0
(-7475 1300);
DISPLAY 0.872340 (-7475 1300);
PAINT GREEN (-7475 1300);
DISPLAY INVISIBLE (-7475 1300);
FORCEPROP 1 LAST COMMENT_BODY TRUE
J 0
(-7675 1325);
DISPLAY 0.872340 (-7675 1325);
PAINT GREEN (-7675 1325);
DISPLAY INVISIBLE (-7675 1325);
FORCEPROP 2 LAST PATH I6
J 0
(-8075 1475);
DISPLAY 0.680851 (-8075 1475);
DISPLAY INVISIBLE (-8075 1475);
FORCEADD Q_RES..1
(-6725 2425);
FORCEPROP 1 LAST LOCATION R6055
J 0
(-6600 2425);
DISPLAY 0.489362 (-6600 2425);
PAINT SKYBLUE (-6600 2425);
FORCEPROP 0 LAST $SEC 1
J 0
(-6600 2475);
DISPLAY 0.680851 (-6600 2475);
PAINT MONO (-6600 2475);
DISPLAY INVISIBLE (-6600 2475);
FORCEPROP 0 LAST CDS_SEC 1
J 0
(-6600 2475);
DISPLAY 1.021277 (-6600 2475);
DISPLAY INVISIBLE (-6600 2475);
FORCEPROP 1 LASTPIN (-6825 2425) $PN 1
J 0
(-6813 2437);
DISPLAY 0.489362 (-6813 2437);
PAINT MONO (-6813 2437);
FORCEPROP 1 LASTPIN (-6625 2425) $PN 2
J 0
(-6663 2437);
DISPLAY 0.489362 (-6663 2437);
PAINT MONO (-6663 2437);
FORCEPROP 1 LAST VALUE 0
J 2
(-6850 2425);
DISPLAY 0.489362 (-6850 2425);
PAINT SKYBLUE (-6850 2425);
FORCEPROP 1 LAST PACK_TYPE 0402LF
J 2
(-6550 2350);
DISPLAY 0.489362 (-6550 2350);
PAINT SKYBLUE (-6550 2350);
DISPLAY INVISIBLE (-6550 2350);
FORCEPROP 1 LAST TOLERANCE 5%
J 0
(-6850 2400);
DISPLAY 0.489362 (-6850 2400);
PAINT SKYBLUE (-6850 2400);
DISPLAY INVISIBLE (-6850 2400);
FORCEPROP 1 LAST MATERIAL CHIP
J 2
(-6550 2400);
DISPLAY 0.489362 (-6550 2400);
PAINT SKYBLUE (-6550 2400);
DISPLAY INVISIBLE (-6550 2400);
FORCEPROP 1 LAST WATTAGE 1/16W
J 2
(-6800 2350);
DISPLAY 0.489362 (-6800 2350);
PAINT SKYBLUE (-6800 2350);
DISPLAY INVISIBLE (-6800 2350);
FORCEPROP 2 LAST CDS_LIB pure_quanta
J 0
(-6725 2425);
DISPLAY INVISIBLE (-6725 2425);
FORCEPROP 2 LAST BOM_COST MEM
J 2
(-6700 2575);
DISPLAY 0.744681 (-6700 2575);
PAINT WHITE (-6700 2575);
DISPLAY INVISIBLE (-6700 2575);
FORCEPROP 1 LAST PATH I60
J 0
(-6775 2575);
DISPLAY 0.978723 (-6775 2575);
PAINT WHITE (-6775 2575);
DISPLAY INVISIBLE (-6775 2575);
FORCEPROP 1 LAST PART_NUMBER CS00002JB13
J 2
(-6625 2475);
DISPLAY 0.489362 (-6625 2475);
PAINT SKYBLUE (-6625 2475);
DISPLAY INVISIBLE (-6625 2475);
FORCEADD Q_RES..1
(-6725 2475);
FORCEPROP 1 LAST LOCATION R209
J 0
(-6600 2475);
DISPLAY 0.489362 (-6600 2475);
PAINT SKYBLUE (-6600 2475);
FORCEPROP 0 LAST $SEC 1
J 0
(-6600 2525);
DISPLAY 0.680851 (-6600 2525);
PAINT MONO (-6600 2525);
DISPLAY INVISIBLE (-6600 2525);
FORCEPROP 0 LAST CDS_SEC 1
J 0
(-6600 2525);
DISPLAY 1.021277 (-6600 2525);
DISPLAY INVISIBLE (-6600 2525);
FORCEPROP 1 LASTPIN (-6825 2475) $PN 1
J 0
(-6813 2487);
DISPLAY 0.489362 (-6813 2487);
PAINT MONO (-6813 2487);
FORCEPROP 1 LASTPIN (-6625 2475) $PN 2
J 0
(-6663 2487);
DISPLAY 0.489362 (-6663 2487);
PAINT MONO (-6663 2487);
FORCEPROP 1 LAST VALUE 0
J 2
(-6850 2475);
DISPLAY 0.489362 (-6850 2475);
PAINT SKYBLUE (-6850 2475);
FORCEPROP 2 LAST BOM_COST MEM
J 2
(-6700 2625);
DISPLAY 0.744681 (-6700 2625);
PAINT WHITE (-6700 2625);
DISPLAY INVISIBLE (-6700 2625);
FORCEPROP 2 LAST CDS_LIB pure_quanta
J 0
(-6725 2475);
DISPLAY INVISIBLE (-6725 2475);
FORCEPROP 1 LAST WATTAGE 1/16W
J 2
(-6800 2400);
DISPLAY 0.489362 (-6800 2400);
PAINT SKYBLUE (-6800 2400);
DISPLAY INVISIBLE (-6800 2400);
FORCEPROP 1 LAST MATERIAL CHIP
J 2
(-6550 2450);
DISPLAY 0.489362 (-6550 2450);
PAINT SKYBLUE (-6550 2450);
DISPLAY INVISIBLE (-6550 2450);
FORCEPROP 1 LAST TOLERANCE 5%
J 0
(-6850 2450);
DISPLAY 0.489362 (-6850 2450);
PAINT SKYBLUE (-6850 2450);
DISPLAY INVISIBLE (-6850 2450);
FORCEPROP 1 LAST PACK_TYPE 0402LF
J 2
(-6550 2400);
DISPLAY 0.489362 (-6550 2400);
PAINT SKYBLUE (-6550 2400);
DISPLAY INVISIBLE (-6550 2400);
FORCEPROP 1 LAST PATH I61
J 0
(-6775 2625);
DISPLAY 0.978723 (-6775 2625);
PAINT WHITE (-6775 2625);
DISPLAY INVISIBLE (-6775 2625);
FORCEPROP 1 LAST PART_NUMBER CS00002JB13
J 2
(-6625 2525);
DISPLAY 0.489362 (-6625 2525);
PAINT SKYBLUE (-6625 2525);
DISPLAY INVISIBLE (-6625 2525);
FORCEADD Q_RES..1
(-6725 2625);
FORCEPROP 1 LAST LOCATION R286
J 0
(-6600 2625);
DISPLAY 0.489362 (-6600 2625);
PAINT SKYBLUE (-6600 2625);
FORCEPROP 0 LAST $SEC 1
J 0
(-6600 2675);
DISPLAY 0.680851 (-6600 2675);
PAINT MONO (-6600 2675);
DISPLAY INVISIBLE (-6600 2675);
FORCEPROP 0 LAST CDS_SEC 1
J 0
(-6600 2675);
DISPLAY 1.021277 (-6600 2675);
DISPLAY INVISIBLE (-6600 2675);
FORCEPROP 1 LASTPIN (-6825 2625) $PN 1
J 0
(-6813 2637);
DISPLAY 0.489362 (-6813 2637);
PAINT MONO (-6813 2637);
FORCEPROP 1 LASTPIN (-6625 2625) $PN 2
J 0
(-6663 2637);
DISPLAY 0.489362 (-6663 2637);
PAINT MONO (-6663 2637);
FORCEPROP 1 LAST VALUE 0
J 2
(-6850 2625);
DISPLAY 0.489362 (-6850 2625);
PAINT SKYBLUE (-6850 2625);
FORCEPROP 1 LAST PACK_TYPE 0402LF
J 2
(-6550 2550);
DISPLAY 0.489362 (-6550 2550);
PAINT SKYBLUE (-6550 2550);
DISPLAY INVISIBLE (-6550 2550);
FORCEPROP 1 LAST TOLERANCE 5%
J 0
(-6850 2600);
DISPLAY 0.489362 (-6850 2600);
PAINT SKYBLUE (-6850 2600);
DISPLAY INVISIBLE (-6850 2600);
FORCEPROP 1 LAST MATERIAL CHIP
J 2
(-6550 2600);
DISPLAY 0.489362 (-6550 2600);
PAINT SKYBLUE (-6550 2600);
DISPLAY INVISIBLE (-6550 2600);
FORCEPROP 1 LAST WATTAGE 1/16W
J 2
(-6800 2550);
DISPLAY 0.489362 (-6800 2550);
PAINT SKYBLUE (-6800 2550);
DISPLAY INVISIBLE (-6800 2550);
FORCEPROP 2 LAST CDS_LIB pure_quanta
J 2
(-6725 2625);
DISPLAY INVISIBLE (-6725 2625);
FORCEPROP 2 LAST BOM_COST MEM
J 2
(-6700 2775);
DISPLAY 0.744681 (-6700 2775);
PAINT WHITE (-6700 2775);
DISPLAY INVISIBLE (-6700 2775);
FORCEPROP 1 LAST PATH I62
J 0
(-6775 2775);
DISPLAY 0.978723 (-6775 2775);
PAINT WHITE (-6775 2775);
DISPLAY INVISIBLE (-6775 2775);
FORCEPROP 1 LAST PART_NUMBER CS00002JB13
J 2
(-6625 2675);
DISPLAY 0.489362 (-6625 2675);
PAINT SKYBLUE (-6625 2675);
DISPLAY INVISIBLE (-6625 2675);
FORCEADD Q_RES..1
(-6725 2675);
FORCEPROP 1 LAST LOCATION R1563
J 0
(-6600 2675);
DISPLAY 0.489362 (-6600 2675);
PAINT SKYBLUE (-6600 2675);
FORCEPROP 0 LAST $SEC 1
J 0
(-6600 2700);
DISPLAY 0.680851 (-6600 2700);
PAINT MONO (-6600 2700);
DISPLAY INVISIBLE (-6600 2700);
FORCEPROP 0 LAST CDS_SEC 1
J 0
(-6600 2700);
DISPLAY 0.680851 (-6600 2700);
DISPLAY INVISIBLE (-6600 2700);
FORCEPROP 1 LASTPIN (-6825 2675) $PN 1
J 0
(-6813 2687);
DISPLAY 0.787234 (-6813 2687);
PAINT MONO (-6813 2687);
FORCEPROP 1 LASTPIN (-6625 2675) $PN 2
J 0
(-6663 2687);
DISPLAY 0.787234 (-6663 2687);
PAINT MONO (-6663 2687);
FORCEPROP 1 LAST VALUE 33
J 2
(-6850 2675);
DISPLAY 0.489362 (-6850 2675);
PAINT SKYBLUE (-6850 2675);
FORCEPROP 2 LAST CDS_LIB pure_quanta
J 0
(-6725 2675);
DISPLAY INVISIBLE (-6725 2675);
FORCEPROP 1 LAST PACK_TYPE 0402LF
J 2
(-6550 2600);
DISPLAY 0.489362 (-6550 2600);
PAINT SKYBLUE (-6550 2600);
DISPLAY INVISIBLE (-6550 2600);
FORCEPROP 1 LAST TOLERANCE 5%
J 0
(-6850 2650);
DISPLAY 0.489362 (-6850 2650);
PAINT SKYBLUE (-6850 2650);
DISPLAY INVISIBLE (-6850 2650);
FORCEPROP 1 LAST MATERIAL CHIP
J 2
(-6550 2650);
DISPLAY 0.489362 (-6550 2650);
PAINT SKYBLUE (-6550 2650);
DISPLAY INVISIBLE (-6550 2650);
FORCEPROP 1 LAST WATTAGE 1/16W
J 2
(-6800 2600);
DISPLAY 0.489362 (-6800 2600);
PAINT SKYBLUE (-6800 2600);
DISPLAY INVISIBLE (-6800 2600);
FORCEPROP 2 LAST BOM_COST MEM
J 2
(-6700 2825);
DISPLAY 0.744681 (-6700 2825);
PAINT WHITE (-6700 2825);
DISPLAY INVISIBLE (-6700 2825);
FORCEPROP 1 LAST PATH I63
J 0
(-6775 2825);
DISPLAY 0.978723 (-6775 2825);
PAINT WHITE (-6775 2825);
DISPLAY INVISIBLE (-6775 2825);
FORCEPROP 1 LAST PART_NUMBER CS03302JB10
J 2
(-6625 2725);
DISPLAY 0.489362 (-6625 2725);
PAINT SKYBLUE (-6625 2725);
DISPLAY INVISIBLE (-6625 2725);
FORCEADD Q_RES..1
(-6725 2975);
FORCEPROP 1 LAST LOCATION R6046
J 0
(-6600 2975);
DISPLAY 0.489362 (-6600 2975);
PAINT SKYBLUE (-6600 2975);
FORCEPROP 0 LAST $SEC 1
J 0
(-6600 3025);
DISPLAY 0.680851 (-6600 3025);
PAINT MONO (-6600 3025);
DISPLAY INVISIBLE (-6600 3025);
FORCEPROP 0 LAST CDS_SEC 1
J 0
(-6600 3025);
DISPLAY 1.021277 (-6600 3025);
DISPLAY INVISIBLE (-6600 3025);
FORCEPROP 1 LASTPIN (-6825 2975) $PN 1
J 0
(-6813 2987);
DISPLAY 0.489362 (-6813 2987);
PAINT MONO (-6813 2987);
FORCEPROP 1 LASTPIN (-6625 2975) $PN 2
J 0
(-6663 2987);
DISPLAY 0.489362 (-6663 2987);
PAINT MONO (-6663 2987);
FORCEPROP 1 LAST VALUE 100
J 2
(-6850 2975);
DISPLAY 0.489362 (-6850 2975);
PAINT SKYBLUE (-6850 2975);
FORCEPROP 2 LAST BOM_COST MEM
J 2
(-6700 3125);
DISPLAY 0.744681 (-6700 3125);
PAINT WHITE (-6700 3125);
DISPLAY INVISIBLE (-6700 3125);
FORCEPROP 2 LAST CDS_LIB pure_quanta
J 2
(-6725 2975);
DISPLAY INVISIBLE (-6725 2975);
FORCEPROP 1 LAST WATTAGE 1/16W
J 2
(-6800 2900);
DISPLAY 0.489362 (-6800 2900);
PAINT SKYBLUE (-6800 2900);
DISPLAY INVISIBLE (-6800 2900);
FORCEPROP 1 LAST MATERIAL CHIP
J 2
(-6550 2950);
DISPLAY 0.489362 (-6550 2950);
PAINT SKYBLUE (-6550 2950);
DISPLAY INVISIBLE (-6550 2950);
FORCEPROP 1 LAST PACK_TYPE 0402LF
J 2
(-6550 2900);
DISPLAY 0.489362 (-6550 2900);
PAINT SKYBLUE (-6550 2900);
DISPLAY INVISIBLE (-6550 2900);
FORCEPROP 1 LAST TOLERANCE 1%
J 0
(-6850 2950);
DISPLAY 0.489362 (-6850 2950);
PAINT SKYBLUE (-6850 2950);
DISPLAY INVISIBLE (-6850 2950);
FORCEPROP 1 LAST PATH I64
J 0
(-6775 3125);
DISPLAY 0.978723 (-6775 3125);
PAINT WHITE (-6775 3125);
DISPLAY INVISIBLE (-6775 3125);
FORCEPROP 1 LAST PART_NUMBER CS11002FB07
J 2
(-6625 3025);
DISPLAY 0.489362 (-6625 3025);
PAINT SKYBLUE (-6625 3025);
DISPLAY INVISIBLE (-6625 3025);
FORCEADD Q_RES..1
(-6725 2825);
FORCEPROP 1 LAST LOCATION R208
J 0
(-6600 2825);
DISPLAY 0.489362 (-6600 2825);
PAINT SKYBLUE (-6600 2825);
FORCEPROP 0 LAST $SEC 1
J 0
(-6600 2875);
DISPLAY 0.680851 (-6600 2875);
PAINT MONO (-6600 2875);
DISPLAY INVISIBLE (-6600 2875);
FORCEPROP 0 LAST CDS_SEC 1
J 0
(-6600 2875);
DISPLAY 1.021277 (-6600 2875);
DISPLAY INVISIBLE (-6600 2875);
FORCEPROP 1 LASTPIN (-6825 2825) $PN 1
J 0
(-6813 2837);
DISPLAY 0.489362 (-6813 2837);
PAINT MONO (-6813 2837);
FORCEPROP 1 LASTPIN (-6625 2825) $PN 2
J 0
(-6663 2837);
DISPLAY 0.489362 (-6663 2837);
PAINT MONO (-6663 2837);
FORCEPROP 1 LAST VALUE 33
J 2
(-6850 2825);
DISPLAY 0.489362 (-6850 2825);
PAINT SKYBLUE (-6850 2825);
FORCEPROP 1 LAST PACK_TYPE 0402LF
J 2
(-6550 2750);
DISPLAY 0.489362 (-6550 2750);
PAINT SKYBLUE (-6550 2750);
DISPLAY INVISIBLE (-6550 2750);
FORCEPROP 1 LAST TOLERANCE 5%
J 0
(-6850 2800);
DISPLAY 0.489362 (-6850 2800);
PAINT SKYBLUE (-6850 2800);
DISPLAY INVISIBLE (-6850 2800);
FORCEPROP 1 LAST MATERIAL CHIP
J 2
(-6550 2800);
DISPLAY 0.489362 (-6550 2800);
PAINT SKYBLUE (-6550 2800);
DISPLAY INVISIBLE (-6550 2800);
FORCEPROP 1 LAST WATTAGE 1/16W
J 2
(-6800 2750);
DISPLAY 0.489362 (-6800 2750);
PAINT SKYBLUE (-6800 2750);
DISPLAY INVISIBLE (-6800 2750);
FORCEPROP 2 LAST BOM_COST MEM
J 2
(-6700 2975);
DISPLAY 0.744681 (-6700 2975);
PAINT WHITE (-6700 2975);
DISPLAY INVISIBLE (-6700 2975);
FORCEPROP 2 LAST CDS_LIB pure_quanta
J 0
(-6725 2825);
DISPLAY INVISIBLE (-6725 2825);
FORCEPROP 1 LAST PATH I65
J 0
(-6775 2975);
DISPLAY 0.978723 (-6775 2975);
PAINT WHITE (-6775 2975);
DISPLAY INVISIBLE (-6775 2975);
FORCEPROP 1 LAST PART_NUMBER CS03302JB10
J 2
(-6625 2875);
DISPLAY 0.489362 (-6625 2875);
PAINT SKYBLUE (-6625 2875);
DISPLAY INVISIBLE (-6625 2875);
FORCEADD Q_RES..1
(-6725 2875);
FORCEPROP 1 LAST LOCATION R228
J 0
(-6600 2875);
DISPLAY 0.489362 (-6600 2875);
PAINT SKYBLUE (-6600 2875);
FORCEPROP 0 LAST $SEC 1
J 0
(-6600 2925);
DISPLAY 0.680851 (-6600 2925);
PAINT MONO (-6600 2925);
DISPLAY INVISIBLE (-6600 2925);
FORCEPROP 0 LAST CDS_SEC 1
J 0
(-6600 2925);
DISPLAY 1.021277 (-6600 2925);
DISPLAY INVISIBLE (-6600 2925);
FORCEPROP 1 LASTPIN (-6825 2875) $PN 1
J 0
(-6813 2887);
DISPLAY 0.489362 (-6813 2887);
PAINT MONO (-6813 2887);
FORCEPROP 1 LASTPIN (-6625 2875) $PN 2
J 0
(-6663 2887);
DISPLAY 0.489362 (-6663 2887);
PAINT MONO (-6663 2887);
FORCEPROP 1 LAST VALUE 0
J 2
(-6850 2875);
DISPLAY 0.489362 (-6850 2875);
PAINT SKYBLUE (-6850 2875);
FORCEPROP 1 LAST PACK_TYPE 0402LF
J 2
(-6550 2800);
DISPLAY 0.489362 (-6550 2800);
PAINT SKYBLUE (-6550 2800);
DISPLAY INVISIBLE (-6550 2800);
FORCEPROP 1 LAST TOLERANCE 5%
J 0
(-6850 2850);
DISPLAY 0.489362 (-6850 2850);
PAINT SKYBLUE (-6850 2850);
DISPLAY INVISIBLE (-6850 2850);
FORCEPROP 1 LAST MATERIAL CHIP
J 2
(-6550 2850);
DISPLAY 0.489362 (-6550 2850);
PAINT SKYBLUE (-6550 2850);
DISPLAY INVISIBLE (-6550 2850);
FORCEPROP 1 LAST WATTAGE 1/16W
J 2
(-6800 2800);
DISPLAY 0.489362 (-6800 2800);
PAINT SKYBLUE (-6800 2800);
DISPLAY INVISIBLE (-6800 2800);
FORCEPROP 2 LAST CDS_LIB pure_quanta
J 2
(-6725 2875);
DISPLAY INVISIBLE (-6725 2875);
FORCEPROP 2 LAST BOM_COST MEM
J 2
(-6700 3025);
DISPLAY 0.744681 (-6700 3025);
PAINT WHITE (-6700 3025);
DISPLAY INVISIBLE (-6700 3025);
FORCEPROP 1 LAST PATH I66
J 0
(-6775 3025);
DISPLAY 0.978723 (-6775 3025);
PAINT WHITE (-6775 3025);
DISPLAY INVISIBLE (-6775 3025);
FORCEPROP 1 LAST PART_NUMBER CS00002JB13
J 2
(-6625 2925);
DISPLAY 0.489362 (-6625 2925);
PAINT SKYBLUE (-6625 2925);
DISPLAY INVISIBLE (-6625 2925);
FORCEADD Q_RES..1
(-6725 3025);
FORCEPROP 1 LAST LOCATION R230
J 0
(-6600 3025);
DISPLAY 0.489362 (-6600 3025);
PAINT SKYBLUE (-6600 3025);
FORCEPROP 0 LAST $SEC 1
J 0
(-6600 3075);
DISPLAY 0.680851 (-6600 3075);
PAINT MONO (-6600 3075);
DISPLAY INVISIBLE (-6600 3075);
FORCEPROP 0 LAST CDS_SEC 1
J 0
(-6600 3075);
DISPLAY 1.021277 (-6600 3075);
DISPLAY INVISIBLE (-6600 3075);
FORCEPROP 1 LASTPIN (-6825 3025) $PN 1
J 0
(-6813 3037);
DISPLAY 0.489362 (-6813 3037);
PAINT MONO (-6813 3037);
FORCEPROP 1 LASTPIN (-6625 3025) $PN 2
J 0
(-6663 3037);
DISPLAY 0.489362 (-6663 3037);
PAINT MONO (-6663 3037);
FORCEPROP 1 LAST VALUE 0
J 2
(-6850 3025);
DISPLAY 0.489362 (-6850 3025);
PAINT SKYBLUE (-6850 3025);
FORCEPROP 2 LAST CDS_LIB pure_quanta
J 2
(-6725 3025);
DISPLAY INVISIBLE (-6725 3025);
FORCEPROP 2 LAST BOM_COST MEM
J 2
(-6700 3175);
DISPLAY 0.744681 (-6700 3175);
PAINT WHITE (-6700 3175);
DISPLAY INVISIBLE (-6700 3175);
FORCEPROP 1 LAST WATTAGE 1/16W
J 2
(-6800 2950);
DISPLAY 0.489362 (-6800 2950);
PAINT SKYBLUE (-6800 2950);
DISPLAY INVISIBLE (-6800 2950);
FORCEPROP 1 LAST MATERIAL CHIP
J 2
(-6550 3000);
DISPLAY 0.489362 (-6550 3000);
PAINT SKYBLUE (-6550 3000);
DISPLAY INVISIBLE (-6550 3000);
FORCEPROP 1 LAST TOLERANCE 5%
J 0
(-6850 3000);
DISPLAY 0.489362 (-6850 3000);
PAINT SKYBLUE (-6850 3000);
DISPLAY INVISIBLE (-6850 3000);
FORCEPROP 1 LAST PACK_TYPE 0402LF
J 2
(-6550 2950);
DISPLAY 0.489362 (-6550 2950);
PAINT SKYBLUE (-6550 2950);
DISPLAY INVISIBLE (-6550 2950);
FORCEPROP 1 LAST PATH I67
J 0
(-6775 3175);
DISPLAY 0.978723 (-6775 3175);
PAINT WHITE (-6775 3175);
DISPLAY INVISIBLE (-6775 3175);
FORCEPROP 1 LAST PART_NUMBER CS00002JB13
J 2
(-6625 3075);
DISPLAY 0.489362 (-6625 3075);
PAINT SKYBLUE (-6625 3075);
DISPLAY INVISIBLE (-6625 3075);
FORCEADD Q_RES..1
(-6725 3075);
FORCEPROP 1 LAST LOCATION R229
J 0
(-6600 3075);
DISPLAY 0.489362 (-6600 3075);
PAINT SKYBLUE (-6600 3075);
FORCEPROP 0 LAST $SEC 1
J 2
(-6600 3125);
DISPLAY 0.680851 (-6600 3125);
PAINT MONO (-6600 3125);
DISPLAY INVISIBLE (-6600 3125);
FORCEPROP 0 LAST CDS_SEC 1
J 2
(-6600 3125);
DISPLAY 1.021277 (-6600 3125);
DISPLAY INVISIBLE (-6600 3125);
FORCEPROP 1 LASTPIN (-6825 3075) $PN 1
J 0
(-6813 3087);
DISPLAY 0.489362 (-6813 3087);
PAINT MONO (-6813 3087);
FORCEPROP 1 LASTPIN (-6625 3075) $PN 2
J 0
(-6663 3087);
DISPLAY 0.489362 (-6663 3087);
PAINT MONO (-6663 3087);
FORCEPROP 1 LAST VALUE 33
J 2
(-6850 3075);
DISPLAY 0.489362 (-6850 3075);
PAINT SKYBLUE (-6850 3075);
FORCEPROP 2 LAST BOM_COST MEM
J 2
(-6700 3225);
DISPLAY 0.744681 (-6700 3225);
PAINT WHITE (-6700 3225);
DISPLAY INVISIBLE (-6700 3225);
FORCEPROP 2 LAST CDS_LIB pure_quanta
J 2
(-6725 3075);
DISPLAY INVISIBLE (-6725 3075);
FORCEPROP 1 LAST WATTAGE 1/16W
J 2
(-6800 3000);
DISPLAY 0.489362 (-6800 3000);
PAINT SKYBLUE (-6800 3000);
DISPLAY INVISIBLE (-6800 3000);
FORCEPROP 1 LAST MATERIAL CHIP
J 2
(-6550 3050);
DISPLAY 0.489362 (-6550 3050);
PAINT SKYBLUE (-6550 3050);
DISPLAY INVISIBLE (-6550 3050);
FORCEPROP 1 LAST TOLERANCE 5%
J 0
(-6850 3050);
DISPLAY 0.489362 (-6850 3050);
PAINT SKYBLUE (-6850 3050);
DISPLAY INVISIBLE (-6850 3050);
FORCEPROP 1 LAST PACK_TYPE 0402LF
J 2
(-6550 3000);
DISPLAY 0.489362 (-6550 3000);
PAINT SKYBLUE (-6550 3000);
DISPLAY INVISIBLE (-6550 3000);
FORCEPROP 1 LAST PATH I68
J 0
(-6775 3225);
DISPLAY 0.978723 (-6775 3225);
PAINT WHITE (-6775 3225);
DISPLAY INVISIBLE (-6775 3225);
FORCEPROP 1 LAST PART_NUMBER CS03302JB10
J 2
(-6625 3125);
DISPLAY 0.489362 (-6625 3125);
PAINT SKYBLUE (-6625 3125);
DISPLAY INVISIBLE (-6625 3125);
FORCEADD OFFPAGE..4
R 2
(-7350 4175);
FORCEPROP 2 LAST $XR0 27 
J 0
(-7571 4175);
DISPLAY 0.638298 (-7571 4175);
PAINT MONO (-7571 4175);
FORCEPROP 2 LAST CDS_LIB standard
J 0
(-7350 4175);
DISPLAY INVISIBLE (-7350 4175);
FORCEPROP 1 LAST OFFPAGE TRUE
J 2
(-7675 4050);
DISPLAY 0.872340 (-7675 4050);
PAINT GREEN (-7675 4050);
DISPLAY INVISIBLE (-7675 4050);
FORCEPROP 1 LAST COMMENT_BODY TRUE
J 2
(-7325 4075);
DISPLAY 0.872340 (-7325 4075);
PAINT GREEN (-7325 4075);
DISPLAY INVISIBLE (-7325 4075);
FORCEPROP 2 LAST PATH I69
J 0
(-7550 4225);
DISPLAY 0.680851 (-7550 4225);
DISPLAY INVISIBLE (-7550 4225);
FORCEADD OFFPAGE..4
R 2
(-7350 4225);
FORCEPROP 2 LAST $XR0 54 
J 0
(-7571 4225);
DISPLAY 0.638298 (-7571 4225);
PAINT MONO (-7571 4225);
FORCEPROP 2 LAST CDS_LIB standard
J 0
(-7350 4225);
DISPLAY INVISIBLE (-7350 4225);
FORCEPROP 1 LAST OFFPAGE TRUE
J 2
(-7675 4100);
DISPLAY 0.872340 (-7675 4100);
PAINT GREEN (-7675 4100);
DISPLAY INVISIBLE (-7675 4100);
FORCEPROP 1 LAST COMMENT_BODY TRUE
J 2
(-7325 4125);
DISPLAY 0.872340 (-7325 4125);
PAINT GREEN (-7325 4125);
DISPLAY INVISIBLE (-7325 4125);
FORCEPROP 2 LAST PATH I70
J 0
(-7600 4275);
DISPLAY 0.680851 (-7600 4275);
DISPLAY INVISIBLE (-7600 4275);
FORCEADD OFFPAGE..2
R 2
(-7350 4325);
FORCEPROP 2 LAST $XR1 27 
J 0
(-7664 4325);
DISPLAY 0.638298 (-7664 4325);
PAINT MONO (-7664 4325);
FORCEPROP 2 LAST $XR0 83 
J 0
(-7574 4325);
DISPLAY 0.638298 (-7574 4325);
PAINT MONO (-7574 4325);
FORCEPROP 2 LAST CDS_LIB standard
J 0
(-7350 4325);
DISPLAY INVISIBLE (-7350 4325);
FORCEPROP 1 LAST OFFPAGE TRUE
J 2
(-7675 4200);
DISPLAY 0.872340 (-7675 4200);
PAINT GREEN (-7675 4200);
DISPLAY INVISIBLE (-7675 4200);
FORCEPROP 1 LAST COMMENT_BODY TRUE
J 2
(-7305 4230);
DISPLAY 0.872340 (-7305 4230);
PAINT GREEN (-7305 4230);
DISPLAY INVISIBLE (-7305 4230);
FORCEPROP 2 LAST PATH I71
J 0
(-7600 4375);
DISPLAY 0.680851 (-7600 4375);
DISPLAY INVISIBLE (-7600 4375);
FORCEADD OFFPAGE..2
R 2
(-7350 4275);
FORCEPROP 2 LAST $XR1 27 
J 0
(-7664 4275);
DISPLAY 0.638298 (-7664 4275);
PAINT MONO (-7664 4275);
FORCEPROP 2 LAST $XR0 83 
J 0
(-7574 4275);
DISPLAY 0.638298 (-7574 4275);
PAINT MONO (-7574 4275);
FORCEPROP 2 LAST CDS_LIB standard
J 0
(-7350 4275);
DISPLAY INVISIBLE (-7350 4275);
FORCEPROP 1 LAST OFFPAGE TRUE
J 2
(-7675 4150);
DISPLAY 0.872340 (-7675 4150);
PAINT GREEN (-7675 4150);
DISPLAY INVISIBLE (-7675 4150);
FORCEPROP 1 LAST COMMENT_BODY TRUE
J 2
(-7305 4180);
DISPLAY 0.872340 (-7305 4180);
PAINT GREEN (-7305 4180);
DISPLAY INVISIBLE (-7305 4180);
FORCEPROP 2 LAST PATH I72
J 0
(-7600 4325);
DISPLAY 0.680851 (-7600 4325);
DISPLAY INVISIBLE (-7600 4325);
FORCEADD OFFPAGE..2
R 2
(-7350 4475);
FORCEPROP 2 LAST $XR1 54 
J 0
(-7664 4475);
DISPLAY 0.638298 (-7664 4475);
PAINT MONO (-7664 4475);
FORCEPROP 2 LAST $XR0 83 
J 0
(-7574 4475);
DISPLAY 0.638298 (-7574 4475);
PAINT MONO (-7574 4475);
FORCEPROP 2 LAST CDS_LIB standard
J 0
(-7350 4475);
DISPLAY INVISIBLE (-7350 4475);
FORCEPROP 1 LAST OFFPAGE TRUE
J 2
(-7675 4350);
DISPLAY 0.872340 (-7675 4350);
PAINT GREEN (-7675 4350);
DISPLAY INVISIBLE (-7675 4350);
FORCEPROP 1 LAST COMMENT_BODY TRUE
J 2
(-7305 4380);
DISPLAY 0.872340 (-7305 4380);
PAINT GREEN (-7305 4380);
DISPLAY INVISIBLE (-7305 4380);
FORCEPROP 2 LAST PATH I73
J 0
(-7600 4525);
DISPLAY 0.680851 (-7600 4525);
DISPLAY INVISIBLE (-7600 4525);
FORCEADD OFFPAGE..2
R 2
(-7350 4525);
FORCEPROP 2 LAST $XR0 28 
J 0
(-7574 4525);
DISPLAY 0.638298 (-7574 4525);
PAINT MONO (-7574 4525);
FORCEPROP 2 LAST CDS_LIB standard
J 0
(-7350 4525);
DISPLAY INVISIBLE (-7350 4525);
FORCEPROP 1 LAST OFFPAGE TRUE
J 2
(-7675 4400);
DISPLAY 0.872340 (-7675 4400);
PAINT GREEN (-7675 4400);
DISPLAY INVISIBLE (-7675 4400);
FORCEPROP 1 LAST COMMENT_BODY TRUE
J 2
(-7305 4430);
DISPLAY 0.872340 (-7305 4430);
PAINT GREEN (-7305 4430);
DISPLAY INVISIBLE (-7305 4430);
FORCEPROP 2 LAST PATH I74
J 0
(-7600 4575);
DISPLAY 0.680851 (-7600 4575);
DISPLAY INVISIBLE (-7600 4575);
FORCEADD OFFPAGE..2
R 2
(-7350 4625);
FORCEPROP 2 LAST $XR1 54 
J 0
(-7694 4625);
DISPLAY 0.638298 (-7694 4625);
PAINT MONO (-7694 4625);
FORCEPROP 2 LAST $XR0 83 
J 0
(-7604 4625);
DISPLAY 0.638298 (-7604 4625);
PAINT MONO (-7604 4625);
FORCEPROP 2 LAST CDS_LIB standard
J 0
(-7350 4625);
DISPLAY INVISIBLE (-7350 4625);
FORCEPROP 1 LAST OFFPAGE TRUE
J 2
(-7675 4500);
DISPLAY 0.872340 (-7675 4500);
PAINT GREEN (-7675 4500);
DISPLAY INVISIBLE (-7675 4500);
FORCEPROP 1 LAST COMMENT_BODY TRUE
J 2
(-7305 4530);
DISPLAY 0.872340 (-7305 4530);
PAINT GREEN (-7305 4530);
DISPLAY INVISIBLE (-7305 4530);
FORCEPROP 2 LAST PATH I75
J 0
(-7600 4675);
DISPLAY 0.680851 (-7600 4675);
DISPLAY INVISIBLE (-7600 4675);
FORCEADD OFFPAGE..1
(-7350 4725);
FORCEPROP 2 LAST $XR0 167 
J 0
(-7602 4725);
DISPLAY 0.638298 (-7602 4725);
PAINT MONO (-7602 4725);
FORCEPROP 2 LAST CDS_LIB standard
J 2
(-7350 4725);
DISPLAY INVISIBLE (-7350 4725);
FORCEPROP 1 LAST OFFPAGE TRUE
J 0
(-7025 4600);
DISPLAY 0.872340 (-7025 4600);
DISPLAY INVISIBLE (-7025 4600);
FORCEPROP 1 LAST COMMENT_BODY TRUE
J 0
(-7225 4625);
DISPLAY 0.872340 (-7225 4625);
PAINT GREEN (-7225 4625);
DISPLAY INVISIBLE (-7225 4625);
FORCEPROP 2 LAST PATH I76
J 2
(-7075 4775);
DISPLAY 0.680851 (-7075 4775);
DISPLAY INVISIBLE (-7075 4775);
FORCEADD OFFPAGE..3
R 2
(-7350 4675);
FORCEPROP 2 LAST $XR2 78 
J 0
(-7779 4675);
DISPLAY 0.638298 (-7779 4675);
PAINT MONO (-7779 4675);
FORCEPROP 2 LAST $XR1 85 
J 0
(-7689 4675);
DISPLAY 0.638298 (-7689 4675);
PAINT MONO (-7689 4675);
FORCEPROP 2 LAST $XR0 55 
J 0
(-7599 4675);
DISPLAY 0.638298 (-7599 4675);
PAINT MONO (-7599 4675);
FORCEPROP 2 LAST CDS_LIB standard
J 0
(-7350 4675);
DISPLAY INVISIBLE (-7350 4675);
FORCEPROP 1 LAST OFFPAGE TRUE
J 2
(-7675 4550);
DISPLAY 0.872340 (-7675 4550);
PAINT GREEN (-7675 4550);
DISPLAY INVISIBLE (-7675 4550);
FORCEPROP 1 LAST COMMENT_BODY TRUE
J 2
(-7300 4575);
DISPLAY 0.872340 (-7300 4575);
PAINT GREEN (-7300 4575);
DISPLAY INVISIBLE (-7300 4575);
FORCEPROP 2 LAST PATH I77
J 0
(-7625 4725);
DISPLAY 0.680851 (-7625 4725);
DISPLAY INVISIBLE (-7625 4725);
FORCEADD OFFPAGE..2
R 2
(-7350 4775);
FORCEPROP 2 LAST $XR0 28 
J 0
(-7574 4775);
DISPLAY 0.638298 (-7574 4775);
PAINT MONO (-7574 4775);
FORCEPROP 2 LAST CDS_LIB standard
J 0
(-7350 4775);
DISPLAY INVISIBLE (-7350 4775);
FORCEPROP 1 LAST OFFPAGE TRUE
J 2
(-7675 4650);
DISPLAY 0.872340 (-7675 4650);
PAINT GREEN (-7675 4650);
DISPLAY INVISIBLE (-7675 4650);
FORCEPROP 1 LAST COMMENT_BODY TRUE
J 2
(-7305 4680);
DISPLAY 0.872340 (-7305 4680);
PAINT GREEN (-7305 4680);
DISPLAY INVISIBLE (-7305 4680);
FORCEPROP 2 LAST PATH I78
J 0
(-7600 4825);
DISPLAY 0.680851 (-7600 4825);
DISPLAY INVISIBLE (-7600 4825);
FORCEADD OFFPAGE..2
R 2
(-7350 4825);
FORCEPROP 2 LAST $XR0 224 
J 0
(-7605 4825);
DISPLAY 0.638298 (-7605 4825);
PAINT MONO (-7605 4825);
FORCEPROP 2 LAST CDS_LIB standard
J 0
(-7350 4825);
DISPLAY INVISIBLE (-7350 4825);
FORCEPROP 1 LAST OFFPAGE TRUE
J 2
(-7675 4700);
DISPLAY 0.872340 (-7675 4700);
PAINT GREEN (-7675 4700);
DISPLAY INVISIBLE (-7675 4700);
FORCEPROP 1 LAST COMMENT_BODY TRUE
J 2
(-7305 4730);
DISPLAY 0.872340 (-7305 4730);
PAINT GREEN (-7305 4730);
DISPLAY INVISIBLE (-7305 4730);
FORCEPROP 2 LAST PATH I79
J 0
(-7625 4875);
DISPLAY 0.680851 (-7625 4875);
DISPLAY INVISIBLE (-7625 4875);
FORCEADD OFFPAGE..2
R 2
(-7350 4875);
FORCEPROP 2 LAST $XR0 207 
J 0
(-7605 4875);
DISPLAY 0.638298 (-7605 4875);
PAINT MONO (-7605 4875);
FORCEPROP 2 LAST CDS_LIB standard
J 0
(-7350 4875);
DISPLAY INVISIBLE (-7350 4875);
FORCEPROP 1 LAST OFFPAGE TRUE
J 2
(-7675 4750);
DISPLAY 0.872340 (-7675 4750);
PAINT GREEN (-7675 4750);
DISPLAY INVISIBLE (-7675 4750);
FORCEPROP 1 LAST COMMENT_BODY TRUE
J 2
(-7305 4780);
DISPLAY 0.872340 (-7305 4780);
PAINT GREEN (-7305 4780);
DISPLAY INVISIBLE (-7305 4780);
FORCEPROP 2 LAST PATH I80
J 0
(-7625 4925);
DISPLAY 0.680851 (-7625 4925);
DISPLAY INVISIBLE (-7625 4925);
FORCEADD OFFPAGE..3
R 2
(-7350 4975);
FORCEPROP 2 LAST $XR2 85 
J 0
(-7779 4975);
DISPLAY 0.638298 (-7779 4975);
PAINT MONO (-7779 4975);
FORCEPROP 2 LAST $XR1 78 
J 0
(-7689 4975);
DISPLAY 0.638298 (-7689 4975);
PAINT MONO (-7689 4975);
FORCEPROP 2 LAST $XR0 28 
J 0
(-7599 4975);
DISPLAY 0.638298 (-7599 4975);
PAINT MONO (-7599 4975);
FORCEPROP 2 LAST CDS_LIB standard
J 0
(-7350 4975);
DISPLAY INVISIBLE (-7350 4975);
FORCEPROP 1 LAST OFFPAGE TRUE
J 2
(-7675 4850);
DISPLAY 0.872340 (-7675 4850);
PAINT GREEN (-7675 4850);
DISPLAY INVISIBLE (-7675 4850);
FORCEPROP 1 LAST COMMENT_BODY TRUE
J 2
(-7300 4875);
DISPLAY 0.872340 (-7300 4875);
PAINT GREEN (-7300 4875);
DISPLAY INVISIBLE (-7300 4875);
FORCEPROP 2 LAST PATH I81
J 0
(-7625 5025);
DISPLAY 0.680851 (-7625 5025);
DISPLAY INVISIBLE (-7625 5025);
FORCEADD OFFPAGE..4
R 2
(-7350 4925);
FORCEPROP 2 LAST $XR0 55 
J 0
(-7601 4925);
DISPLAY 0.638298 (-7601 4925);
PAINT MONO (-7601 4925);
FORCEPROP 2 LAST CDS_LIB standard
J 0
(-7350 4925);
DISPLAY INVISIBLE (-7350 4925);
FORCEPROP 1 LAST OFFPAGE TRUE
J 2
(-7675 4800);
DISPLAY 0.872340 (-7675 4800);
PAINT GREEN (-7675 4800);
DISPLAY INVISIBLE (-7675 4800);
FORCEPROP 1 LAST COMMENT_BODY TRUE
J 2
(-7325 4825);
DISPLAY 0.872340 (-7325 4825);
PAINT GREEN (-7325 4825);
DISPLAY INVISIBLE (-7325 4825);
FORCEPROP 2 LAST PATH I82
J 0
(-7625 4975);
DISPLAY 0.680851 (-7625 4975);
DISPLAY INVISIBLE (-7625 4975);
FORCEADD OFFPAGE..2
R 2
(-7350 5075);
FORCEPROP 2 LAST $XR1 29 
J 0
(-7694 5075);
DISPLAY 0.638298 (-7694 5075);
PAINT MONO (-7694 5075);
FORCEPROP 2 LAST $XR0 83 
J 0
(-7604 5075);
DISPLAY 0.638298 (-7604 5075);
PAINT MONO (-7604 5075);
FORCEPROP 2 LAST CDS_LIB standard
J 0
(-7350 5075);
DISPLAY INVISIBLE (-7350 5075);
FORCEPROP 1 LAST OFFPAGE TRUE
J 2
(-7675 4950);
DISPLAY 0.872340 (-7675 4950);
PAINT GREEN (-7675 4950);
DISPLAY INVISIBLE (-7675 4950);
FORCEPROP 1 LAST COMMENT_BODY TRUE
J 2
(-7305 4980);
DISPLAY 0.872340 (-7305 4980);
PAINT GREEN (-7305 4980);
DISPLAY INVISIBLE (-7305 4980);
FORCEPROP 2 LAST PATH I83
J 0
(-7600 5125);
DISPLAY 0.680851 (-7600 5125);
DISPLAY INVISIBLE (-7600 5125);
FORCEADD OFFPAGE..2
R 2
(-7350 5025);
FORCEPROP 2 LAST $XR0 173 
J 0
(-7605 5025);
DISPLAY 0.638298 (-7605 5025);
PAINT MONO (-7605 5025);
FORCEPROP 2 LAST CDS_LIB standard
J 0
(-7350 5025);
DISPLAY INVISIBLE (-7350 5025);
FORCEPROP 1 LAST OFFPAGE TRUE
J 2
(-7675 4900);
DISPLAY 0.872340 (-7675 4900);
PAINT GREEN (-7675 4900);
DISPLAY INVISIBLE (-7675 4900);
FORCEPROP 1 LAST COMMENT_BODY TRUE
J 2
(-7305 4930);
DISPLAY 0.872340 (-7305 4930);
PAINT GREEN (-7305 4930);
DISPLAY INVISIBLE (-7305 4930);
FORCEPROP 2 LAST PATH I84
J 0
(-7625 5075);
DISPLAY 0.680851 (-7625 5075);
DISPLAY INVISIBLE (-7625 5075);
FORCEADD OFFPAGE..3
R 2
(-7350 5125);
FORCEPROP 2 LAST $XR1 85 
J 0
(-7689 5125);
DISPLAY 0.638298 (-7689 5125);
PAINT MONO (-7689 5125);
FORCEPROP 2 LAST $XR0 55 
J 0
(-7599 5125);
DISPLAY 0.638298 (-7599 5125);
PAINT MONO (-7599 5125);
FORCEPROP 2 LAST CDS_LIB standard
J 0
(-7350 5125);
DISPLAY INVISIBLE (-7350 5125);
FORCEPROP 1 LAST OFFPAGE TRUE
J 2
(-7675 5000);
DISPLAY 0.872340 (-7675 5000);
PAINT GREEN (-7675 5000);
DISPLAY INVISIBLE (-7675 5000);
FORCEPROP 1 LAST COMMENT_BODY TRUE
J 2
(-7300 5025);
DISPLAY 0.872340 (-7300 5025);
PAINT GREEN (-7300 5025);
DISPLAY INVISIBLE (-7300 5025);
FORCEPROP 2 LAST PATH I85
J 0
(-7625 5175);
DISPLAY 0.680851 (-7625 5175);
DISPLAY INVISIBLE (-7625 5175);
FORCEADD OFFPAGE..3
R 2
(-7350 5175);
FORCEPROP 2 LAST $XR1 85 
J 0
(-7689 5175);
DISPLAY 0.638298 (-7689 5175);
PAINT MONO (-7689 5175);
FORCEPROP 2 LAST $XR0 28 
J 0
(-7599 5175);
DISPLAY 0.638298 (-7599 5175);
PAINT MONO (-7599 5175);
FORCEPROP 2 LAST CDS_LIB standard
J 0
(-7350 5175);
DISPLAY INVISIBLE (-7350 5175);
FORCEPROP 1 LAST OFFPAGE TRUE
J 2
(-7675 5050);
DISPLAY 0.872340 (-7675 5050);
PAINT GREEN (-7675 5050);
DISPLAY INVISIBLE (-7675 5050);
FORCEPROP 1 LAST COMMENT_BODY TRUE
J 2
(-7300 5075);
DISPLAY 0.872340 (-7300 5075);
PAINT GREEN (-7300 5075);
DISPLAY INVISIBLE (-7300 5075);
FORCEPROP 2 LAST PATH I86
J 0
(-7625 5225);
DISPLAY 0.680851 (-7625 5225);
DISPLAY INVISIBLE (-7625 5225);
FORCEADD OFFPAGE..2
R 2
(-7350 5375);
FORCEPROP 2 LAST $XR0 55 
J 0
(-7574 5375);
DISPLAY 0.638298 (-7574 5375);
PAINT MONO (-7574 5375);
FORCEPROP 2 LAST CDS_LIB standard
J 0
(-7350 5375);
DISPLAY INVISIBLE (-7350 5375);
FORCEPROP 1 LAST OFFPAGE TRUE
J 2
(-7675 5250);
DISPLAY 0.872340 (-7675 5250);
PAINT GREEN (-7675 5250);
DISPLAY INVISIBLE (-7675 5250);
FORCEPROP 1 LAST COMMENT_BODY TRUE
J 2
(-7305 5280);
DISPLAY 0.872340 (-7305 5280);
PAINT GREEN (-7305 5280);
DISPLAY INVISIBLE (-7305 5280);
FORCEPROP 2 LAST PATH I88
J 0
(-7600 5425);
DISPLAY 0.680851 (-7600 5425);
DISPLAY INVISIBLE (-7600 5425);
FORCEADD OFFPAGE..4
R 2
(-7350 5325);
FORCEPROP 2 LAST $XR0 28 
J 0
(-7571 5325);
DISPLAY 0.638298 (-7571 5325);
PAINT MONO (-7571 5325);
FORCEPROP 2 LAST CDS_LIB standard
J 0
(-7350 5325);
DISPLAY INVISIBLE (-7350 5325);
FORCEPROP 1 LAST OFFPAGE TRUE
J 2
(-7675 5200);
DISPLAY 0.872340 (-7675 5200);
PAINT GREEN (-7675 5200);
DISPLAY INVISIBLE (-7675 5200);
FORCEPROP 1 LAST COMMENT_BODY TRUE
J 2
(-7325 5225);
DISPLAY 0.872340 (-7325 5225);
PAINT GREEN (-7325 5225);
DISPLAY INVISIBLE (-7325 5225);
FORCEPROP 2 LAST PATH I89
J 0
(-7600 5375);
DISPLAY 0.680851 (-7600 5375);
DISPLAY INVISIBLE (-7600 5375);
FORCEADD OFFPAGE..1
(-7800 1525);
FORCEPROP 2 LAST $XR0 217 
J 0
(-8052 1525);
DISPLAY 0.638298 (-8052 1525);
PAINT MONO (-8052 1525);
FORCEPROP 2 LAST CDS_LIB standard
J 0
(-7800 1525);
DISPLAY INVISIBLE (-7800 1525);
FORCEPROP 1 LAST OFFPAGE TRUE
J 0
(-7475 1400);
DISPLAY 0.872340 (-7475 1400);
PAINT GREEN (-7475 1400);
DISPLAY INVISIBLE (-7475 1400);
FORCEPROP 1 LAST COMMENT_BODY TRUE
J 0
(-7675 1425);
DISPLAY 0.872340 (-7675 1425);
PAINT GREEN (-7675 1425);
DISPLAY INVISIBLE (-7675 1425);
FORCEPROP 2 LAST PATH I9
J 0
(-8075 1575);
DISPLAY 0.680851 (-8075 1575);
DISPLAY INVISIBLE (-8075 1575);
FORCEADD OFFPAGE..2
R 2
(-7350 5425);
FORCEPROP 2 LAST $XR0 28 
J 0
(-7574 5425);
DISPLAY 0.638298 (-7574 5425);
PAINT MONO (-7574 5425);
FORCEPROP 2 LAST CDS_LIB standard
J 0
(-7350 5425);
DISPLAY INVISIBLE (-7350 5425);
FORCEPROP 1 LAST OFFPAGE TRUE
J 2
(-7675 5300);
DISPLAY 0.872340 (-7675 5300);
PAINT GREEN (-7675 5300);
DISPLAY INVISIBLE (-7675 5300);
FORCEPROP 1 LAST COMMENT_BODY TRUE
J 2
(-7305 5330);
DISPLAY 0.872340 (-7305 5330);
PAINT GREEN (-7305 5330);
DISPLAY INVISIBLE (-7305 5330);
FORCEPROP 2 LAST PATH I90
J 0
(-7600 5475);
DISPLAY 0.680851 (-7600 5475);
DISPLAY INVISIBLE (-7600 5475);
FORCEADD OFFPAGE..2
R 2
(-7350 5525);
FORCEPROP 2 LAST $XR1 255 
J 0
(-7694 5525);
DISPLAY 0.638298 (-7694 5525);
PAINT MONO (-7694 5525);
FORCEPROP 2 LAST $XR0 28 
J 0
(-7574 5525);
DISPLAY 0.638298 (-7574 5525);
PAINT MONO (-7574 5525);
FORCEPROP 2 LAST CDS_LIB standard
J 0
(-7350 5525);
DISPLAY INVISIBLE (-7350 5525);
FORCEPROP 1 LAST OFFPAGE TRUE
J 2
(-7675 5400);
DISPLAY 0.872340 (-7675 5400);
DISPLAY INVISIBLE (-7675 5400);
FORCEPROP 1 LAST COMMENT_BODY TRUE
J 2
(-7305 5430);
DISPLAY 0.872340 (-7305 5430);
PAINT GREEN (-7305 5430);
DISPLAY INVISIBLE (-7305 5430);
FORCEPROP 2 LAST PATH I91
J 0
(-7550 5575);
DISPLAY 0.680851 (-7550 5575);
DISPLAY INVISIBLE (-7550 5575);
FORCEADD OFFPAGE..2
R 2
(-7350 5575);
FORCEPROP 2 LAST $XR0 55 
J 0
(-7574 5575);
DISPLAY 0.638298 (-7574 5575);
PAINT MONO (-7574 5575);
FORCEPROP 2 LAST CDS_LIB standard
J 0
(-7350 5575);
DISPLAY INVISIBLE (-7350 5575);
FORCEPROP 1 LAST OFFPAGE TRUE
J 2
(-7675 5450);
DISPLAY 0.872340 (-7675 5450);
DISPLAY INVISIBLE (-7675 5450);
FORCEPROP 1 LAST COMMENT_BODY TRUE
J 2
(-7305 5480);
DISPLAY 0.872340 (-7305 5480);
PAINT GREEN (-7305 5480);
DISPLAY INVISIBLE (-7305 5480);
FORCEPROP 2 LAST PATH I92
J 0
(-7550 5625);
DISPLAY 0.680851 (-7550 5625);
DISPLAY INVISIBLE (-7550 5625);
FORCEADD OFFPAGE..4
R 2
(-7350 5825);
FORCEPROP 2 LAST $XR1 83 
J 0
(-7661 5825);
DISPLAY 0.638298 (-7661 5825);
PAINT MONO (-7661 5825);
FORCEPROP 2 LAST $XR0 28 
J 0
(-7571 5825);
DISPLAY 0.638298 (-7571 5825);
PAINT MONO (-7571 5825);
FORCEPROP 2 LAST CDS_LIB standard
J 0
(-7350 5825);
DISPLAY INVISIBLE (-7350 5825);
FORCEPROP 1 LAST OFFPAGE TRUE
J 2
(-7675 5700);
DISPLAY 0.872340 (-7675 5700);
PAINT GREEN (-7675 5700);
DISPLAY INVISIBLE (-7675 5700);
FORCEPROP 1 LAST COMMENT_BODY TRUE
J 2
(-7325 5725);
DISPLAY 0.872340 (-7325 5725);
PAINT GREEN (-7325 5725);
DISPLAY INVISIBLE (-7325 5725);
FORCEPROP 2 LAST PATH I93
J 0
(-7550 5875);
DISPLAY 0.680851 (-7550 5875);
DISPLAY INVISIBLE (-7550 5875);
FORCEADD OFFPAGE..4
R 2
(-7350 5675);
FORCEPROP 2 LAST $XR1 83 
J 0
(-7691 5675);
DISPLAY 0.638298 (-7691 5675);
PAINT MONO (-7691 5675);
FORCEPROP 2 LAST $XR0 55 
J 0
(-7601 5675);
DISPLAY 0.638298 (-7601 5675);
PAINT MONO (-7601 5675);
FORCEPROP 2 LAST CDS_LIB standard
J 0
(-7350 5675);
DISPLAY INVISIBLE (-7350 5675);
FORCEPROP 1 LAST OFFPAGE TRUE
J 2
(-7675 5550);
DISPLAY 0.872340 (-7675 5550);
PAINT GREEN (-7675 5550);
DISPLAY INVISIBLE (-7675 5550);
FORCEPROP 1 LAST COMMENT_BODY TRUE
J 2
(-7325 5575);
DISPLAY 0.872340 (-7325 5575);
PAINT GREEN (-7325 5575);
DISPLAY INVISIBLE (-7325 5575);
FORCEPROP 2 LAST PATH I94
J 0
(-7550 5725);
DISPLAY 0.680851 (-7550 5725);
DISPLAY INVISIBLE (-7550 5725);
FORCEADD OFFPAGE..4
R 2
(-7350 5925);
FORCEPROP 2 LAST $XR0 55 
J 0
(-7571 5925);
DISPLAY 0.638298 (-7571 5925);
PAINT MONO (-7571 5925);
FORCEPROP 2 LAST CDS_LIB standard
J 0
(-7350 5925);
DISPLAY INVISIBLE (-7350 5925);
FORCEPROP 1 LAST OFFPAGE TRUE
J 2
(-7675 5800);
DISPLAY 0.872340 (-7675 5800);
PAINT GREEN (-7675 5800);
DISPLAY INVISIBLE (-7675 5800);
FORCEPROP 1 LAST COMMENT_BODY TRUE
J 2
(-7325 5825);
DISPLAY 0.872340 (-7325 5825);
PAINT GREEN (-7325 5825);
DISPLAY INVISIBLE (-7325 5825);
FORCEPROP 2 LAST PATH I95
J 0
(-7550 5975);
DISPLAY 0.680851 (-7550 5975);
DISPLAY INVISIBLE (-7550 5975);
FORCEADD OFFPAGE..4
R 2
(-7350 5975);
FORCEPROP 2 LAST $XR0 55 
J 0
(-7571 5975);
DISPLAY 0.638298 (-7571 5975);
PAINT MONO (-7571 5975);
FORCEPROP 2 LAST CDS_LIB standard
J 0
(-7350 5975);
DISPLAY INVISIBLE (-7350 5975);
FORCEPROP 1 LAST OFFPAGE TRUE
J 2
(-7675 5850);
DISPLAY 0.872340 (-7675 5850);
PAINT GREEN (-7675 5850);
DISPLAY INVISIBLE (-7675 5850);
FORCEPROP 1 LAST COMMENT_BODY TRUE
J 2
(-7325 5875);
DISPLAY 0.872340 (-7325 5875);
PAINT GREEN (-7325 5875);
DISPLAY INVISIBLE (-7325 5875);
FORCEPROP 2 LAST PATH I96
J 0
(-7550 6025);
DISPLAY 0.680851 (-7550 6025);
DISPLAY INVISIBLE (-7550 6025);
FORCEADD OFFPAGE..4
R 2
(-7350 6025);
FORCEPROP 2 LAST $XR1 83 
J 0
(-7661 6025);
DISPLAY 0.638298 (-7661 6025);
PAINT MONO (-7661 6025);
FORCEPROP 2 LAST $XR0 55 
J 0
(-7571 6025);
DISPLAY 0.638298 (-7571 6025);
PAINT MONO (-7571 6025);
FORCEPROP 2 LAST CDS_LIB standard
J 0
(-7350 6025);
DISPLAY INVISIBLE (-7350 6025);
FORCEPROP 1 LAST OFFPAGE TRUE
J 2
(-7675 5900);
DISPLAY 0.872340 (-7675 5900);
PAINT GREEN (-7675 5900);
DISPLAY INVISIBLE (-7675 5900);
FORCEPROP 1 LAST COMMENT_BODY TRUE
J 2
(-7325 5925);
DISPLAY 0.872340 (-7325 5925);
PAINT GREEN (-7325 5925);
DISPLAY INVISIBLE (-7325 5925);
FORCEPROP 2 LAST PATH I97
J 0
(-7550 6075);
DISPLAY 0.680851 (-7550 6075);
DISPLAY INVISIBLE (-7550 6075);
FORCEADD OFFPAGE..4
R 2
(-7350 6075);
FORCEPROP 2 LAST $XR1 83 
J 0
(-7661 6075);
DISPLAY 0.638298 (-7661 6075);
PAINT MONO (-7661 6075);
FORCEPROP 2 LAST $XR0 28 
J 0
(-7571 6075);
DISPLAY 0.638298 (-7571 6075);
PAINT MONO (-7571 6075);
FORCEPROP 2 LAST CDS_LIB standard
J 0
(-7350 6075);
DISPLAY INVISIBLE (-7350 6075);
FORCEPROP 1 LAST OFFPAGE TRUE
J 2
(-7675 5950);
DISPLAY 0.872340 (-7675 5950);
PAINT GREEN (-7675 5950);
DISPLAY INVISIBLE (-7675 5950);
FORCEPROP 1 LAST COMMENT_BODY TRUE
J 2
(-7325 5975);
DISPLAY 0.872340 (-7325 5975);
PAINT GREEN (-7325 5975);
DISPLAY INVISIBLE (-7325 5975);
FORCEPROP 2 LAST PATH I98
J 0
(-7550 6125);
DISPLAY 0.680851 (-7550 6125);
DISPLAY INVISIBLE (-7550 6125);
FORCEADD OFFPAGE..4
R 2
(-7350 6125);
FORCEPROP 2 LAST $XR0 28 
J 0
(-7571 6125);
DISPLAY 0.638298 (-7571 6125);
PAINT MONO (-7571 6125);
FORCEPROP 2 LAST CDS_LIB standard
J 0
(-7350 6125);
DISPLAY INVISIBLE (-7350 6125);
FORCEPROP 1 LAST OFFPAGE TRUE
J 2
(-7675 6000);
DISPLAY 0.872340 (-7675 6000);
PAINT GREEN (-7675 6000);
DISPLAY INVISIBLE (-7675 6000);
FORCEPROP 1 LAST COMMENT_BODY TRUE
J 2
(-7325 6025);
DISPLAY 0.872340 (-7325 6025);
PAINT GREEN (-7325 6025);
DISPLAY INVISIBLE (-7325 6025);
FORCEPROP 2 LAST PATH I99
J 0
(-7550 6175);
DISPLAY 0.680851 (-7550 6175);
DISPLAY INVISIBLE (-7550 6175);
FORCEADD QUANTA_TITLE_BLOCK_C..1
(-25 100);
FORCEPROP 0 LAST CDS_CON_LAST_MODIFIED Thu Sep 14 16:12:34 2023
J 0
(-1910 115);
DISPLAY INVISIBLE (-1910 115);
FORCEPROP 1 LAST CUSTOM_TXT_CDS <CON_LAST_MODIFIED>
J 0
(-1910 115);
DISPLAY 0.978723 (-1910 115);
FORCEPROP 2 LAST CUSTOM_TXT_CDS <XR_PAGE_TITLE>
J 0
(-7915 5350);
DISPLAY 0.638298 (-7915 5350);
PAINT PINK (-7915 5350);
DISPLAY INVISIBLE (-7915 5350);
FORCEPROP 1 LAST CUSTOM_TXT_CDS <NAME_2>
J 0
(-3200 150);
FORCEPROP 1 LAST CUSTOM_TXT_CDS <NAME_1>
J 0
(-3200 275);
FORCEPROP 1 LAST CUSTOM_TXT_CDS <Q_NUMBER>
J 0
(-1428 203);
DISPLAY 1.212766 (-1428 203);
FORCEPROP 1 LAST CUSTOM_TXT_CDS <Q_PROJ>
J 0
(-2407 202);
DISPLAY 1.212766 (-2407 202);
FORCEPROP 1 LAST CUSTOM_TXT_CDS <Q_REV>
J 0
(-209 203);
DISPLAY 1.212766 (-209 203);
FORCEPROP 1 LAST CUSTOM_TXT_CDS <CON_PAGE_NUM> OF <CON_TOTAL_PAGES>
J 0
(-471 118);
DISPLAY 0.978723 (-471 118);
FORCEPROP 1 LAST Q_TITLE FPGA 2/6
J 0
(-9300 175);
DISPLAY 2.446809 (-9300 175);
PAINT GREEN (-9300 175);
FORCEPROP 2 LAST CDS_LIB pure_quanta
J 0
(-25 100);
DISPLAY INVISIBLE (-25 100);
FORCEPROP 1 LAST CDS_LMAN_SYM_OUTLINE -9475,6775,100,-125
J 0
(-25 100);
DISPLAY 0.468085 (-25 100);
PAINT GREEN (-25 100);
DISPLAY INVISIBLE (-25 100);
FORCEPROP 2 LAST PAGE_BORDER TRUE
J 0
(-7915 5350);
DISPLAY 0.638298 (-7915 5350);
PAINT PINK (-7915 5350);
DISPLAY INVISIBLE (-7915 5350);
FORCEPROP 2 LAST CDS_XR_PAGE_TITLE CR-81 : @T6G_MB_LIB.T6G(SCH_1):PAGE81
J 0
(-7915 5350);
DISPLAY 0.638298 (-7915 5350);
PAINT PINK (-7915 5350);
DISPLAY INVISIBLE (-7915 5350);
FORCEPROP 1 LAST Q_DEPT BU9
J 1
(-3788 149);
DISPLAY 1.957447 (-3788 149);
PAINT GREEN (-3788 149);
DISPLAY INVISIBLE (-3788 149);
FORCEPROP 1 LAST COMMENT_BODY TRUE
J 0
(-13 87);
DISPLAY 0.978723 (-13 87);
PAINT GREEN (-13 87);
DISPLAY INVISIBLE (-13 87);
FORCEADD DNS..2
(-6450 5400);
PAINT RED (-6450 5400);
FORCEPROP 2 LAST CDS_LIB mstr_misc
J 0
(-6450 5400);
DISPLAY INVISIBLE (-6450 5400);
FORCEPROP 1 LAST COMMENT_BODY TRUE
R 1
J 0
(-6375 5175);
DISPLAY 0.872340 (-6375 5175);
PAINT PEACH (-6375 5175);
DISPLAY INVISIBLE (-6375 5175);
WIRE 16 -1 (-275 1225)(-275 1300);
WIRE 16 -1 (-6825 575)(-7750 575);
FORCEPROP 2 LAST SIG_NAME E1S_0_P3V3_EN
J 0
(-7650 585);
DISPLAY 0.489362 (-7650 585);
WIRE 16 -1 (-5375 1075)(-7750 1075);
FORCEPROP 2 LAST SIG_NAME BMC_FPGA_LED1
J 0
(-6150 1085);
DISPLAY 0.489362 (-6150 1085);
WIRE 16 -1 (-7750 975)(-5375 975);
FORCEPROP 2 LAST SIG_NAME P3V3_E1S_PWRGD_0_R
J 0
(-7650 985);
DISPLAY 0.510638 (-7650 985);
PAINT WHITE (-7650 985);
WIRE 16 -1 (-7750 825)(-5375 825);
FORCEPROP 2 LAST SIG_NAME RST_PERST_CPU1_SWB_1_N
J 0
(-7275 835);
DISPLAY 0.510638 (-7275 835);
PAINT WHITE (-7275 835);
WIRE 16 -1 (-6625 575)(-5375 575);
FORCEPROP 2 LAST SIG_NAME P3V3_E1S_0_EN_R
J 0
(-6150 585);
DISPLAY 0.489362 (-6150 585);
FORCEPROP 2 LASTPROP $XRERR UNIQUE?
J 0
(-6390 585);
DISPLAY 0.638298 (-6390 585);
PAINT MONO (-6390 585);
DISPLAY INVISIBLE (-6390 585);
WIRE 16 -1 (-6625 675)(-5375 675);
FORCEPROP 0 LAST CDS_PHYS_NET_NAME FM_SWB_PWR_EN
J 0
(-6600 717);
PAINT MONO (-6600 717);
DISPLAY INVISIBLE (-6600 717);
FORCEPROP 0 LAST SIG_NAME HPDB_HSC_PWRGD_ISO_R
J 0
(-6150 675);
DISPLAY 0.553191 (-6150 675);
PAINT WHITE (-6150 675);
FORCEPROP 2 LASTPROP $XRERR UNIQUE?
J 0
(-6390 675);
DISPLAY 0.638298 (-6390 675);
PAINT MONO (-6390 675);
DISPLAY INVISIBLE (-6390 675);
WIRE 16 -1 (-7750 725)(-5375 725);
FORCEPROP 2 LAST SIG_NAME FM_LED_PWRGD_PVDD11_S3_P0
J 0
(-7650 730);
DISPLAY 0.489362 (-7650 730);
WIRE 16 -1 (-7750 775)(-5375 775);
FORCEPROP 2 LAST SIG_NAME FM_LED_PWRGD_PVDDIO_P0
J 0
(-7650 780);
DISPLAY 0.489362 (-7650 780);
WIRE 16 -1 (-7750 875)(-5375 875);
FORCEPROP 2 LAST SIG_NAME FM_LED_PWRGD_PVDD18_S5_P0
J 0
(-7650 880);
DISPLAY 0.489362 (-7650 880);
WIRE 16 -1 (-6625 925)(-5375 925);
FORCEPROP 2 LAST SIG_NAME P12V_E1S_0_EN
J 0
(-6150 935);
DISPLAY 0.489362 (-6150 935);
FORCEPROP 2 LASTPROP $XRERR UNIQUE?
J 0
(-6390 935);
DISPLAY 0.638298 (-6390 935);
PAINT MONO (-6390 935);
DISPLAY INVISIBLE (-6390 935);
WIRE 16 -1 (-7750 1025)(-5375 1025);
FORCEPROP 2 LAST SIG_NAME FM_LED_PWRGD_PVDD33_S5
J 0
(-7650 1030);
DISPLAY 0.489362 (-7650 1030);
WIRE 72 -1 (-6625 1125)(-5375 1125);
FORCEPROP 2 LAST SIG_NAME P0V9_RETIMER_CPU0_EN_R2
J 0
(-6150 1135);
DISPLAY 0.510638 (-6150 1135);
PAINT WHITE (-6150 1135);
FORCEPROP 2 LASTPROP $XRERR UNIQUE?
J 0
(-6390 1135);
DISPLAY 0.638298 (-6390 1135);
PAINT MONO (-6390 1135);
DISPLAY INVISIBLE (-6390 1135);
WIRE 16 -1 (-5375 1225)(-7750 1225);
FORCEPROP 2 LAST SIG_NAME BMC_FPGA_LED2
J 0
(-6150 1235);
DISPLAY 0.489362 (-6150 1235);
WIRE 16 -1 (-7750 1375)(-5375 1375);
FORCEPROP 2 LAST SIG_NAME FM_LED_PWRGD_PVDDCR_CPU0_P1
J 0
(-7650 1380);
DISPLAY 0.489362 (-7650 1380);
WIRE 16 -1 (-5375 1525)(-6625 1525);
FORCEPROP 2 LAST SIG_NAME FM_PWRGD_PVDDIO_P1
J 0
(-6150 1530);
DISPLAY 0.489362 (-6150 1530);
FORCEPROP 2 LASTPROP $XRERR UNIQUE?
J 0
(-6390 1530);
DISPLAY 0.638298 (-6390 1530);
PAINT MONO (-6390 1530);
DISPLAY INVISIBLE (-6390 1530);
WIRE 16 -1 (-7750 1725)(-5375 1725);
FORCEPROP 2 LAST SIG_NAME FM_PWRGD_PVDD18_S5_P0
J 0
(-7650 1730);
DISPLAY 0.489362 (-7650 1730);
WIRE 16 -1 (-7750 1275)(-5375 1275);
FORCEPROP 2 LAST SIG_NAME PWRGD_P1V2_AUX_R
J 0
(-7660 1285);
DISPLAY 0.510638 (-7660 1285);
PAINT WHITE (-7660 1285);
WIRE 16 -1 (-6625 1325)(-5375 1325);
FORCEPROP 2 LAST SIG_NAME FM_PLD_OCP_SFF_PWR_GOOD_R
J 0
(-6150 1340);
DISPLAY 0.489362 (-6150 1340);
FORCEPROP 2 LASTPROP $XRERR UNIQUE?
J 0
(-6390 1340);
DISPLAY 0.638298 (-6390 1340);
PAINT MONO (-6390 1340);
DISPLAY INVISIBLE (-6390 1340);
WIRE 16 -1 (-6625 1425)(-5375 1425);
FORCEPROP 2 LAST SIG_NAME P12V_E1S_0_PWRGD
J 0
(-6150 1435);
DISPLAY 0.489362 (-6150 1435);
FORCEPROP 2 LASTPROP $XRERR UNIQUE?
J 0
(-6390 1435);
DISPLAY 0.638298 (-6390 1435);
PAINT MONO (-6390 1435);
DISPLAY INVISIBLE (-6390 1435);
WIRE 16 -1 (-5375 1625)(-6625 1625);
FORCEPROP 2 LAST SIG_NAME FM_CPU0_PWR_GOOD
J 0
(-6150 1630);
DISPLAY 0.489362 (-6150 1630);
FORCEPROP 2 LASTPROP $XRERR UNIQUE?
J 0
(-6390 1630);
DISPLAY 0.638298 (-6390 1630);
PAINT MONO (-6390 1630);
DISPLAY INVISIBLE (-6390 1630);
WIRE 16 -1 (-7750 1675)(-5375 1675);
FORCEPROP 2 LAST SIG_NAME PWRGD_P1V8_AUX_R
J 0
(-7650 1680);
DISPLAY 0.489362 (-7650 1680);
WIRE 16 -1 (-5375 1775)(-6625 1775);
FORCEPROP 2 LAST SIG_NAME FM_PVDD18_S5_P0_EN
J 0
(-6150 1780);
DISPLAY 0.489362 (-6150 1780);
FORCEPROP 2 LASTPROP $XRERR UNIQUE?
J 0
(-6390 1780);
DISPLAY 0.638298 (-6390 1780);
PAINT MONO (-6390 1780);
DISPLAY INVISIBLE (-6390 1780);
WIRE 16 -1 (-6625 1825)(-5375 1825);
FORCEPROP 2 LAST SIG_NAME PWRGD_P3V3_AUX_R
J 0
(-6150 1835);
DISPLAY 0.489362 (-6150 1835);
FORCEPROP 2 LASTPROP $XRERR UNIQUE?
J 0
(-6390 1835);
DISPLAY 0.638298 (-6390 1835);
PAINT MONO (-6390 1835);
DISPLAY INVISIBLE (-6390 1835);
WIRE 72 -1 (-5375 1925)(-7750 1925);
FORCEPROP 0 LAST CDS_PHYS_NET_NAME TP_SPI_PLD_D1
J 2
(-5650 1975);
PAINT MONO (-5650 1975);
DISPLAY INVISIBLE (-5650 1975);
FORCEPROP 2 LAST SIG_NAME FM_PWRGD_P1V8_RETIMER_CPU1
J 0
(-7660 1935);
DISPLAY 0.489362 (-7660 1935);
WIRE 16 -1 (-5375 2025)(-6625 2025);
FORCEPROP 2 LAST SIG_NAME FM_FPGA_DEBUG_SW_SPARE
J 0
(-6150 2035);
DISPLAY 0.446809 (-6150 2035);
FORCEPROP 2 LASTPROP $XRERR UNIQUE?
J 0
(-6390 2035);
DISPLAY 0.638298 (-6390 2035);
PAINT MONO (-6390 2035);
DISPLAY INVISIBLE (-6390 2035);
WIRE 16 -1 (-5375 2125)(-6625 2125);
FORCEPROP 2 LAST SIG_NAME FM_PWRGD_PVDD11_S3_P1
J 0
(-6150 2130);
DISPLAY 0.489362 (-6150 2130);
FORCEPROP 2 LASTPROP $XRERR UNIQUE?
J 0
(-6390 2130);
DISPLAY 0.638298 (-6390 2130);
PAINT MONO (-6390 2130);
DISPLAY INVISIBLE (-6390 2130);
WIRE 16 -1 (-5375 2175)(-6625 2175);
FORCEPROP 2 LAST SIG_NAME FM_PVDD11_S3_P1_EN
J 0
(-6150 2180);
DISPLAY 0.489362 (-6150 2180);
FORCEPROP 2 LASTPROP $XRERR UNIQUE?
J 0
(-6390 2180);
DISPLAY 0.638298 (-6390 2180);
PAINT MONO (-6390 2180);
DISPLAY INVISIBLE (-6390 2180);
WIRE 16 -1 (-7750 2325)(-5375 2325);
FORCEPROP 2 LAST SIG_NAME FM_PWRGD_PVDD33_S5
J 0
(-7650 2330);
DISPLAY 0.489362 (-7650 2330);
WIRE 16 -1 (-7750 2375)(-5375 2375);
FORCEPROP 2 LAST SIG_NAME PWRGD_PVDD18_S5_R_P1
J 0
(-7650 2380);
DISPLAY 0.489362 (-7650 2380);
WIRE 16 -1 (-6625 2425)(-5375 2425);
FORCEPROP 2 LAST SIG_NAME P12V_SCM_PWRGD_R
J 0
(-6150 2435);
DISPLAY 0.489362 (-6150 2435);
FORCEPROP 2 LASTPROP $XRERR UNIQUE?
J 0
(-6390 2435);
DISPLAY 0.638298 (-6390 2435);
PAINT MONO (-6390 2435);
DISPLAY INVISIBLE (-6390 2435);
WIRE 16 -1 (-6625 2525)(-5375 2525);
FORCEPROP 0 LAST CDS_PHYS_NET_NAME GPU_3V3IO_RSVD1_ISO_R
J 0
(-6600 2567);
PAINT MONO (-6600 2567);
DISPLAY INVISIBLE (-6600 2567);
FORCEPROP 0 LAST SIG_NAME BMC_MONITER
J 0
(-6150 2535);
DISPLAY 0.553191 (-6150 2535);
PAINT WHITE (-6150 2535);
FORCEPROP 2 LASTPROP $XRERR UNIQUE?
J 0
(-6390 2535);
DISPLAY 0.638298 (-6390 2535);
PAINT MONO (-6390 2535);
DISPLAY INVISIBLE (-6390 2535);
WIRE 16 -1 (-6625 2575)(-5375 2575);
FORCEPROP 0 LAST CDS_PHYS_NET_NAME GPU_3V3IO_RSVD1_ISO_R
J 0
(-6600 2617);
PAINT MONO (-6600 2617);
DISPLAY INVISIBLE (-6600 2617);
FORCEPROP 0 LAST SIG_NAME GPU_FPGA_EROT_RECOV_R_N
J 0
(-6150 2585);
DISPLAY 0.553191 (-6150 2585);
PAINT WHITE (-6150 2585);
FORCEPROP 2 LASTPROP $XRERR UNIQUE?
J 0
(-6390 2585);
DISPLAY 0.638298 (-6390 2585);
PAINT MONO (-6390 2585);
DISPLAY INVISIBLE (-6390 2585);
WIRE 16 -1 (-5375 2675)(-6625 2675);
FORCEPROP 2 LAST SIG_NAME FM_UART_LS_EN
J 0
(-6150 2685);
DISPLAY 0.446809 (-6150 2685);
FORCEPROP 2 LASTPROP $XRERR UNIQUE?
J 0
(-6390 2685);
DISPLAY 0.638298 (-6390 2685);
PAINT MONO (-6390 2685);
DISPLAY INVISIBLE (-6390 2685);
WIRE 16 -1 (-6625 2725)(-5375 2725);
FORCEPROP 2 LAST SIG_NAME PRSNT_SWB_ISO_R_N
J 0
(-6160 2735);
DISPLAY 0.489362 (-6160 2735);
PAINT SKYBLUE (-6160 2735);
FORCEPROP 2 LASTPROP $XRERR UNIQUE?
J 0
(-6400 2735);
DISPLAY 0.638298 (-6400 2735);
PAINT MONO (-6400 2735);
DISPLAY INVISIBLE (-6400 2735);
WIRE 16 -1 (-6625 2775)(-5375 2775);
FORCEPROP 0 LAST CDS_PHYS_NET_NAME GPU_3V3IO_RSVD1_ISO_R
J 0
(-6600 2817);
PAINT MONO (-6600 2817);
DISPLAY INVISIBLE (-6600 2817);
FORCEPROP 0 LAST SIG_NAME GPU_FPGA_EROT_RST_R_N
J 0
(-6150 2785);
DISPLAY 0.553191 (-6150 2785);
PAINT WHITE (-6150 2785);
FORCEPROP 2 LASTPROP $XRERR UNIQUE?
J 0
(-6390 2785);
DISPLAY 0.638298 (-6390 2785);
PAINT MONO (-6390 2785);
DISPLAY INVISIBLE (-6390 2785);
WIRE 16 -1 (-5375 2825)(-6625 2825);
FORCEPROP 2 LAST SIG_NAME FM_PVDDCR_CPU0_P1_R_EN
J 0
(-6150 2830);
DISPLAY 0.489362 (-6150 2830);
FORCEPROP 2 LASTPROP $XRERR UNIQUE?
J 0
(-6390 2830);
DISPLAY 0.638298 (-6390 2830);
PAINT MONO (-6390 2830);
DISPLAY INVISIBLE (-6390 2830);
WIRE 16 -1 (-5375 2925)(-7750 2925);
FORCEPROP 2 LAST SIG_NAME PVDDCR_CPU0_P0_PMALERT
J 0
(-7650 2935);
DISPLAY 0.489362 (-7650 2935);
WIRE 16 -1 (-6625 2975)(-5375 2975);
FORCEPROP 2 LAST SIG_NAME PRSNT_OCP_SFF_N
J 0
(-6150 2985);
DISPLAY 0.489362 (-6150 2985);
FORCEPROP 2 LASTPROP $XRERR UNIQUE?
J 0
(-6390 2985);
DISPLAY 0.638298 (-6390 2985);
PAINT MONO (-6390 2985);
DISPLAY INVISIBLE (-6390 2985);
WIRE 16 -1 (-5375 3025)(-6625 3025);
FORCEPROP 2 LAST SIG_NAME FM_PWRGD_PVDDIO_P0
J 0
(-6150 3030);
DISPLAY 0.489362 (-6150 3030);
FORCEPROP 2 LASTPROP $XRERR UNIQUE?
J 0
(-6390 3030);
DISPLAY 0.638298 (-6390 3030);
PAINT MONO (-6390 3030);
DISPLAY INVISIBLE (-6390 3030);
WIRE 16 -1 (-5375 3075)(-6625 3075);
FORCEPROP 2 LAST SIG_NAME FM_PVDDIO_P0_EN
J 0
(-6150 3080);
DISPLAY 0.489362 (-6150 3080);
FORCEPROP 2 LASTPROP $XRERR UNIQUE?
J 0
(-6390 3080);
DISPLAY 0.638298 (-6390 3080);
PAINT MONO (-6390 3080);
DISPLAY INVISIBLE (-6390 3080);
WIRE 16 -1 (-3625 1325)(-825 1325);
FORCEPROP 2 LAST SIG_NAME RST_PERST_OCP_V3_2_N
J 0
(-3450 1335);
DISPLAY 0.553191 (-3450 1335);
PAINT WHITE (-3450 1335);
WIRE 16 -1 (-3625 825)(-1500 825);
FORCEPROP 2 LAST SIG_NAME FM_P5V_EN
J 0
(-2225 835);
DISPLAY 0.553191 (-2225 835);
PAINT WHITE (-2225 835);
WIRE 16 -1 (-3625 875)(-1500 875);
FORCEPROP 2 LAST SIG_NAME P3V3_OCP_V3_2_EN_R
J 0
(-2225 885);
DISPLAY 0.553191 (-2225 885);
PAINT WHITE (-2225 885);
WIRE 16 -1 (-2375 925)(-3625 925);
FORCEPROP 2 LAST SIG_NAME P0V9_RETIMER_CPU1_EN_R2
J 0
(-3110 935);
DISPLAY 0.489362 (-3110 935);
FORCEPROP 2 LASTPROP $XRERR UNIQUE?
J 0
(-3350 935);
DISPLAY 0.638298 (-3350 935);
PAINT MONO (-3350 935);
DISPLAY INVISIBLE (-3350 935);
WIRE 16 -1 (-3625 1025)(-850 1025);
FORCEPROP 0 LAST CDS_PHYS_NET_NAME GPU_FPGA_READY_ISO_R
J 0
(-3600 1067);
PAINT MONO (-3600 1067);
DISPLAY INVISIBLE (-3600 1067);
FORCEPROP 0 LAST SIG_NAME FM_AC_PWR_BTN_PLD_ISO_N
J 0
(-1700 1035);
DISPLAY 0.553191 (-1700 1035);
PAINT WHITE (-1700 1035);
WIRE 16 -1 (-3625 1125)(-850 1125);
FORCEPROP 2 LAST SIG_NAME P12V_OCP_V3_2_EN_R
J 0
(-1700 1135);
DISPLAY 0.553191 (-1700 1135);
PAINT WHITE (-1700 1135);
WIRE 16 -1 (-3625 1175)(-875 1175);
FORCEPROP 2 LAST SIG_NAME PRSNT_HDT_N
J 0
(-3450 1185);
DISPLAY 0.489362 (-3450 1185);
WIRE 16 -1 (-3625 1225)(-850 1225);
FORCEPROP 2 LAST SIG_NAME FM_NCSI_OCP_V3_2_R_OE
J 0
(-1700 1235);
DISPLAY 0.553191 (-1700 1235);
PAINT WHITE (-1700 1235);
WIRE 16 -1 (-2200 1375)(-850 1375);
FORCEPROP 0 LAST CDS_PHYS_NET_NAME SWB_HSC_PWRGD_ISO
J 0
(-2175 1417);
PAINT MONO (-2175 1417);
DISPLAY INVISIBLE (-2175 1417);
FORCEPROP 0 LAST SIG_NAME GPU_FPGA_READY_ISO
J 0
(-1700 1385);
DISPLAY 0.553191 (-1700 1385);
PAINT WHITE (-1700 1385);
WIRE 16 -1 (-3625 1425)(-825 1425);
FORCEPROP 2 LAST SIG_NAME RST_PERST_OCP_SFF_N
J 0
(-3450 1435);
DISPLAY 0.553191 (-3450 1435);
PAINT WHITE (-3450 1435);
WIRE 16 -1 (-2200 1275)(-850 1275);
FORCEPROP 0 LAST CDS_PHYS_NET_NAME SWB_HSC_PWRGD_ISO
J 0
(-2175 1317);
PAINT MONO (-2175 1317);
DISPLAY INVISIBLE (-2175 1317);
FORCEPROP 0 LAST SIG_NAME GPU_FPGA_BOOT_EN
J 0
(-1700 1285);
DISPLAY 0.553191 (-1700 1285);
PAINT WHITE (-1700 1285);
WIRE 16 -1 (-2175 925)(-825 925);
FORCEPROP 2 LAST SIG_NAME P0V9_RETIMER_CPU1_EN
J 0
(-1785 935);
DISPLAY 0.553191 (-1785 935);
WIRE 16 -1 (-3625 975)(-275 975);
FORCEPROP 0 LAST CDS_PHYS_NET_NAME TP_SPI_PLD_D0
J 2
(-550 1025);
PAINT MONO (-550 1025);
DISPLAY INVISIBLE (-550 1025);
FORCEPROP 2 LAST SIG_NAME PU_SPI_PLD_CS_N
J 0
(-2225 985);
DISPLAY 0.489362 (-2225 985);
FORCEPROP 2 LASTPROP $XRERR UNIQUE?
J 0
(-2465 985);
DISPLAY 0.638298 (-2465 985);
PAINT MONO (-2465 985);
DISPLAY INVISIBLE (-2465 985);
WIRE 16 -1 (-275 975)(-275 1025);
WIRE 16 -1 (-2200 1075)(-850 1075);
FORCEPROP 0 LAST CDS_PHYS_NET_NAME SWB_HSC_PWRGD_ISO
J 0
(-2175 1117);
PAINT MONO (-2175 1117);
DISPLAY INVISIBLE (-2175 1117);
FORCEPROP 0 LAST SIG_NAME GPU_BASE_STBY_EN
J 0
(-1700 1085);
DISPLAY 0.553191 (-1700 1085);
PAINT WHITE (-1700 1085);
WIRE 16 -1 (-2200 1475)(-850 1475);
FORCEPROP 0 LAST CDS_PHYS_NET_NAME SWB_HSC_PWRGD_ISO
J 0
(-2175 1517);
PAINT MONO (-2175 1517);
DISPLAY INVISIBLE (-2175 1517);
FORCEPROP 0 LAST SIG_NAME FM_SMB_2_ALERT_GPU_ISO_N
J 0
(-1700 1485);
DISPLAY 0.553191 (-1700 1485);
PAINT WHITE (-1700 1485);
WIRE 16 -1 (-6825 2625)(-7750 2625);
FORCEPROP 2 LAST SIG_NAME PWRGD_PVDDCR_CPU1_P1
J 0
(-7650 2635);
DISPLAY 0.489362 (-7650 2635);
WIRE 16 -1 (-6825 2725)(-7725 2725);
FORCEPROP 2 LAST SIG_NAME PRSNT_SWB_ISO_N
J 0
(-7660 2735);
DISPLAY 0.680851 (-7660 2735);
PAINT SKYBLUE (-7660 2735);
WIRE 16 -1 (-7750 2775)(-6825 2775);
FORCEPROP 0 LAST CDS_PHYS_NET_NAME GPU_3V3IO_RSVD1_ISO
J 0
(-7725 2817);
PAINT MONO (-7725 2817);
DISPLAY INVISIBLE (-7725 2817);
FORCEPROP 0 LAST SIG_NAME GPU_FPGA_EROT_RST_N
J 0
(-7650 2785);
DISPLAY 0.553191 (-7650 2785);
PAINT WHITE (-7650 2785);
WIRE 16 -1 (-7750 2975)(-6825 2975);
FORCEPROP 2 LAST SIG_NAME HP_LVC3_OCP_SFF_PRSNT2_PLD_N
J 0
(-7650 2985);
DISPLAY 0.446809 (-7650 2985);
WIRE 16 -1 (-6825 3025)(-7750 3025);
FORCEPROP 2 LAST SIG_NAME PWRGD_PVDDIO_P0
J 0
(-7650 3035);
DISPLAY 0.489362 (-7650 3035);
WIRE 16 -1 (-7750 2275)(-6825 2275);
FORCEPROP 0 LAST CDS_PHYS_NET_NAME GPU_3V3IO_RSVD1_ISO
J 0
(-7725 2317);
PAINT MONO (-7725 2317);
DISPLAY INVISIBLE (-7725 2317);
FORCEPROP 0 LAST SIG_NAME FM_GPU_PWR_EN_R
J 0
(-7650 2285);
DISPLAY 0.553191 (-7650 2285);
PAINT WHITE (-7650 2285);
WIRE 16 -1 (-6825 2475)(-7750 2475);
FORCEPROP 2 LAST SIG_NAME PWRGD_PVDDCR_CPU0_P1
J 0
(-7650 2485);
DISPLAY 0.489362 (-7650 2485);
WIRE 16 -1 (-6825 2675)(-7750 2675);
FORCEPROP 2 LAST SIG_NAME UART_LS_EN
J 0
(-7650 2685);
DISPLAY 0.446809 (-7650 2685);
WIRE 16 -1 (-6625 3125)(-5375 3125);
FORCEPROP 0 LAST CDS_PHYS_NET_NAME GPU_3V3IO_RSVD1_ISO_R
J 0
(-6600 3167);
PAINT MONO (-6600 3167);
DISPLAY INVISIBLE (-6600 3167);
FORCEPROP 0 LAST SIG_NAME GPU_NVS_PWR_BRAKE_R_N
J 0
(-6150 3135);
DISPLAY 0.553191 (-6150 3135);
PAINT WHITE (-6150 3135);
FORCEPROP 2 LASTPROP $XRERR UNIQUE?
J 0
(-6390 3135);
DISPLAY 0.638298 (-6390 3135);
PAINT MONO (-6390 3135);
DISPLAY INVISIBLE (-6390 3135);
WIRE 16 -1 (-6525 3875)(-7300 3875);
FORCEPROP 2 LAST SIG_NAME RST_RT_CPU0_P1_PERST_R_N
J 0
(-7235 3885);
DISPLAY 0.553191 (-7235 3885);
WIRE 16 -1 (-7750 3125)(-6825 3125);
FORCEPROP 0 LAST CDS_PHYS_NET_NAME GPU_3V3IO_RSVD1_ISO
J 0
(-7725 3167);
PAINT MONO (-7725 3167);
DISPLAY INVISIBLE (-7725 3167);
FORCEPROP 0 LAST SIG_NAME GPU_NVS_PWR_BRAKE_N
J 0
(-7650 3135);
DISPLAY 0.553191 (-7650 3135);
PAINT WHITE (-7650 3135);
WIRE 16 -1 (-7750 3175)(-6825 3175);
FORCEPROP 0 LAST CDS_PHYS_NET_NAME GPU_3V3IO_RSVD1_ISO
J 0
(-7725 3217);
PAINT MONO (-7725 3217);
DISPLAY INVISIBLE (-7725 3217);
FORCEPROP 0 LAST SIG_NAME FM_SWB_PWR_EN_R
J 0
(-7650 3185);
DISPLAY 0.553191 (-7650 3185);
PAINT WHITE (-7650 3185);
WIRE 16 -1 (-2200 2875)(-850 2875);
FORCEPROP 0 LAST CDS_PHYS_NET_NAME GPU_3V3IO_RSVD1_ISO
J 0
(-2175 2917);
PAINT MONO (-2175 2917);
DISPLAY INVISIBLE (-2175 2917);
FORCEPROP 0 LAST SIG_NAME GPU_3V3IO_RSVD4_ISO
J 0
(-1700 2885);
DISPLAY 0.553191 (-1700 2885);
PAINT WHITE (-1700 2885);
WIRE 16 -1 (-6625 3175)(-5375 3175);
FORCEPROP 0 LAST CDS_PHYS_NET_NAME GPU_3V3IO_RSVD1_ISO_R
J 0
(-6600 3217);
PAINT MONO (-6600 3217);
DISPLAY INVISIBLE (-6600 3217);
FORCEPROP 0 LAST SIG_NAME FM_SWB_PWR_EN
J 0
(-6150 3185);
DISPLAY 0.553191 (-6150 3185);
PAINT WHITE (-6150 3185);
FORCEPROP 2 LASTPROP $XRERR UNIQUE?
J 0
(-6390 3185);
DISPLAY 0.638298 (-6390 3185);
PAINT MONO (-6390 3185);
DISPLAY INVISIBLE (-6390 3185);
WIRE 16 -1 (-3625 1775)(-2400 1775);
FORCEPROP 0 LAST CDS_PHYS_NET_NAME GPU_3V3IO_RSVD1_ISO_R
J 0
(-3600 1817);
PAINT MONO (-3600 1817);
DISPLAY INVISIBLE (-3600 1817);
FORCEPROP 0 LAST SIG_NAME FM_SWB_BIC_READY_ISO_R_N
J 0
(-3450 1785);
DISPLAY 0.553191 (-3450 1785);
PAINT WHITE (-3450 1785);
FORCEPROP 2 LASTPROP $XRERR UNIQUE?
J 0
(-3690 1785);
DISPLAY 0.638298 (-3690 1785);
PAINT MONO (-3690 1785);
DISPLAY INVISIBLE (-3690 1785);
WIRE 16 -1 (-3625 1825)(-2400 1825);
FORCEPROP 0 LAST CDS_PHYS_NET_NAME GPU_3V3IO_RSVD1_ISO_R
J 0
(-3600 1867);
PAINT MONO (-3600 1867);
DISPLAY INVISIBLE (-3600 1867);
FORCEPROP 0 LAST SIG_NAME RST_BMC_FROM_SWB_ISO_R_N
J 0
(-3450 1835);
DISPLAY 0.553191 (-3450 1835);
PAINT WHITE (-3450 1835);
FORCEPROP 2 LASTPROP $XRERR UNIQUE?
J 0
(-3690 1835);
DISPLAY 0.638298 (-3690 1835);
PAINT MONO (-3690 1835);
DISPLAY INVISIBLE (-3690 1835);
WIRE 16 -1 (-3625 1725)(-2400 1725);
FORCEPROP 0 LAST CDS_PHYS_NET_NAME GPU_3V3IO_RSVD1_ISO_R
J 0
(-3600 1767);
PAINT MONO (-3600 1767);
DISPLAY INVISIBLE (-3600 1767);
FORCEPROP 0 LAST SIG_NAME FM_SMB_1_ALERT_GPU_ISO_R_N
J 0
(-3450 1735);
DISPLAY 0.553191 (-3450 1735);
PAINT WHITE (-3450 1735);
FORCEPROP 2 LASTPROP $XRERR UNIQUE?
J 0
(-3690 1735);
DISPLAY 0.638298 (-3690 1735);
PAINT MONO (-3690 1735);
DISPLAY INVISIBLE (-3690 1735);
WIRE 16 -1 (-3325 3825)(-4200 3825);
FORCEPROP 2 LAST SIG_NAME FM_CPU1_FORCE_SELFREFRESH
J 0
(-4060 3835);
DISPLAY 0.489362 (-4060 3835);
FORCEPROP 2 LASTPROP $XRERR UNIQUE?
J 0
(-4300 3835);
DISPLAY 0.638298 (-4300 3835);
PAINT MONO (-4300 3835);
DISPLAY INVISIBLE (-4300 3835);
WIRE 16 -1 (-3325 3875)(-4200 3875);
FORCEPROP 2 LAST SIG_NAME FM_FORCE_ALL_PWRON_R
J 0
(-4060 3885);
DISPLAY 0.489362 (-4060 3885);
FORCEPROP 2 LASTPROP $XRERR UNIQUE?
J 0
(-4300 3885);
DISPLAY 0.638298 (-4300 3885);
PAINT MONO (-4300 3885);
DISPLAY INVISIBLE (-4300 3885);
WIRE 16 -1 (-2350 3875)(-3125 3875);
FORCEPROP 2 LAST SIG_NAME FM_FORCE_ALL_PWRON
J 0
(-2975 3885);
DISPLAY 0.489362 (-2975 3885);
WIRE 16 -1 (-2350 3825)(-3125 3825);
FORCEPROP 2 LAST SIG_NAME CPU1_FORCE_SELFREFRESH
J 0
(-2975 3835);
DISPLAY 0.489362 (-2975 3835);
WIRE 16 -1 (-3125 3775)(-2350 3775);
FORCEPROP 2 LAST SIG_NAME RST_SMB_RT_R1_N
J 0
(-2960 3785);
DISPLAY 0.553191 (-2960 3785);
WIRE 16 -1 (-3125 4075)(-2350 4075);
FORCEPROP 2 LAST SIG_NAME CPU1_PWR_GD_IN
J 0
(-2975 4085);
DISPLAY 0.446809 (-2975 4085);
WIRE 16 -1 (-2350 4025)(-3125 4025);
FORCEPROP 2 LAST SIG_NAME CPU0_FORCE_SELFREFRESH
J 0
(-2975 4035);
DISPLAY 0.489362 (-2975 4035);
WIRE 16 -1 (-6525 5025)(-7300 5025);
FORCEPROP 2 LAST SIG_NAME CPU0_JTAG_BUF_OE
J 0
(-7135 5035);
DISPLAY 0.446809 (-7135 5035);
WIRE 16 -1 (-7300 4975)(-6525 4975);
FORCEPROP 2 LAST SIG_NAME PWRGD_CPU0_PWROK
J 0
(-7125 4985);
DISPLAY 0.489362 (-7125 4985);
WIRE 16 -1 (-6525 4925)(-7300 4925);
FORCEPROP 2 LAST SIG_NAME CPU1_NV_SAVE_N
J 0
(-7125 4935);
DISPLAY 0.489362 (-7125 4935);
WIRE 16 -1 (-6525 4675)(-7300 4675);
FORCEPROP 2 LAST SIG_NAME PWRGD_CPU1_PWROK
J 0
(-7125 4685);
DISPLAY 0.489362 (-7125 4685);
WIRE 16 -1 (-7300 4725)(-6525 4725);
FORCEPROP 2 LAST SIG_NAME FPGA_DEBUG_LED_CTRL
J 0
(-7125 4735);
DISPLAY 0.489362 (-7125 4735);
WIRE 16 -1 (-6325 4725)(-5450 4725);
FORCEPROP 2 LAST SIG_NAME FM_FPGA_DEBUG_LED_CTRL
J 0
(-6175 4735);
DISPLAY 0.489362 (-6175 4735);
FORCEPROP 2 LASTPROP $XRERR UNIQUE?
J 0
(-6415 4735);
DISPLAY 0.638298 (-6415 4735);
PAINT MONO (-6415 4735);
DISPLAY INVISIBLE (-6415 4735);
WIRE 16 -1 (-6525 4525)(-7300 4525);
FORCEPROP 2 LAST SIG_NAME CPU0_PWR_BTN_N
J 0
(-7125 4535);
DISPLAY 0.489362 (-7125 4535);
WIRE 16 -1 (-7300 4625)(-6525 4625);
FORCEPROP 2 LAST SIG_NAME FM_P1_PCC0_N
J 0
(-7125 4635);
DISPLAY 0.489362 (-7125 4635);
WIRE 16 -1 (-6525 4425)(-7300 4425);
FORCEPROP 2 LAST SIG_NAME RST_RT_CPU1_P2_PERST_R_N
J 0
(-7260 4435);
DISPLAY 0.553191 (-7260 4435);
WIRE 16 -1 (-6525 4375)(-7300 4375);
FORCEPROP 2 LAST SIG_NAME RST_RT_CPU1_P2_RESET_R_N
J 0
(-7260 4385);
DISPLAY 0.553191 (-7260 4385);
WIRE 16 -1 (-2400 1625)(-3625 1625);
FORCEPROP 2 LAST SIG_NAME RST_PERST_M2_0_R_N
J 0
(-3450 1630);
DISPLAY 0.617021 (-3450 1630);
FORCEPROP 2 LASTPROP $XRERR UNIQUE?
J 0
(-3690 1630);
DISPLAY 0.638298 (-3690 1630);
PAINT MONO (-3690 1630);
DISPLAY INVISIBLE (-3690 1630);
WIRE 16 -1 (-3625 1525)(-2400 1525);
FORCEPROP 0 LAST CDS_PHYS_NET_NAME GPU_3V3IO_RSVD1_ISO_R
J 0
(-3600 1567);
PAINT MONO (-3600 1567);
DISPLAY INVISIBLE (-3600 1567);
FORCEPROP 0 LAST SIG_NAME FM_GPU_PWRGD_ISO_R
J 0
(-3450 1535);
DISPLAY 0.553191 (-3450 1535);
PAINT WHITE (-3450 1535);
FORCEPROP 2 LASTPROP $XRERR UNIQUE?
J 0
(-3690 1535);
DISPLAY 0.638298 (-3690 1535);
PAINT MONO (-3690 1535);
DISPLAY INVISIBLE (-3690 1535);
WIRE 16 -1 (-3625 1375)(-2400 1375);
FORCEPROP 0 LAST CDS_PHYS_NET_NAME GPU_3V3IO_RSVD1_ISO_R
J 0
(-3600 1417);
PAINT MONO (-3600 1417);
DISPLAY INVISIBLE (-3600 1417);
FORCEPROP 0 LAST SIG_NAME GPU_FPGA_READY_ISO_R
J 0
(-3450 1385);
DISPLAY 0.553191 (-3450 1385);
PAINT WHITE (-3450 1385);
FORCEPROP 2 LASTPROP $XRERR UNIQUE?
J 0
(-3690 1385);
DISPLAY 0.638298 (-3690 1385);
PAINT MONO (-3690 1385);
DISPLAY INVISIBLE (-3690 1385);
WIRE 16 -1 (-2200 2675)(-850 2675);
FORCEPROP 0 LAST CDS_PHYS_NET_NAME GPU_3V3IO_RSVD1_ISO
J 0
(-2175 2717);
PAINT MONO (-2175 2717);
DISPLAY INVISIBLE (-2175 2717);
FORCEPROP 0 LAST SIG_NAME SWB_HSC_EN
J 0
(-1700 2685);
DISPLAY 0.553191 (-1700 2685);
PAINT WHITE (-1700 2685);
WIRE 16 -1 (-2200 2025)(-850 2025);
FORCEPROP 0 LAST CDS_PHYS_NET_NAME GPU_BB_RSVD_1_ISO
J 0
(-2175 2067);
PAINT MONO (-2175 2067);
DISPLAY INVISIBLE (-2175 2067);
FORCEPROP 0 LAST SIG_NAME GPU_WP_HW_CTRL_N
J 0
(-1700 2035);
DISPLAY 0.553191 (-1700 2035);
PAINT WHITE (-1700 2035);
WIRE 16 -1 (-2200 2625)(-850 2625);
FORCEPROP 0 LAST CDS_PHYS_NET_NAME GPU_3V3IO_RSVD1_ISO
J 0
(-2175 2667);
PAINT MONO (-2175 2667);
DISPLAY INVISIBLE (-2175 2667);
FORCEPROP 0 LAST SIG_NAME GPU_3V3IO_RSVD0_FFU_ISO
J 0
(-1700 2635);
DISPLAY 0.553191 (-1700 2635);
PAINT WHITE (-1700 2635);
WIRE 16 -1 (-2200 1975)(-850 1975);
FORCEPROP 0 LAST CDS_PHYS_NET_NAME SWB_HSC_PWRGD_ISO
J 0
(-2175 2017);
PAINT MONO (-2175 2017);
DISPLAY INVISIBLE (-2175 2017);
FORCEPROP 0 LAST SIG_NAME GPU_PRSNT_N_ISO
J 0
(-1700 1985);
DISPLAY 0.553191 (-1700 1985);
PAINT WHITE (-1700 1985);
WIRE 16 -1 (-2200 2075)(-850 2075);
FORCEPROP 0 LAST CDS_PHYS_NET_NAME SWB_HSC_PWRGD_ISO
J 0
(-2175 2117);
PAINT MONO (-2175 2117);
DISPLAY INVISIBLE (-2175 2117);
FORCEPROP 0 LAST SIG_NAME GPU_FPGA_OVERT_ISO_N
J 0
(-1700 2085);
DISPLAY 0.553191 (-1700 2085);
PAINT WHITE (-1700 2085);
WIRE 16 -1 (-2200 2425)(-850 2425);
FORCEPROP 0 LAST CDS_PHYS_NET_NAME GPU_3V3IO_RSVD0_FFU_ISO
J 0
(-2175 2467);
PAINT MONO (-2175 2467);
DISPLAY INVISIBLE (-2175 2467);
FORCEPROP 0 LAST SIG_NAME PRSNT_CABLE_GPU_A2_ISO_N
J 0
(-1700 2435);
DISPLAY 0.553191 (-1700 2435);
PAINT WHITE (-1700 2435);
WIRE 16 -1 (-2200 2575)(-850 2575);
FORCEPROP 0 LAST CDS_PHYS_NET_NAME GPU_3V3IO_RSVD1_ISO
J 0
(-2175 2617);
PAINT MONO (-2175 2617);
DISPLAY INVISIBLE (-2175 2617);
FORCEPROP 0 LAST SIG_NAME GPU_3V3IO_RSVD1_FFU_ISO
J 0
(-1700 2585);
DISPLAY 0.553191 (-1700 2585);
PAINT WHITE (-1700 2585);
WIRE 16 -1 (-2200 2375)(-850 2375);
FORCEPROP 0 LAST CDS_PHYS_NET_NAME GPU_3V3IO_RSVD0_FFU_ISO
J 0
(-2175 2417);
PAINT MONO (-2175 2417);
DISPLAY INVISIBLE (-2175 2417);
FORCEPROP 0 LAST SIG_NAME GPU_3V3IO_RSVD5_FFU_ISO
J 0
(-1700 2385);
DISPLAY 0.553191 (-1700 2385);
PAINT WHITE (-1700 2385);
WIRE 16 -1 (-2200 2175)(-850 2175);
FORCEPROP 0 LAST CDS_PHYS_NET_NAME GPU_3V3IO_RSVD0_FFU_ISO
J 0
(-2175 2217);
PAINT MONO (-2175 2217);
DISPLAY INVISIBLE (-2175 2217);
FORCEPROP 0 LAST SIG_NAME GPU_BASE_HMC_READY_ISO
J 0
(-1700 2185);
DISPLAY 0.553191 (-1700 2185);
PAINT WHITE (-1700 2185);
WIRE 16 -1 (-3625 2125)(-2400 2125);
FORCEPROP 0 LAST CDS_PHYS_NET_NAME GPU_3V3IO_RSVD1_ISO_R
J 0
(-3600 2167);
PAINT MONO (-3600 2167);
DISPLAY INVISIBLE (-3600 2167);
FORCEPROP 0 LAST SIG_NAME GPU_HMC_PRSNT_ISO_R_N
J 0
(-3450 2135);
DISPLAY 0.553191 (-3450 2135);
PAINT WHITE (-3450 2135);
FORCEPROP 2 LASTPROP $XRERR UNIQUE?
J 0
(-3690 2135);
DISPLAY 0.638298 (-3690 2135);
PAINT MONO (-3690 2135);
DISPLAY INVISIBLE (-3690 2135);
WIRE 16 -1 (-2200 2325)(-850 2325);
FORCEPROP 0 LAST CDS_PHYS_NET_NAME GPU_3V3IO_RSVD0_FFU_ISO
J 0
(-2175 2367);
PAINT MONO (-2175 2367);
DISPLAY INVISIBLE (-2175 2367);
FORCEPROP 0 LAST SIG_NAME PRSNT_CABLE_GPU_A1_ISO_N
J 0
(-1700 2335);
DISPLAY 0.553191 (-1700 2335);
PAINT WHITE (-1700 2335);
WIRE 16 -1 (-3625 2275)(-2400 2275);
FORCEPROP 0 LAST CDS_PHYS_NET_NAME GPU_3V3IO_RSVD1_ISO_R
J 0
(-3600 2317);
PAINT MONO (-3600 2317);
DISPLAY INVISIBLE (-3600 2317);
FORCEPROP 0 LAST SIG_NAME SWB_HSC_PWRGD_ISO_R
J 0
(-3450 2285);
DISPLAY 0.553191 (-3450 2285);
PAINT WHITE (-3450 2285);
FORCEPROP 2 LASTPROP $XRERR UNIQUE?
J 0
(-3690 2285);
DISPLAY 0.638298 (-3690 2285);
PAINT MONO (-3690 2285);
DISPLAY INVISIBLE (-3690 2285);
WIRE 16 -1 (-3625 2225)(-2400 2225);
FORCEPROP 0 LAST CDS_PHYS_NET_NAME GPU_3V3IO_RSVD1_ISO_R
J 0
(-3600 2267);
PAINT MONO (-3600 2267);
DISPLAY INVISIBLE (-3600 2267);
FORCEPROP 0 LAST SIG_NAME GPU_FPGA_THERM_OVERT_ISO_R_N
J 0
(-3450 2235);
DISPLAY 0.553191 (-3450 2235);
PAINT WHITE (-3450 2235);
FORCEPROP 2 LASTPROP $XRERR UNIQUE?
J 0
(-3690 2235);
DISPLAY 0.638298 (-3690 2235);
PAINT MONO (-3690 2235);
DISPLAY INVISIBLE (-3690 2235);
WIRE 16 -1 (-3625 2175)(-2400 2175);
FORCEPROP 0 LAST CDS_PHYS_NET_NAME GPU_3V3IO_RSVD1_ISO_R
J 0
(-3600 2217);
PAINT MONO (-3600 2217);
DISPLAY INVISIBLE (-3600 2217);
FORCEPROP 0 LAST SIG_NAME GPU_BASE_HMC_READY_ISO_R
J 0
(-3450 2185);
DISPLAY 0.553191 (-3450 2185);
PAINT WHITE (-3450 2185);
FORCEPROP 2 LASTPROP $XRERR UNIQUE?
J 0
(-3690 2185);
DISPLAY 0.638298 (-3690 2185);
PAINT MONO (-3690 2185);
DISPLAY INVISIBLE (-3690 2185);
WIRE 16 -1 (-6525 4775)(-7300 4775);
FORCEPROP 2 LAST SIG_NAME CPU0_NMI_SYNC_FLOOD_N
J 0
(-7125 4785);
DISPLAY 0.489362 (-7125 4785);
WIRE 16 -1 (-7300 5075)(-6525 5075);
FORCEPROP 2 LAST SIG_NAME RST_CPU0_KBRST_R_N
J 0
(-7125 5085);
DISPLAY 0.489362 (-7125 5085);
WIRE 16 -1 (-7300 5125)(-6525 5125);
FORCEPROP 2 LAST SIG_NAME RST_CPU1_RESETL_N
J 0
(-7125 5135);
DISPLAY 0.489362 (-7125 5135);
WIRE 16 -1 (-6525 5225)(-7325 5225);
FORCEPROP 2 LAST SIG_NAME RST_RT_CPU1_P1_RESET_R_N
J 0
(-7285 5235);
DISPLAY 0.553191 (-7285 5235);
WIRE 16 -1 (-7300 4475)(-6525 4475);
FORCEPROP 2 LAST SIG_NAME FM_P1_PCC1_N
J 0
(-7125 4485);
DISPLAY 0.489362 (-7125 4485);
WIRE 16 -1 (-6525 4275)(-7300 4275);
FORCEPROP 2 LAST SIG_NAME FM_P0_PCC0_N
J 0
(-7125 4285);
DISPLAY 0.489362 (-7125 4285);
WIRE 16 -1 (-6525 4325)(-7300 4325);
FORCEPROP 2 LAST SIG_NAME FM_P0_PCC1_N
J 0
(-7125 4335);
DISPLAY 0.489362 (-7125 4335);
WIRE 16 -1 (-6525 3975)(-7300 3975);
FORCEPROP 2 LAST SIG_NAME RST_RT_CPU0_P0_PERST_R_N
J 0
(-7235 3985);
DISPLAY 0.553191 (-7235 3985);
WIRE 16 -1 (-6525 3925)(-7300 3925);
FORCEPROP 2 LAST SIG_NAME RST_RT_CPU0_P0_RESET_R_N
J 0
(-7235 3935);
DISPLAY 0.553191 (-7235 3935);
WIRE 16 -1 (-6525 4025)(-7300 4025);
FORCEPROP 2 LAST SIG_NAME RST_RT_CPU1_P3_RESET_R_N
J 0
(-7235 4035);
DISPLAY 0.553191 (-7235 4035);
WIRE 16 -1 (-6525 4075)(-7300 4075);
FORCEPROP 2 LAST SIG_NAME RST_RT_CPU1_P3_PERST_R_N
J 0
(-7235 4085);
DISPLAY 0.553191 (-7235 4085);
WIRE 16 -1 (-2350 4225)(-3125 4225);
FORCEPROP 2 LAST SIG_NAME FM_SPD_CPU0_SWITCH_CTRL_N
J 0
(-2975 4235);
DISPLAY 0.489362 (-2975 4235);
WIRE 16 -1 (-2350 4175)(-3125 4175);
FORCEPROP 2 LAST SIG_NAME CPU0_HDT_BYPASS_SEL
J 0
(-2975 4185);
DISPLAY 0.489362 (-2975 4185);
WIRE 16 -1 (-3125 4125)(-2350 4125);
FORCEPROP 2 LAST SIG_NAME CPU1_PWRGD_OUT
J 0
(-2975 4135);
DISPLAY 0.446809 (-2975 4135);
WIRE 16 -1 (-5450 4425)(-6325 4425);
FORCEPROP 0 LAST SIG_NAME RST_RT_CPU1_P2_PERST_R2_N
J 0
(-6150 4435);
DISPLAY 0.489362 (-6150 4435);
FORCEPROP 2 LASTPROP $XRERR UNIQUE?
J 0
(-6390 4435);
DISPLAY 0.638298 (-6390 4435);
PAINT MONO (-6390 4435);
DISPLAY INVISIBLE (-6390 4435);
WIRE 16 -1 (-6325 4375)(-5450 4375);
FORCEPROP 0 LAST SIG_NAME RST_RT_CPU1_P2_RESET_R2_N
J 0
(-6150 4385);
DISPLAY 0.489362 (-6150 4385);
FORCEPROP 2 LASTPROP $XRERR UNIQUE?
J 0
(-6390 4385);
DISPLAY 0.638298 (-6390 4385);
PAINT MONO (-6390 4385);
DISPLAY INVISIBLE (-6390 4385);
WIRE 16 -1 (-5450 4325)(-6325 4325);
FORCEPROP 2 LAST SIG_NAME FM_P0_PCC1_R_N
J 0
(-6175 4335);
DISPLAY 0.489362 (-6175 4335);
FORCEPROP 2 LASTPROP $XRERR UNIQUE?
J 0
(-6415 4335);
DISPLAY 0.638298 (-6415 4335);
PAINT MONO (-6415 4335);
DISPLAY INVISIBLE (-6415 4335);
WIRE 16 -1 (-6325 4275)(-5450 4275);
FORCEPROP 2 LAST SIG_NAME FM_P0_PCC0_R_N
J 0
(-6175 4285);
DISPLAY 0.489362 (-6175 4285);
FORCEPROP 2 LASTPROP $XRERR UNIQUE?
J 0
(-6415 4285);
DISPLAY 0.638298 (-6415 4285);
PAINT MONO (-6415 4285);
DISPLAY INVISIBLE (-6415 4285);
WIRE 16 -1 (-7300 4225)(-5450 4225);
FORCEPROP 2 LAST SIG_NAME APML_CPU1_ALERT_R_N
J 0
(-7125 4235);
DISPLAY 0.489362 (-7125 4235);
WIRE 16 -1 (-6525 4125)(-7300 4125);
FORCEPROP 2 LAST SIG_NAME CPU1_SPD_HOST_CTRL_N
J 0
(-7125 4135);
DISPLAY 0.489362 (-7125 4135);
WIRE 16 -1 (-6325 4025)(-5450 4025);
FORCEPROP 2 LAST SIG_NAME RST_RT_CPU1_P3_RESET_R2_N
J 0
(-6150 4035);
DISPLAY 0.489362 (-6150 4035);
FORCEPROP 2 LASTPROP $XRERR UNIQUE?
J 0
(-6390 4035);
DISPLAY 0.638298 (-6390 4035);
PAINT MONO (-6390 4035);
DISPLAY INVISIBLE (-6390 4035);
WIRE 16 -1 (-6525 3825)(-7300 3825);
FORCEPROP 2 LAST SIG_NAME RST_RT_CPU0_P1_RESET_R_N
J 0
(-7235 3835);
DISPLAY 0.553191 (-7235 3835);
WIRE 16 -1 (-6325 4125)(-5450 4125);
FORCEPROP 2 LAST SIG_NAME CPU1_SPD_HOST_CTRL_R1_N
J 0
(-6175 4135);
DISPLAY 0.489362 (-6175 4135);
FORCEPROP 2 LASTPROP $XRERR UNIQUE?
J 0
(-6415 4135);
DISPLAY 0.638298 (-6415 4135);
PAINT MONO (-6415 4135);
DISPLAY INVISIBLE (-6415 4135);
WIRE 16 -1 (-5450 3825)(-6325 3825);
FORCEPROP 2 LAST SIG_NAME RST_RT_CPU0_P1_RESET_R2_N
J 0
(-6160 3835);
DISPLAY 0.489362 (-6160 3835);
FORCEPROP 2 LASTPROP $XRERR UNIQUE?
J 0
(-6400 3835);
DISPLAY 0.638298 (-6400 3835);
PAINT MONO (-6400 3835);
DISPLAY INVISIBLE (-6400 3835);
WIRE 16 -1 (-6325 3975)(-5450 3975);
FORCEPROP 2 LAST SIG_NAME RST_RT_CPU0_P0_PERST_R2_N
J 0
(-6150 3985);
DISPLAY 0.489362 (-6150 3985);
FORCEPROP 2 LASTPROP $XRERR UNIQUE?
J 0
(-6390 3985);
DISPLAY 0.638298 (-6390 3985);
PAINT MONO (-6390 3985);
DISPLAY INVISIBLE (-6390 3985);
WIRE 16 -1 (-3125 5875)(-2350 5875);
FORCEPROP 2 LAST SIG_NAME FM_ESPI_CPU0_ALERT_R_SEL
J 0
(-2985 5885);
DISPLAY 0.553191 (-2985 5885);
WIRE 16 -1 (-3125 6175)(-2350 6175);
FORCEPROP 2 LAST SIG_NAME FM_SMERR_LED_N
J 0
(-2975 6185);
DISPLAY 0.489362 (-2975 6185);
WIRE 16 -1 (-3125 6125)(-2350 6125);
FORCEPROP 2 LAST SIG_NAME CPU0_SMERR_N
J 0
(-2975 6135);
DISPLAY 0.489362 (-2975 6135);
WIRE 16 -1 (-3325 5425)(-4200 5425);
FORCEPROP 2 LAST SIG_NAME ESPI_CPU0_ALERT_R_N
J 0
(-4060 5435);
DISPLAY 0.446809 (-4060 5435);
FORCEPROP 2 LASTPROP $XRERR UNIQUE?
J 0
(-4300 5435);
DISPLAY 0.638298 (-4300 5435);
PAINT MONO (-4300 5435);
DISPLAY INVISIBLE (-4300 5435);
WIRE 16 -1 (-3325 5375)(-4200 5375);
FORCEPROP 2 LAST SIG_NAME RST_ESPI_CPU0_RSTOUT_R_N
J 0
(-4060 5385);
DISPLAY 0.446809 (-4060 5385);
FORCEPROP 2 LASTPROP $XRERR UNIQUE?
J 0
(-4300 5385);
DISPLAY 0.638298 (-4300 5385);
PAINT MONO (-4300 5385);
DISPLAY INVISIBLE (-4300 5385);
WIRE 16 -1 (-3125 5325)(-2350 5325);
FORCEPROP 2 LAST SIG_NAME ESPI_CPU0_D0
J 0
(-2975 5335);
DISPLAY 0.446809 (-2975 5335);
WIRE 16 -1 (-3325 4925)(-4200 4925);
FORCEPROP 2 LAST SIG_NAME FM_CPU1_NMI_SYNC_FLOOD_N
J 0
(-4060 4935);
DISPLAY 0.489362 (-4060 4935);
FORCEPROP 2 LASTPROP $XRERR UNIQUE?
J 0
(-4300 4935);
DISPLAY 0.638298 (-4300 4935);
PAINT MONO (-4300 4935);
DISPLAY INVISIBLE (-4300 4935);
WIRE 16 -1 (-3125 5025)(-2350 5025);
FORCEPROP 2 LAST SIG_NAME FM_BIOS_POST_CMPLT_BUF_N
J 0
(-2975 5035);
DISPLAY 0.489362 (-2975 5035);
WIRE 16 -1 (-3125 5125)(-2350 5125);
FORCEPROP 2 LAST SIG_NAME HDT_HDR_PWROK
J 0
(-2975 5135);
DISPLAY 0.489362 (-2975 5135);
WIRE 16 -1 (-3125 5175)(-2350 5175);
FORCEPROP 2 LAST SIG_NAME ESPI_CPU0_D3
J 0
(-2975 5185);
DISPLAY 0.446809 (-2975 5185);
WIRE 16 -1 (-3125 5225)(-2350 5225);
FORCEPROP 2 LAST SIG_NAME ESPI_CPU0_D2
J 0
(-2975 5235);
DISPLAY 0.446809 (-2975 5235);
WIRE 16 -1 (-3125 5275)(-2350 5275);
FORCEPROP 2 LAST SIG_NAME ESPI_CPU0_D1
J 0
(-2975 5285);
DISPLAY 0.446809 (-2975 5285);
WIRE 16 -1 (-6325 3875)(-5450 3875);
FORCEPROP 2 LAST SIG_NAME RST_RT_CPU0_P1_PERST_R2_N
J 0
(-6150 3885);
DISPLAY 0.489362 (-6150 3885);
FORCEPROP 2 LASTPROP $XRERR UNIQUE?
J 0
(-6390 3885);
DISPLAY 0.638298 (-6390 3885);
PAINT MONO (-6390 3885);
DISPLAY INVISIBLE (-6390 3885);
WIRE 16 -1 (-6325 3925)(-5450 3925);
FORCEPROP 2 LAST SIG_NAME RST_RT_CPU0_P0_RESET_R2_N
J 0
(-6150 3935);
DISPLAY 0.489362 (-6150 3935);
FORCEPROP 2 LASTPROP $XRERR UNIQUE?
J 0
(-6390 3935);
DISPLAY 0.638298 (-6390 3935);
PAINT MONO (-6390 3935);
DISPLAY INVISIBLE (-6390 3935);
WIRE 16 -1 (-6325 4075)(-5450 4075);
FORCEPROP 2 LAST SIG_NAME RST_RT_CPU1_P3_PERST_R2_N
J 0
(-6150 4085);
DISPLAY 0.489362 (-6150 4085);
FORCEPROP 2 LASTPROP $XRERR UNIQUE?
J 0
(-6390 4085);
DISPLAY 0.638298 (-6390 4085);
PAINT MONO (-6390 4085);
DISPLAY INVISIBLE (-6390 4085);
WIRE 16 -1 (-7300 4175)(-5450 4175);
FORCEPROP 2 LAST SIG_NAME APML_CPU0_ALERT_R_N
J 0
(-7125 4185);
DISPLAY 0.489362 (-7125 4185);
WIRE 16 -1 (-3325 5925)(-4200 5925);
FORCEPROP 2 LAST SIG_NAME FM_CPU1_SMERR_N
J 0
(-4060 5935);
DISPLAY 0.489362 (-4060 5935);
FORCEPROP 2 LASTPROP $XRERR UNIQUE?
J 0
(-4300 5935);
DISPLAY 0.638298 (-4300 5935);
PAINT MONO (-4300 5935);
DISPLAY INVISIBLE (-4300 5935);
WIRE 16 -1 (-3325 6175)(-4200 6175);
FORCEPROP 2 LAST SIG_NAME FM_SMERR_LED_R_N
J 0
(-4060 6185);
DISPLAY 0.489362 (-4060 6185);
FORCEPROP 2 LASTPROP $XRERR UNIQUE?
J 0
(-4300 6185);
DISPLAY 0.638298 (-4300 6185);
PAINT MONO (-4300 6185);
DISPLAY INVISIBLE (-4300 6185);
WIRE 16 -1 (-3125 5475)(-2350 5475);
FORCEPROP 2 LAST SIG_NAME ESPI_CPU0_CS1_N
J 0
(-2975 5485);
DISPLAY 0.446809 (-2975 5485);
WIRE 16 -1 (-3125 5425)(-2350 5425);
FORCEPROP 2 LAST SIG_NAME ESPI_CPU0_ALERT_PLD_N
J 0
(-2975 5435);
DISPLAY 0.446809 (-2975 5435);
WIRE 16 -1 (-3125 5375)(-2350 5375);
FORCEPROP 2 LAST SIG_NAME RST_ESPI_CPU0_RSTOUT_N
J 0
(-2975 5385);
DISPLAY 0.446809 (-2975 5385);
WIRE 16 -1 (-3325 4725)(-4200 4725);
FORCEPROP 2 LAST SIG_NAME CPU0_SPD_HOST_CTRL_R1_N
J 0
(-4060 4735);
DISPLAY 0.489362 (-4060 4735);
FORCEPROP 2 LASTPROP $XRERR UNIQUE?
J 0
(-4300 4735);
DISPLAY 0.638298 (-4300 4735);
PAINT MONO (-4300 4735);
DISPLAY INVISIBLE (-4300 4735);
WIRE 16 -1 (-2350 4925)(-3125 4925);
FORCEPROP 2 LAST SIG_NAME CPU1_NMI_SYNC_FLOOD_N
J 0
(-2975 4935);
DISPLAY 0.489362 (-2975 4935);
WIRE 16 -1 (-3325 4475)(-4200 4475);
FORCEPROP 2 LAST SIG_NAME P12V_ALL_PWROK_R
J 0
(-4060 4485);
DISPLAY 0.489362 (-4060 4485);
FORCEPROP 2 LASTPROP $XRERR UNIQUE?
J 0
(-4300 4485);
DISPLAY 0.638298 (-4300 4485);
PAINT MONO (-4300 4485);
DISPLAY INVISIBLE (-4300 4485);
WIRE 16 -1 (-2350 4675)(-3125 4675);
FORCEPROP 2 LAST SIG_NAME CPU1_HDT_BYPASS_SEL
J 0
(-2975 4685);
DISPLAY 0.489362 (-2975 4685);
WIRE 16 -1 (-3125 4725)(-2350 4725);
FORCEPROP 2 LAST SIG_NAME CPU0_SPD_HOST_CTRL_N
J 0
(-2975 4735);
DISPLAY 0.489362 (-2975 4735);
WIRE 16 -1 (-2350 4475)(-3125 4475);
FORCEPROP 2 LAST SIG_NAME P12V_ALL_PWROK
J 0
(-2975 4485);
DISPLAY 0.489362 (-2975 4485);
WIRE 16 -1 (-3125 4275)(-2350 4275);
FORCEPROP 2 LAST SIG_NAME ROM_SD_LS_OE
J 0
(-2975 4285);
DISPLAY 0.446809 (-2975 4285);
WIRE 16 -1 (-3325 4125)(-4200 4125);
FORCEPROP 2 LAST SIG_NAME FM_CPU1_PWRGD_OUT
J 0
(-4060 4135);
DISPLAY 0.446809 (-4060 4135);
FORCEPROP 2 LASTPROP $XRERR UNIQUE?
J 0
(-4300 4135);
DISPLAY 0.638298 (-4300 4135);
PAINT MONO (-4300 4135);
DISPLAY INVISIBLE (-4300 4135);
WIRE 16 -1 (-3325 4225)(-4200 4225);
FORCEPROP 2 LAST SIG_NAME FM_SPD_CPU0_SWITCH_CTRL_R_N
J 0
(-4060 4235);
DISPLAY 0.489362 (-4060 4235);
FORCEPROP 2 LASTPROP $XRERR UNIQUE?
J 0
(-4300 4235);
DISPLAY 0.638298 (-4300 4235);
PAINT MONO (-4300 4235);
DISPLAY INVISIBLE (-4300 4235);
WIRE 16 -1 (-3125 4375)(-2350 4375);
FORCEPROP 2 LAST SIG_NAME BMC_JTAG_SEL
J 0
(-2975 4385);
DISPLAY 0.489362 (-2975 4385);
WIRE 16 -1 (-3125 4325)(-2350 4325);
FORCEPROP 2 LAST SIG_NAME ROM_LS_EN
J 0
(-2975 4335);
DISPLAY 0.446809 (-2975 4335);
WIRE 16 -1 (-3325 4075)(-4200 4075);
FORCEPROP 2 LAST SIG_NAME FM_CPU1_PWR_GD_IN
J 0
(-4060 4085);
DISPLAY 0.446809 (-4060 4085);
FORCEPROP 2 LASTPROP $XRERR UNIQUE?
J 0
(-4300 4085);
DISPLAY 0.638298 (-4300 4085);
PAINT MONO (-4300 4085);
DISPLAY INVISIBLE (-4300 4085);
WIRE 16 -1 (-3325 4025)(-4200 4025);
FORCEPROP 2 LAST SIG_NAME FM_CPU0_FORCE_SELFREFRESH
J 0
(-4060 4035);
DISPLAY 0.489362 (-4060 4035);
FORCEPROP 2 LASTPROP $XRERR UNIQUE?
J 0
(-4300 4035);
DISPLAY 0.638298 (-4300 4035);
PAINT MONO (-4300 4035);
DISPLAY INVISIBLE (-4300 4035);
WIRE 16 -1 (-2350 4575)(-3125 4575);
FORCEPROP 2 LAST SIG_NAME SCM_IRQ_1V8_N
J 0
(-2975 4585);
DISPLAY 0.489362 (-2975 4585);
WIRE 16 -1 (-3125 4625)(-2350 4625);
FORCEPROP 2 LAST SIG_NAME CPU1_JTAG_BUF_OE
J 0
(-2975 4635);
DISPLAY 0.489362 (-2975 4635);
WIRE 72 -1 (-3125 4425)(-2350 4425);
FORCEPROP 2 LAST SIG_NAME RST_RT_CPU0_P3_RESET_R_N
J 0
(-2960 4435);
DISPLAY 0.553191 (-2960 4435);
WIRE 16 -1 (-2350 4825)(-3125 4825);
FORCEPROP 2 LAST SIG_NAME SCM_USB_OC_N
J 0
(-2975 4835);
DISPLAY 0.489362 (-2975 4835);
WIRE 72 -1 (-3125 4525)(-2350 4525);
FORCEPROP 2 LAST SIG_NAME RST_RT_CPU0_P3_PERST_R_N
J 0
(-2960 4535);
DISPLAY 0.553191 (-2960 4535);
WIRE 72 -1 (-3125 4875)(-2325 4875);
FORCEPROP 2 LAST SIG_NAME RST_RT_CPU0_P2_RESET_R_N
J 0
(-2985 4885);
DISPLAY 0.553191 (-2985 4885);
WIRE 16 -1 (-3125 3925)(-2325 3925);
FORCEPROP 2 LAST SIG_NAME RST_SMB_RT_ROM_R1_N
J 0
(-2960 3935);
DISPLAY 0.553191 (-2960 3935);
WIRE 16 -1 (-3125 5075)(-2350 5075);
FORCEPROP 2 LAST SIG_NAME HDT_HDR_RESET_N
J 0
(-2975 5085);
DISPLAY 0.489362 (-2975 5085);
WIRE 16 -1 (-3125 5525)(-2350 5525);
FORCEPROP 2 LAST SIG_NAME CLK_ESPI_CPU0_CLK1
J 0
(-2975 5535);
DISPLAY 0.446809 (-2975 5535);
WIRE 16 -1 (-3125 5575)(-2325 5575);
FORCEPROP 2 LAST SIG_NAME FM_JTAG_BMC_R_OE
J 0
(-2885 5585);
DISPLAY 0.553191 (-2885 5585);
WIRE 16 -1 (-2350 5725)(-3125 5725);
FORCEPROP 2 LAST SIG_NAME CPU0_HDT_CONN_TESTEN
J 0
(-2975 5735);
DISPLAY 0.489362 (-2975 5735);
WIRE 16 -1 (-3125 5775)(-2350 5775);
FORCEPROP 2 LAST SIG_NAME BIOS_DEBUG_MODE
J 0
(-2975 5785);
DISPLAY 0.489362 (-2975 5785);
WIRE 16 -1 (-3325 5725)(-4200 5725);
FORCEPROP 2 LAST SIG_NAME FM_CPU0_HDT_CONN_TESTEN
J 0
(-4060 5735);
DISPLAY 0.489362 (-4060 5735);
FORCEPROP 2 LASTPROP $XRERR UNIQUE?
J 0
(-4300 5735);
DISPLAY 0.638298 (-4300 5735);
PAINT MONO (-4300 5735);
DISPLAY INVISIBLE (-4300 5735);
WIRE 16 -1 (-6325 5175)(-5450 5175);
FORCEPROP 2 LAST SIG_NAME FM_RST_CPU0_RESETL_N
J 0
(-6175 5185);
DISPLAY 0.489362 (-6175 5185);
FORCEPROP 2 LASTPROP $XRERR UNIQUE?
J 0
(-6415 5185);
DISPLAY 0.638298 (-6415 5185);
PAINT MONO (-6415 5185);
DISPLAY INVISIBLE (-6415 5185);
WIRE 16 -1 (-6325 4975)(-5450 4975);
FORCEPROP 2 LAST SIG_NAME FM_PWRGD_CPU0_PWROK
J 0
(-6175 4985);
DISPLAY 0.489362 (-6175 4985);
FORCEPROP 2 LASTPROP $XRERR UNIQUE?
J 0
(-6415 4985);
DISPLAY 0.638298 (-6415 4985);
PAINT MONO (-6415 4985);
DISPLAY INVISIBLE (-6415 4985);
WIRE 16 -1 (-6325 5025)(-5450 5025);
FORCEPROP 2 LAST SIG_NAME CPU0_JTAG_BUF_R_OE
J 0
(-6185 5035);
DISPLAY 0.446809 (-6185 5035);
FORCEPROP 2 LASTPROP $XRERR UNIQUE?
J 0
(-6425 5035);
DISPLAY 0.638298 (-6425 5035);
PAINT MONO (-6425 5035);
DISPLAY INVISIBLE (-6425 5035);
WIRE 16 -1 (-6325 5225)(-5450 5225);
FORCEPROP 0 LAST SIG_NAME RST_RT_CPU1_P1_RESET_R2_N
J 0
(-6150 5235);
DISPLAY 0.489362 (-6150 5235);
FORCEPROP 2 LASTPROP $XRERR UNIQUE?
J 0
(-6390 5235);
DISPLAY 0.638298 (-6390 5235);
PAINT MONO (-6390 5235);
DISPLAY INVISIBLE (-6390 5235);
WIRE 16 -1 (-6325 5275)(-5450 5275);
FORCEPROP 0 LAST SIG_NAME RST_RT_CPU1_P1_PERST_R2_N
J 0
(-6150 5285);
DISPLAY 0.489362 (-6150 5285);
FORCEPROP 2 LASTPROP $XRERR UNIQUE?
J 0
(-6390 5285);
DISPLAY 0.638298 (-6390 5285);
PAINT MONO (-6390 5285);
DISPLAY INVISIBLE (-6390 5285);
WIRE 16 -1 (-6325 5325)(-5450 5325);
FORCEPROP 2 LAST SIG_NAME FM_CPU0_NV_SAVE_N
J 0
(-6175 5335);
DISPLAY 0.489362 (-6175 5335);
FORCEPROP 2 LASTPROP $XRERR UNIQUE?
J 0
(-6415 5335);
DISPLAY 0.638298 (-6415 5335);
PAINT MONO (-6415 5335);
DISPLAY INVISIBLE (-6415 5335);
WIRE 16 -1 (-6325 5375)(-5450 5375);
FORCEPROP 2 LAST SIG_NAME FM_CPU1_SYS_RESET_N
J 0
(-6175 5385);
DISPLAY 0.489362 (-6175 5385);
FORCEPROP 2 LASTPROP $XRERR UNIQUE?
J 0
(-6415 5385);
DISPLAY 0.638298 (-6415 5385);
PAINT MONO (-6415 5385);
DISPLAY INVISIBLE (-6415 5385);
WIRE 16 -1 (-6325 5425)(-5450 5425);
FORCEPROP 2 LAST SIG_NAME FM_CPU0_SYS_RESET_N
J 0
(-6175 5435);
DISPLAY 0.489362 (-6175 5435);
FORCEPROP 2 LASTPROP $XRERR UNIQUE?
J 0
(-6415 5435);
DISPLAY 0.638298 (-6415 5435);
PAINT MONO (-6415 5435);
DISPLAY INVISIBLE (-6415 5435);
WIRE 16 -1 (-6325 5125)(-5450 5125);
FORCEPROP 2 LAST SIG_NAME FM_RST_CPU1_RESETL_N
J 0
(-6175 5135);
DISPLAY 0.489362 (-6175 5135);
FORCEPROP 2 LASTPROP $XRERR UNIQUE?
J 0
(-6415 5135);
DISPLAY 0.638298 (-6415 5135);
PAINT MONO (-6415 5135);
DISPLAY INVISIBLE (-6415 5135);
WIRE 16 -1 (-6325 5075)(-5450 5075);
FORCEPROP 2 LAST SIG_NAME RST_CPU0_KBRST_N
J 0
(-6175 5085);
DISPLAY 0.489362 (-6175 5085);
FORCEPROP 2 LASTPROP $XRERR UNIQUE?
J 0
(-6415 5085);
DISPLAY 0.638298 (-6415 5085);
PAINT MONO (-6415 5085);
DISPLAY INVISIBLE (-6415 5085);
WIRE 16 -1 (-6325 4925)(-5450 4925);
FORCEPROP 2 LAST SIG_NAME FM_CPU1_NV_SAVE_N
J 0
(-6175 4935);
DISPLAY 0.489362 (-6175 4935);
FORCEPROP 2 LASTPROP $XRERR UNIQUE?
J 0
(-6415 4935);
DISPLAY 0.638298 (-6415 4935);
PAINT MONO (-6415 4935);
DISPLAY INVISIBLE (-6415 4935);
WIRE 16 -1 (-7300 4875)(-5450 4875);
FORCEPROP 2 LAST SIG_NAME PVDD11_S3_P0_RESET_N
J 0
(-7125 4885);
DISPLAY 0.489362 (-7125 4885);
WIRE 16 -1 (-7300 4825)(-5450 4825);
FORCEPROP 2 LAST SIG_NAME PVDD11_S3_P1_RESET_N
J 0
(-7125 4835);
DISPLAY 0.489362 (-7125 4835);
WIRE 16 -1 (-6325 4775)(-5450 4775);
FORCEPROP 2 LAST SIG_NAME FM_CPU0_NMI_SYNC_FLOOD_N
J 0
(-6175 4785);
DISPLAY 0.489362 (-6175 4785);
FORCEPROP 2 LASTPROP $XRERR UNIQUE?
J 0
(-6415 4785);
DISPLAY 0.638298 (-6415 4785);
PAINT MONO (-6415 4785);
DISPLAY INVISIBLE (-6415 4785);
WIRE 16 -1 (-5450 4675)(-6325 4675);
FORCEPROP 2 LAST SIG_NAME FM_PWRGD_CPU1_PWROK
J 0
(-6175 4685);
DISPLAY 0.489362 (-6175 4685);
FORCEPROP 2 LASTPROP $XRERR UNIQUE?
J 0
(-6415 4685);
DISPLAY 0.638298 (-6415 4685);
PAINT MONO (-6415 4685);
DISPLAY INVISIBLE (-6415 4685);
WIRE 16 -1 (-7300 4575)(-5450 4575);
FORCEPROP 0 LAST SIG_NAME TP_SLOT2_CLKREQ_0_R_N
J 0
(-7125 4585);
DISPLAY 0.489362 (-7125 4585);
FORCEPROP 2 LASTPROP $XRERR UNIQUE?
J 0
(-7540 4575);
DISPLAY 0.638298 (-7540 4575);
PAINT MONO (-7540 4575);
DISPLAY INVISIBLE (-7540 4575);
WIRE 16 -1 (-6325 4525)(-5450 4525);
FORCEPROP 2 LAST SIG_NAME FM_CPU0_PWR_BTN_N
J 0
(-6175 4535);
DISPLAY 0.489362 (-6175 4535);
FORCEPROP 2 LASTPROP $XRERR UNIQUE?
J 0
(-6415 4535);
DISPLAY 0.638298 (-6415 4535);
PAINT MONO (-6415 4535);
DISPLAY INVISIBLE (-6415 4535);
WIRE 16 -1 (-5450 4475)(-6325 4475);
FORCEPROP 2 LAST SIG_NAME FM_P1_PCC1_R_N
J 0
(-6175 4485);
DISPLAY 0.489362 (-6175 4485);
FORCEPROP 2 LASTPROP $XRERR UNIQUE?
J 0
(-6415 4485);
DISPLAY 0.638298 (-6415 4485);
PAINT MONO (-6415 4485);
DISPLAY INVISIBLE (-6415 4485);
WIRE 16 -1 (-3325 4275)(-4200 4275);
FORCEPROP 2 LAST SIG_NAME FM_ROM_SD_LS_OE
J 0
(-4060 4285);
DISPLAY 0.446809 (-4060 4285);
FORCEPROP 2 LASTPROP $XRERR UNIQUE?
J 0
(-4300 4285);
DISPLAY 0.638298 (-4300 4285);
PAINT MONO (-4300 4285);
DISPLAY INVISIBLE (-4300 4285);
WIRE 72 -1 (-3325 4425)(-4200 4425);
FORCEPROP 2 LAST SIG_NAME RST_RT_CPU0_P3_RESET_R2_N
J 0
(-4055 4435);
DISPLAY 0.489362 (-4055 4435);
PAINT WHITE (-4055 4435);
FORCEPROP 2 LASTPROP $XRERR UNIQUE?
J 0
(-4295 4435);
DISPLAY 0.638298 (-4295 4435);
PAINT MONO (-4295 4435);
DISPLAY INVISIBLE (-4295 4435);
WIRE 16 -1 (-3325 4375)(-4200 4375);
FORCEPROP 2 LAST SIG_NAME BMC_JTAG_SEL_R
J 0
(-4060 4385);
DISPLAY 0.489362 (-4060 4385);
FORCEPROP 2 LASTPROP $XRERR UNIQUE?
J 0
(-4300 4385);
DISPLAY 0.638298 (-4300 4385);
PAINT MONO (-4300 4385);
DISPLAY INVISIBLE (-4300 4385);
WIRE 16 -1 (-3325 4325)(-4200 4325);
FORCEPROP 2 LAST SIG_NAME FM_ROM_LS_EN
J 0
(-4060 4335);
DISPLAY 0.446809 (-4060 4335);
FORCEPROP 2 LASTPROP $XRERR UNIQUE?
J 0
(-4300 4335);
DISPLAY 0.638298 (-4300 4335);
PAINT MONO (-4300 4335);
DISPLAY INVISIBLE (-4300 4335);
WIRE 16 -1 (-3325 4175)(-4200 4175);
FORCEPROP 0 LAST CDS_PHYS_NET_NAME FM_PLD_CPU0_PRSNT_HDT
J 0
(-3900 4225);
PAINT MONO (-3900 4225);
DISPLAY INVISIBLE (-3900 4225);
FORCEPROP 2 LAST SIG_NAME FM_PLD_CPU0_PRSNT_HDT
J 0
(-4060 4185);
DISPLAY 0.489362 (-4060 4185);
FORCEPROP 2 LASTPROP $XRERR UNIQUE?
J 0
(-4300 4185);
DISPLAY 0.638298 (-4300 4185);
PAINT MONO (-4300 4185);
DISPLAY INVISIBLE (-4300 4185);
WIRE 16 -1 (-3625 2925)(-2400 2925);
FORCEPROP 0 LAST CDS_PHYS_NET_NAME GPU_3V3IO_RSVD1_ISO_R
J 0
(-3600 2967);
PAINT MONO (-3600 2967);
DISPLAY INVISIBLE (-3600 2967);
FORCEPROP 0 LAST SIG_NAME GPU_3V3IO_RSVD3_ISO_R
J 0
(-3450 2935);
DISPLAY 0.553191 (-3450 2935);
PAINT WHITE (-3450 2935);
FORCEPROP 2 LASTPROP $XRERR UNIQUE?
J 0
(-3690 2935);
DISPLAY 0.638298 (-3690 2935);
PAINT MONO (-3690 2935);
DISPLAY INVISIBLE (-3690 2935);
WIRE 16 -1 (-3625 2975)(-2400 2975);
FORCEPROP 0 LAST CDS_PHYS_NET_NAME GPU_3V3IO_RSVD1_ISO_R
J 0
(-3600 3017);
PAINT MONO (-3600 3017);
DISPLAY INVISIBLE (-3600 3017);
FORCEPROP 0 LAST SIG_NAME GPU_3V3IO_RSVD1_ISO_R
J 0
(-3450 2985);
DISPLAY 0.553191 (-3450 2985);
PAINT WHITE (-3450 2985);
FORCEPROP 2 LASTPROP $XRERR UNIQUE?
J 0
(-3690 2985);
DISPLAY 0.638298 (-3690 2985);
PAINT MONO (-3690 2985);
DISPLAY INVISIBLE (-3690 2985);
WIRE 16 -1 (-7750 2225)(-6825 2225);
FORCEPROP 0 LAST CDS_PHYS_NET_NAME GPU_3V3IO_RSVD1_ISO
J 0
(-7725 2267);
PAINT MONO (-7725 2267);
DISPLAY INVISIBLE (-7725 2267);
FORCEPROP 0 LAST SIG_NAME GPU_FPGA_RST_R_N
J 0
(-7650 2235);
DISPLAY 0.553191 (-7650 2235);
PAINT WHITE (-7650 2235);
WIRE 16 -1 (-6825 2175)(-7750 2175);
FORCEPROP 2 LAST SIG_NAME PVDD11_S3_P1_EN
J 0
(-7650 2185);
DISPLAY 0.489362 (-7650 2185);
WIRE 16 -1 (-3325 3775)(-4200 3775);
FORCEPROP 2 LAST SIG_NAME RST_SMB_RT_R2_N
J 0
(-4060 3785);
DISPLAY 0.489362 (-4060 3785);
FORCEPROP 2 LASTPROP $XRERR UNIQUE?
J 0
(-4300 3785);
DISPLAY 0.638298 (-4300 3785);
PAINT MONO (-4300 3785);
DISPLAY INVISIBLE (-4300 3785);
WIRE 16 -1 (-3325 3925)(-4200 3925);
FORCEPROP 2 LAST SIG_NAME RST_SMB_RT_ROM_R2_N
J 0
(-4060 3935);
DISPLAY 0.489362 (-4060 3935);
FORCEPROP 2 LASTPROP $XRERR UNIQUE?
J 0
(-4300 3935);
DISPLAY 0.638298 (-4300 3935);
PAINT MONO (-4300 3935);
DISPLAY INVISIBLE (-4300 3935);
WIRE 16 -1 (-3325 3975)(-4200 3975);
FORCEPROP 2 LAST SIG_NAME TP_FM_CLK_BUFFER_EN_R
J 0
(-4060 3985);
DISPLAY 0.489362 (-4060 3985);
FORCEPROP 2 LASTPROP $XRERR UNIQUE?
J 0
(-3295 3975);
DISPLAY 0.638298 (-3295 3975);
PAINT MONO (-3295 3975);
DISPLAY INVISIBLE (-3295 3975);
WIRE 72 -1 (-3325 4525)(-4200 4525);
FORCEPROP 2 LAST SIG_NAME RST_RT_CPU0_P3_PERST_R2_N
J 0
(-4055 4535);
DISPLAY 0.489362 (-4055 4535);
PAINT WHITE (-4055 4535);
FORCEPROP 2 LASTPROP $XRERR UNIQUE?
J 0
(-4295 4535);
DISPLAY 0.638298 (-4295 4535);
PAINT MONO (-4295 4535);
DISPLAY INVISIBLE (-4295 4535);
WIRE 16 -1 (-3325 4575)(-4200 4575);
FORCEPROP 2 LAST SIG_NAME SCM_IRQ_1V8_R_N
J 0
(-4060 4585);
DISPLAY 0.489362 (-4060 4585);
FORCEPROP 2 LASTPROP $XRERR UNIQUE?
J 0
(-4300 4585);
DISPLAY 0.638298 (-4300 4585);
PAINT MONO (-4300 4585);
DISPLAY INVISIBLE (-4300 4585);
WIRE 16 -1 (-3325 4625)(-4200 4625);
FORCEPROP 2 LAST SIG_NAME CPU1_JTAG_BUF_R_OE
J 0
(-4060 4635);
DISPLAY 0.489362 (-4060 4635);
FORCEPROP 2 LASTPROP $XRERR UNIQUE?
J 0
(-4300 4635);
DISPLAY 0.638298 (-4300 4635);
PAINT MONO (-4300 4635);
DISPLAY INVISIBLE (-4300 4635);
WIRE 16 -1 (-3325 4675)(-4200 4675);
FORCEPROP 0 LAST CDS_PHYS_NET_NAME FM_PLD_CPU1_PRSNT_HDT
J 2
(-3600 4725);
PAINT MONO (-3600 4725);
DISPLAY INVISIBLE (-3600 4725);
FORCEPROP 2 LAST SIG_NAME FM_PLD_CPU1_PRSNT_HDT
J 0
(-4060 4685);
DISPLAY 0.489362 (-4060 4685);
FORCEPROP 2 LASTPROP $XRERR UNIQUE?
J 0
(-4300 4685);
DISPLAY 0.638298 (-4300 4685);
PAINT MONO (-4300 4685);
DISPLAY INVISIBLE (-4300 4685);
WIRE 16 -1 (-3325 4825)(-4200 4825);
FORCEPROP 2 LAST SIG_NAME SCM_USB_OC_R_N
J 0
(-4060 4835);
DISPLAY 0.489362 (-4060 4835);
FORCEPROP 2 LASTPROP $XRERR UNIQUE?
J 0
(-4300 4835);
DISPLAY 0.638298 (-4300 4835);
PAINT MONO (-4300 4835);
DISPLAY INVISIBLE (-4300 4835);
WIRE 16 -1 (-3325 5875)(-4200 5875);
FORCEPROP 2 LAST SIG_NAME FM_ESPI_CPU0_ALERT_SEL
J 0
(-4060 5885);
DISPLAY 0.489362 (-4060 5885);
FORCEPROP 2 LASTPROP $XRERR UNIQUE?
J 0
(-4300 5885);
DISPLAY 0.638298 (-4300 5885);
PAINT MONO (-4300 5885);
DISPLAY INVISIBLE (-4300 5885);
WIRE 16 -1 (-2350 5925)(-3125 5925);
FORCEPROP 2 LAST SIG_NAME CPU1_SMERR_N
J 0
(-2975 5935);
DISPLAY 0.489362 (-2975 5935);
WIRE 16 -1 (-2350 5975)(-4200 5975);
FORCEPROP 2 LAST SIG_NAME PWRGD_P3V3_R2
J 0
(-4060 5985);
DISPLAY 0.489362 (-4060 5985);
WIRE 16 -1 (-2350 6025)(-4200 6025);
FORCEPROP 2 LAST SIG_NAME SMB_CPU_5_R1_SDA
J 0
(-4060 6035);
DISPLAY 0.489362 (-4060 6035);
WIRE 16 -1 (-2350 6075)(-4200 6075);
FORCEPROP 2 LAST SIG_NAME SMB_CPU_5_R1_SCL
J 0
(-4060 6085);
DISPLAY 0.489362 (-4060 6085);
WIRE 72 -1 (-3125 5825)(-2350 5825);
FORCEPROP 2 LAST SIG_NAME RST_RT_CPU0_P2_PERST_R_N
J 0
(-2985 5835);
DISPLAY 0.553191 (-2985 5835);
WIRE 72 -1 (-3325 5825)(-4200 5825);
FORCEPROP 2 LAST SIG_NAME RST_RT_CPU0_P2_PERST_R2_N
J 0
(-4060 5835);
DISPLAY 0.446809 (-4060 5835);
PAINT WHITE (-4060 5835);
FORCEPROP 2 LASTPROP $XRERR UNIQUE?
J 0
(-4300 5835);
DISPLAY 0.638298 (-4300 5835);
PAINT MONO (-4300 5835);
DISPLAY INVISIBLE (-4300 5835);
WIRE 16 -1 (-3325 5575)(-4200 5575);
FORCEPROP 2 LAST SIG_NAME FM_JTAG_BMC_OE
J 0
(-3950 5585);
DISPLAY 0.489362 (-3950 5585);
FORCEPROP 2 LASTPROP $XRERR UNIQUE?
J 0
(-4190 5585);
DISPLAY 0.638298 (-4190 5585);
PAINT MONO (-4190 5585);
DISPLAY INVISIBLE (-4190 5585);
WIRE 16 -1 (-3325 5475)(-4200 5475);
FORCEPROP 2 LAST SIG_NAME ESPI_CPU0_CS1_R_N
J 0
(-4060 5485);
DISPLAY 0.446809 (-4060 5485);
FORCEPROP 2 LASTPROP $XRERR UNIQUE?
J 0
(-4300 5485);
DISPLAY 0.638298 (-4300 5485);
PAINT MONO (-4300 5485);
DISPLAY INVISIBLE (-4300 5485);
WIRE 16 -1 (-3325 5325)(-4200 5325);
FORCEPROP 2 LAST SIG_NAME ESPI_CPU0_R1_D0
J 0
(-4060 5335);
DISPLAY 0.446809 (-4060 5335);
FORCEPROP 2 LASTPROP $XRERR UNIQUE?
J 0
(-4300 5335);
DISPLAY 0.638298 (-4300 5335);
PAINT MONO (-4300 5335);
DISPLAY INVISIBLE (-4300 5335);
WIRE 16 -1 (-3325 5275)(-4200 5275);
FORCEPROP 2 LAST SIG_NAME ESPI_CPU0_R1_D1
J 0
(-4060 5285);
DISPLAY 0.446809 (-4060 5285);
FORCEPROP 2 LASTPROP $XRERR UNIQUE?
J 0
(-4300 5285);
DISPLAY 0.638298 (-4300 5285);
PAINT MONO (-4300 5285);
DISPLAY INVISIBLE (-4300 5285);
WIRE 16 -1 (-3325 5225)(-4200 5225);
FORCEPROP 2 LAST SIG_NAME ESPI_CPU0_R1_D2
J 0
(-4060 5235);
DISPLAY 0.446809 (-4060 5235);
FORCEPROP 2 LASTPROP $XRERR UNIQUE?
J 0
(-4300 5235);
DISPLAY 0.638298 (-4300 5235);
PAINT MONO (-4300 5235);
DISPLAY INVISIBLE (-4300 5235);
WIRE 16 -1 (-3325 5175)(-4200 5175);
FORCEPROP 2 LAST SIG_NAME ESPI_CPU0_R1_D3
J 0
(-4060 5185);
DISPLAY 0.446809 (-4060 5185);
FORCEPROP 2 LASTPROP $XRERR UNIQUE?
J 0
(-4300 5185);
DISPLAY 0.638298 (-4300 5185);
PAINT MONO (-4300 5185);
DISPLAY INVISIBLE (-4300 5185);
WIRE 16 -1 (-3325 5775)(-4200 5775);
FORCEPROP 2 LAST SIG_NAME BIOS_DEBUG_MODE_R
J 0
(-4060 5785);
DISPLAY 0.489362 (-4060 5785);
FORCEPROP 2 LASTPROP $XRERR UNIQUE?
J 0
(-4300 5785);
DISPLAY 0.638298 (-4300 5785);
PAINT MONO (-4300 5785);
DISPLAY INVISIBLE (-4300 5785);
WIRE 16 -1 (-3325 5675)(-4200 5675);
FORCEPROP 2 LAST SIG_NAME TP_PWRGD_P12V_FAN_DR_R
J 0
(-4060 5685);
DISPLAY 0.489362 (-4060 5685);
FORCEPROP 2 LASTPROP $XRERR UNIQUE?
J 0
(-3295 5675);
DISPLAY 0.638298 (-3295 5675);
PAINT MONO (-3295 5675);
DISPLAY INVISIBLE (-3295 5675);
WIRE 16 -1 (-2350 5625)(-3675 5625);
WIRE 16 -1 (-3675 5625)(-4200 5625);
FORCEPROP 2 LAST SIG_NAME PWRGD_P12V_MEM_R
J 0
(-4060 5635);
DISPLAY 0.489362 (-4060 5635);
WIRE 16 -1 (-3325 5525)(-4200 5525);
FORCEPROP 2 LAST SIG_NAME CLK_ESPI_CPU0_R1_CLK1
J 0
(-4060 5535);
DISPLAY 0.446809 (-4060 5535);
FORCEPROP 2 LASTPROP $XRERR UNIQUE?
J 0
(-4300 5535);
DISPLAY 0.638298 (-4300 5535);
PAINT MONO (-4300 5535);
DISPLAY INVISIBLE (-4300 5535);
WIRE 16 -1 (-3325 5125)(-4200 5125);
FORCEPROP 2 LAST SIG_NAME FM_HDT_HDR_PWROK
J 0
(-4060 5135);
DISPLAY 0.489362 (-4060 5135);
FORCEPROP 2 LASTPROP $XRERR UNIQUE?
J 0
(-4300 5135);
DISPLAY 0.638298 (-4300 5135);
PAINT MONO (-4300 5135);
DISPLAY INVISIBLE (-4300 5135);
WIRE 16 -1 (-3325 5075)(-4200 5075);
FORCEPROP 2 LAST SIG_NAME FM_HDT_HDR_RESET_N
J 0
(-4060 5085);
DISPLAY 0.489362 (-4060 5085);
FORCEPROP 2 LASTPROP $XRERR UNIQUE?
J 0
(-4300 5085);
DISPLAY 0.638298 (-4300 5085);
PAINT MONO (-4300 5085);
DISPLAY INVISIBLE (-4300 5085);
WIRE 16 -1 (-3325 5025)(-4200 5025);
FORCEPROP 2 LAST SIG_NAME FM_BIOS_POST_CMPLT_BUF_R_N
J 0
(-4060 5035);
DISPLAY 0.489362 (-4060 5035);
FORCEPROP 2 LASTPROP $XRERR UNIQUE?
J 0
(-4300 5035);
DISPLAY 0.638298 (-4300 5035);
PAINT MONO (-4300 5035);
DISPLAY INVISIBLE (-4300 5035);
WIRE 16 -1 (-2350 4975)(-4200 4975);
FORCEPROP 2 LAST SIG_NAME FM_BIOS_USB_RECOVERY
J 0
(-4060 4985);
DISPLAY 0.489362 (-4060 4985);
WIRE 72 -1 (-3325 4875)(-4200 4875);
FORCEPROP 2 LAST SIG_NAME RST_RT_CPU0_P2_RESET_R2_N
J 0
(-4055 4885);
DISPLAY 0.489362 (-4055 4885);
PAINT WHITE (-4055 4885);
FORCEPROP 2 LASTPROP $XRERR UNIQUE?
J 0
(-4295 4885);
DISPLAY 0.638298 (-4295 4885);
PAINT MONO (-4295 4885);
DISPLAY INVISIBLE (-4295 4885);
WIRE 16 -1 (-6825 2125)(-7750 2125);
FORCEPROP 2 LAST SIG_NAME PWRGD_PVDD11_S3_P1
J 0
(-7650 2135);
DISPLAY 0.489362 (-7650 2135);
WIRE 16 -1 (-7750 2075)(-6825 2075);
FORCEPROP 2 LAST SIG_NAME PVDD18_S5_P1_EN
J 0
(-7650 2085);
DISPLAY 0.489362 (-7650 2085);
WIRE 16 -1 (-6825 2025)(-7750 2025);
FORCEPROP 2 LAST SIG_NAME FPGA_DEBUG_SW_SPARE
J 0
(-7650 2035);
DISPLAY 0.446809 (-7650 2035);
WIRE 16 -1 (-6325 4625)(-5450 4625);
FORCEPROP 2 LAST SIG_NAME FM_P1_PCC0_R_N
J 0
(-6175 4635);
DISPLAY 0.489362 (-6175 4635);
FORCEPROP 2 LASTPROP $XRERR UNIQUE?
J 0
(-6415 4635);
DISPLAY 0.638298 (-6415 4635);
PAINT MONO (-6415 4635);
DISPLAY INVISIBLE (-6415 4635);
WIRE 16 -1 (-3325 6125)(-4200 6125);
FORCEPROP 2 LAST SIG_NAME FM_CPU0_SMERR_N
J 0
(-4060 6135);
DISPLAY 0.489362 (-4060 6135);
FORCEPROP 2 LASTPROP $XRERR UNIQUE?
J 0
(-4300 6135);
DISPLAY 0.638298 (-4300 6135);
PAINT MONO (-4300 6135);
DISPLAY INVISIBLE (-4300 6135);
WIRE 16 -1 (-7300 5175)(-6525 5175);
FORCEPROP 2 LAST SIG_NAME RST_CPU0_RESETL_N
J 0
(-7125 5185);
DISPLAY 0.489362 (-7125 5185);
WIRE 16 -1 (-7300 6075)(-6525 6075);
FORCEPROP 2 LAST SIG_NAME RST_CPU0_PERST0_N
J 0
(-7125 6085);
DISPLAY 0.489362 (-7125 6085);
WIRE 16 -1 (-7300 6175)(-5450 6175);
FORCEPROP 2 LAST SIG_NAME FM_CPU0_SLP_S5_N
J 0
(-7125 6185);
DISPLAY 0.489362 (-7125 6185);
WIRE 16 -1 (-7300 6125)(-5450 6125);
FORCEPROP 2 LAST SIG_NAME FM_CPU0_SLP_S3_N
J 0
(-7125 6135);
DISPLAY 0.489362 (-7125 6135);
WIRE 16 -1 (-6325 6075)(-5450 6075);
FORCEPROP 2 LAST SIG_NAME RST_CPU0_PERST0_R_N
J 0
(-6175 6085);
DISPLAY 0.489362 (-6175 6085);
FORCEPROP 2 LASTPROP $XRERR UNIQUE?
J 0
(-6415 6085);
DISPLAY 0.638298 (-6415 6085);
PAINT MONO (-6415 6085);
DISPLAY INVISIBLE (-6415 6085);
WIRE 16 -1 (-6325 6025)(-5450 6025);
FORCEPROP 2 LAST SIG_NAME RST_CPU1_PERST1_R_N
J 0
(-6175 6035);
DISPLAY 0.489362 (-6175 6035);
FORCEPROP 2 LASTPROP $XRERR UNIQUE?
J 0
(-6415 6035);
DISPLAY 0.638298 (-6415 6035);
PAINT MONO (-6415 6035);
DISPLAY INVISIBLE (-6415 6035);
WIRE 16 -1 (-7300 5925)(-5450 5925);
FORCEPROP 2 LAST SIG_NAME FM_CPU1_SLP_S3_N
J 0
(-7125 5935);
DISPLAY 0.489362 (-7125 5935);
WIRE 16 -1 (-7300 5325)(-6525 5325);
FORCEPROP 2 LAST SIG_NAME CPU0_NV_SAVE_N
J 0
(-7125 5335);
DISPLAY 0.489362 (-7125 5335);
WIRE 16 -1 (-6525 5275)(-7325 5275);
FORCEPROP 2 LAST SIG_NAME RST_RT_CPU1_P1_PERST_R_N
J 0
(-7285 5285);
DISPLAY 0.553191 (-7285 5285);
WIRE 16 -1 (-6525 5675)(-7300 5675);
FORCEPROP 2 LAST SIG_NAME RST_CPU1_PERST0_N
J 0
(-7125 5685);
DISPLAY 0.489362 (-7125 5685);
WIRE 16 -1 (-6525 5725)(-7325 5725);
FORCEPROP 2 LAST SIG_NAME RST_RT_CPU1_P0_RESET_R_N
J 0
(-7135 5735);
DISPLAY 0.446809 (-7135 5735);
WIRE 16 -1 (-6525 5775)(-7325 5775);
FORCEPROP 2 LAST SIG_NAME RST_RT_CPU1_P0_PERST_R_N
J 0
(-7135 5785);
DISPLAY 0.446809 (-7135 5785);
WIRE 16 -1 (-7300 5825)(-6525 5825);
FORCEPROP 2 LAST SIG_NAME RST_CPU0_PERST1_N
J 0
(-7125 5835);
DISPLAY 0.489362 (-7125 5835);
WIRE 72 -1 (-6525 5875)(-7300 5875);
FORCEPROP 2 LAST SIG_NAME PWRGD_P0V9_RETIMER_CPU0
J 0
(-7260 5885);
DISPLAY 0.553191 (-7260 5885);
WIRE 16 -1 (-7300 5975)(-5450 5975);
FORCEPROP 2 LAST SIG_NAME FM_CPU1_SLP_S5_N
J 0
(-7125 5985);
DISPLAY 0.489362 (-7125 5985);
WIRE 16 -1 (-6525 6025)(-7300 6025);
FORCEPROP 2 LAST SIG_NAME RST_CPU1_PERST1_N
J 0
(-7125 6035);
DISPLAY 0.489362 (-7125 6035);
WIRE 16 -1 (-6525 5375)(-7300 5375);
FORCEPROP 2 LAST SIG_NAME RST_CPU1_SYS_N
J 0
(-7125 5385);
DISPLAY 0.489362 (-7125 5385);
WIRE 16 -1 (-6525 5425)(-7300 5425);
FORCEPROP 2 LAST SIG_NAME RST_CPU0_SYS_N
J 0
(-7125 5435);
DISPLAY 0.489362 (-7125 5435);
WIRE 16 -1 (-7300 5475)(-5450 5475);
FORCEPROP 0 LAST SIG_NAME TP_SLOT1_CLKREQ_0_R_N
J 0
(-7125 5485);
DISPLAY 0.489362 (-7125 5485);
FORCEPROP 2 LASTPROP $XRERR UNIQUE?
J 0
(-7540 5475);
DISPLAY 0.638298 (-7540 5475);
PAINT MONO (-7540 5475);
DISPLAY INVISIBLE (-7540 5475);
WIRE 16 -1 (-6325 5825)(-5450 5825);
FORCEPROP 2 LAST SIG_NAME RST_CPU0_PERST1_R_N
J 0
(-6175 5835);
DISPLAY 0.489362 (-6175 5835);
FORCEPROP 2 LASTPROP $XRERR UNIQUE?
J 0
(-6415 5835);
DISPLAY 0.638298 (-6415 5835);
PAINT MONO (-6415 5835);
DISPLAY INVISIBLE (-6415 5835);
WIRE 16 -1 (-6325 5775)(-5450 5775);
FORCEPROP 2 LAST SIG_NAME RST_RT_CPU1_P0_PERST_R2_N
J 0
(-6185 5785);
DISPLAY 0.489362 (-6185 5785);
FORCEPROP 2 LASTPROP $XRERR UNIQUE?
J 0
(-6425 5785);
DISPLAY 0.638298 (-6425 5785);
PAINT MONO (-6425 5785);
DISPLAY INVISIBLE (-6425 5785);
WIRE 16 -1 (-5450 5725)(-6325 5725);
FORCEPROP 2 LAST SIG_NAME RST_RT_CPU1_P0_RESET_R2_N
J 0
(-6185 5735);
DISPLAY 0.446809 (-6185 5735);
FORCEPROP 2 LASTPROP $XRERR UNIQUE?
J 0
(-6425 5735);
DISPLAY 0.638298 (-6425 5735);
PAINT MONO (-6425 5735);
DISPLAY INVISIBLE (-6425 5735);
WIRE 72 -1 (-6525 5625)(-7300 5625);
FORCEPROP 2 LAST SIG_NAME PWRGD_P0V9_RETIMER_CPU1
J 0
(-7260 5635);
DISPLAY 0.553191 (-7260 5635);
WIRE 16 -1 (-7300 5575)(-6525 5575);
FORCEPROP 2 LAST SIG_NAME RST_CPU1_RSMRST_N
J 0
(-7125 5585);
DISPLAY 0.489362 (-7125 5585);
WIRE 16 -1 (-6325 5675)(-5450 5675);
FORCEPROP 2 LAST SIG_NAME RST_CPU1_PERST0_R_N
J 0
(-6175 5685);
DISPLAY 0.489362 (-6175 5685);
FORCEPROP 2 LASTPROP $XRERR UNIQUE?
J 0
(-6415 5685);
DISPLAY 0.638298 (-6415 5685);
PAINT MONO (-6415 5685);
DISPLAY INVISIBLE (-6415 5685);
WIRE 72 -1 (-6325 5875)(-5450 5875);
FORCEPROP 0 LAST SIG_NAME PWRGD_P0V9_RETIMER_CPU0_R2
J 0
(-6160 5885);
DISPLAY 0.489362 (-6160 5885);
FORCEPROP 2 LASTPROP $XRERR UNIQUE?
J 0
(-6400 5885);
DISPLAY 0.638298 (-6400 5885);
PAINT MONO (-6400 5885);
DISPLAY INVISIBLE (-6400 5885);
WIRE 16 -1 (-6325 5575)(-5450 5575);
FORCEPROP 2 LAST SIG_NAME FM_CPU1_RSMRST_N
J 0
(-6175 5585);
DISPLAY 0.489362 (-6175 5585);
FORCEPROP 2 LASTPROP $XRERR UNIQUE?
J 0
(-6415 5585);
DISPLAY 0.638298 (-6415 5585);
PAINT MONO (-6415 5585);
DISPLAY INVISIBLE (-6415 5585);
WIRE 16 -1 (-6325 5525)(-5450 5525);
FORCEPROP 2 LAST SIG_NAME FM_CPU0_RSMRST_N
J 0
(-6175 5535);
DISPLAY 0.489362 (-6175 5535);
FORCEPROP 2 LASTPROP $XRERR UNIQUE?
J 0
(-6415 5535);
DISPLAY 0.638298 (-6415 5535);
PAINT MONO (-6415 5535);
DISPLAY INVISIBLE (-6415 5535);
WIRE 16 -1 (-7300 5525)(-6525 5525);
FORCEPROP 2 LAST SIG_NAME RST_CPU0_RSMRST_N
J 0
(-7125 5535);
DISPLAY 0.489362 (-7125 5535);
WIRE 72 -1 (-6325 5625)(-5450 5625);
FORCEPROP 0 LAST SIG_NAME PWRGD_P0V9_RETIMER_CPU1_R2
J 0
(-6150 5635);
DISPLAY 0.489362 (-6150 5635);
FORCEPROP 2 LASTPROP $XRERR UNIQUE?
J 0
(-6390 5635);
DISPLAY 0.638298 (-6390 5635);
PAINT MONO (-6390 5635);
DISPLAY INVISIBLE (-6390 5635);
WIRE 16 -1 (-825 1675)(-3625 1675);
FORCEPROP 2 LAST SIG_NAME SW_P3V3_EN
J 0
(-3450 1680);
DISPLAY 0.617021 (-3450 1680);
WIRE 16 -1 (-2200 2125)(-850 2125);
FORCEPROP 0 LAST CDS_PHYS_NET_NAME GPU_BB_RSVD_1_ISO
J 0
(-2175 2167);
PAINT MONO (-2175 2167);
DISPLAY INVISIBLE (-2175 2167);
FORCEPROP 0 LAST SIG_NAME GPU_HMC_PRSNT_ISO_N
J 0
(-1700 2135);
DISPLAY 0.553191 (-1700 2135);
PAINT WHITE (-1700 2135);
WIRE 16 -1 (-2200 2225)(-850 2225);
FORCEPROP 0 LAST CDS_PHYS_NET_NAME GPU_3V3IO_RSVD0_FFU_ISO
J 0
(-2175 2267);
PAINT MONO (-2175 2267);
DISPLAY INVISIBLE (-2175 2267);
FORCEPROP 0 LAST SIG_NAME GPU_FPGA_THERM_OVERT_ISO_N
J 0
(-1700 2235);
DISPLAY 0.553191 (-1700 2235);
PAINT WHITE (-1700 2235);
WIRE 16 -1 (-2200 2275)(-850 2275);
FORCEPROP 0 LAST CDS_PHYS_NET_NAME GPU_3V3IO_RSVD0_FFU_ISO
J 0
(-2175 2317);
PAINT MONO (-2175 2317);
DISPLAY INVISIBLE (-2175 2317);
FORCEPROP 0 LAST SIG_NAME SWB_HSC_PWRGD_ISO
J 0
(-1700 2285);
DISPLAY 0.553191 (-1700 2285);
PAINT WHITE (-1700 2285);
WIRE 16 -1 (-3625 2325)(-2400 2325);
FORCEPROP 0 LAST CDS_PHYS_NET_NAME GPU_3V3IO_RSVD1_ISO_R
J 0
(-3600 2367);
PAINT MONO (-3600 2367);
DISPLAY INVISIBLE (-3600 2367);
FORCEPROP 0 LAST SIG_NAME PRSNT_CABLE_GPU_A1_ISO_R_N
J 0
(-3450 2335);
DISPLAY 0.553191 (-3450 2335);
PAINT WHITE (-3450 2335);
FORCEPROP 2 LASTPROP $XRERR UNIQUE?
J 0
(-3690 2335);
DISPLAY 0.638298 (-3690 2335);
PAINT MONO (-3690 2335);
DISPLAY INVISIBLE (-3690 2335);
WIRE 16 -1 (-3625 2375)(-2400 2375);
FORCEPROP 0 LAST CDS_PHYS_NET_NAME GPU_3V3IO_RSVD1_ISO_R
J 0
(-3600 2417);
PAINT MONO (-3600 2417);
DISPLAY INVISIBLE (-3600 2417);
FORCEPROP 0 LAST SIG_NAME GPU_3V3IO_RSVD5_FFU_ISO_R
J 0
(-3450 2385);
DISPLAY 0.553191 (-3450 2385);
PAINT WHITE (-3450 2385);
FORCEPROP 2 LASTPROP $XRERR UNIQUE?
J 0
(-3690 2385);
DISPLAY 0.638298 (-3690 2385);
PAINT MONO (-3690 2385);
DISPLAY INVISIBLE (-3690 2385);
WIRE 16 -1 (-6625 2225)(-5375 2225);
FORCEPROP 0 LAST CDS_PHYS_NET_NAME GPU_3V3IO_RSVD1_ISO_R
J 0
(-6600 2267);
PAINT MONO (-6600 2267);
DISPLAY INVISIBLE (-6600 2267);
FORCEPROP 0 LAST SIG_NAME GPU_FPGA_RST_N
J 0
(-6150 2235);
DISPLAY 0.553191 (-6150 2235);
PAINT WHITE (-6150 2235);
FORCEPROP 2 LASTPROP $XRERR UNIQUE?
J 0
(-6390 2235);
DISPLAY 0.638298 (-6390 2235);
PAINT MONO (-6390 2235);
DISPLAY INVISIBLE (-6390 2235);
WIRE 16 -1 (-6625 2275)(-5375 2275);
FORCEPROP 0 LAST CDS_PHYS_NET_NAME GPU_3V3IO_RSVD1_ISO_R
J 0
(-6600 2317);
PAINT MONO (-6600 2317);
DISPLAY INVISIBLE (-6600 2317);
FORCEPROP 0 LAST SIG_NAME FM_GPU_PWR_EN
J 0
(-6150 2285);
DISPLAY 0.553191 (-6150 2285);
PAINT WHITE (-6150 2285);
FORCEPROP 2 LASTPROP $XRERR UNIQUE?
J 0
(-6390 2285);
DISPLAY 0.638298 (-6390 2285);
PAINT MONO (-6390 2285);
DISPLAY INVISIBLE (-6390 2285);
WIRE 16 -1 (-5375 2475)(-6625 2475);
FORCEPROP 2 LAST SIG_NAME FM_PWRGD_PVDDCR_CPU0_P1
J 0
(-6150 2480);
DISPLAY 0.489362 (-6150 2480);
FORCEPROP 2 LASTPROP $XRERR UNIQUE?
J 0
(-6390 2480);
DISPLAY 0.638298 (-6390 2480);
PAINT MONO (-6390 2480);
DISPLAY INVISIBLE (-6390 2480);
WIRE 16 -1 (-5375 2625)(-6625 2625);
FORCEPROP 2 LAST SIG_NAME FM_PWRGD_PVDDCR_CPU1_P1
J 0
(-6150 2630);
DISPLAY 0.489362 (-6150 2630);
FORCEPROP 2 LASTPROP $XRERR UNIQUE?
J 0
(-6390 2630);
DISPLAY 0.638298 (-6390 2630);
PAINT MONO (-6390 2630);
DISPLAY INVISIBLE (-6390 2630);
WIRE 16 -1 (-5375 2875)(-6625 2875);
FORCEPROP 2 LAST SIG_NAME FM_PWRGD_PVDD11_S3_P0
J 0
(-6150 2880);
DISPLAY 0.489362 (-6150 2880);
FORCEPROP 2 LASTPROP $XRERR UNIQUE?
J 0
(-6390 2880);
DISPLAY 0.638298 (-6390 2880);
PAINT MONO (-6390 2880);
DISPLAY INVISIBLE (-6390 2880);
WIRE 16 -1 (-2200 1925)(-850 1925);
FORCEPROP 0 LAST CDS_PHYS_NET_NAME GPU_BB_RSVD_1_ISO
J 0
(-2175 1967);
PAINT MONO (-2175 1967);
DISPLAY INVISIBLE (-2175 1967);
FORCEPROP 0 LAST SIG_NAME GPU_FPGA_EROT_FATALERR_ISO_N
J 0
(-1700 1935);
DISPLAY 0.553191 (-1700 1935);
PAINT WHITE (-1700 1935);
WIRE 16 -1 (-2200 1825)(-850 1825);
FORCEPROP 0 LAST CDS_PHYS_NET_NAME GPU_BB_RSVD_1_ISO
J 0
(-2175 1867);
PAINT MONO (-2175 1867);
DISPLAY INVISIBLE (-2175 1867);
FORCEPROP 0 LAST SIG_NAME RST_BMC_FROM_SWB_ISO_N
J 0
(-1700 1835);
DISPLAY 0.553191 (-1700 1835);
PAINT WHITE (-1700 1835);
WIRE 16 -1 (-2200 1775)(-850 1775);
FORCEPROP 0 LAST CDS_PHYS_NET_NAME SWB_HSC_PWRGD_ISO
J 0
(-2175 1817);
PAINT MONO (-2175 1817);
DISPLAY INVISIBLE (-2175 1817);
FORCEPROP 0 LAST SIG_NAME FM_SWB_BIC_READY_ISO_N
J 0
(-1700 1785);
DISPLAY 0.553191 (-1700 1785);
PAINT WHITE (-1700 1785);
WIRE 16 -1 (-2200 1525)(-850 1525);
FORCEPROP 0 LAST CDS_PHYS_NET_NAME SWB_HSC_PWRGD_ISO
J 0
(-2175 1567);
PAINT MONO (-2175 1567);
DISPLAY INVISIBLE (-2175 1567);
FORCEPROP 0 LAST SIG_NAME FM_GPU_PWRGD_ISO
J 0
(-1700 1535);
DISPLAY 0.553191 (-1700 1535);
PAINT WHITE (-1700 1535);
WIRE 16 -1 (-3625 1275)(-2400 1275);
FORCEPROP 0 LAST CDS_PHYS_NET_NAME GPU_3V3IO_RSVD1_ISO_R
J 0
(-3600 1317);
PAINT MONO (-3600 1317);
DISPLAY INVISIBLE (-3600 1317);
FORCEPROP 0 LAST SIG_NAME GPU_FPGA_BOOT_EN_R
J 0
(-3450 1285);
DISPLAY 0.553191 (-3450 1285);
PAINT WHITE (-3450 1285);
FORCEPROP 2 LASTPROP $XRERR UNIQUE?
J 0
(-3690 1285);
DISPLAY 0.638298 (-3690 1285);
PAINT MONO (-3690 1285);
DISPLAY INVISIBLE (-3690 1285);
WIRE 16 -1 (-6825 1875)(-7750 1875);
FORCEPROP 2 LAST SIG_NAME PVDD33_S5_EN
J 0
(-7650 1885);
DISPLAY 0.489362 (-7650 1885);
WIRE 16 -1 (-6825 1775)(-7750 1775);
FORCEPROP 2 LAST SIG_NAME PVDD18_S5_P0_EN
J 0
(-7650 1785);
DISPLAY 0.489362 (-7650 1785);
WIRE 16 -1 (-7750 1825)(-6825 1825);
FORCEPROP 2 LAST SIG_NAME PWRGD_P3V3_AUX
J 0
(-7650 1835);
DISPLAY 0.446809 (-7650 1835);
WIRE 72 -1 (-5375 1975)(-7750 1975);
FORCEPROP 0 LAST CDS_PHYS_NET_NAME TP_SPI_PLD_CLK
J 2
(-5650 2025);
PAINT MONO (-5650 2025);
DISPLAY INVISIBLE (-5650 2025);
FORCEPROP 2 LAST SIG_NAME FM_PWRGD_P1V8_RETIMER_CPU0
J 0
(-7660 1985);
DISPLAY 0.489362 (-7660 1985);
WIRE 16 -1 (-6625 2075)(-5375 2075);
FORCEPROP 2 LAST SIG_NAME PVDD18_S5_P1_R_EN
J 0
(-6150 2080);
DISPLAY 0.489362 (-6150 2080);
FORCEPROP 2 LASTPROP $XRERR UNIQUE?
J 0
(-6390 2080);
DISPLAY 0.638298 (-6390 2080);
PAINT MONO (-6390 2080);
DISPLAY INVISIBLE (-6390 2080);
WIRE 16 -1 (-5375 1575)(-6625 1575);
FORCEPROP 2 LAST SIG_NAME FM_PVDDIO_P1_EN
J 0
(-6150 1580);
DISPLAY 0.489362 (-6150 1580);
FORCEPROP 2 LASTPROP $XRERR UNIQUE?
J 0
(-6390 1580);
DISPLAY 0.638298 (-6390 1580);
PAINT MONO (-6390 1580);
DISPLAY INVISIBLE (-6390 1580);
WIRE 16 -1 (-6625 1475)(-5375 1475);
FORCEPROP 0 LAST CDS_PHYS_NET_NAME GPU_3V3IO_RSVD1_ISO_R
J 0
(-6600 1517);
PAINT MONO (-6600 1517);
DISPLAY INVISIBLE (-6600 1517);
FORCEPROP 0 LAST SIG_NAME FM_GPU_HSC_EN_R
J 0
(-6150 1485);
DISPLAY 0.553191 (-6150 1485);
PAINT WHITE (-6150 1485);
FORCEPROP 2 LASTPROP $XRERR UNIQUE?
J 0
(-6390 1485);
DISPLAY 0.638298 (-6390 1485);
PAINT MONO (-6390 1485);
DISPLAY INVISIBLE (-6390 1485);
WIRE 16 -1 (-3625 2425)(-2400 2425);
FORCEPROP 0 LAST CDS_PHYS_NET_NAME GPU_3V3IO_RSVD1_ISO_R
J 0
(-3600 2467);
PAINT MONO (-3600 2467);
DISPLAY INVISIBLE (-3600 2467);
FORCEPROP 0 LAST SIG_NAME PRSNT_CABLE_GPU_A2_ISO_R_N
J 0
(-3450 2435);
DISPLAY 0.553191 (-3450 2435);
PAINT WHITE (-3450 2435);
FORCEPROP 2 LASTPROP $XRERR UNIQUE?
J 0
(-3690 2435);
DISPLAY 0.638298 (-3690 2435);
PAINT MONO (-3690 2435);
DISPLAY INVISIBLE (-3690 2435);
WIRE 16 -1 (-5375 1875)(-6625 1875);
FORCEPROP 2 LAST SIG_NAME FM_PVDD33_S5_EN
J 0
(-6150 1880);
DISPLAY 0.489362 (-6150 1880);
FORCEPROP 2 LASTPROP $XRERR UNIQUE?
J 0
(-6390 1880);
DISPLAY 0.638298 (-6390 1880);
PAINT MONO (-6390 1880);
DISPLAY INVISIBLE (-6390 1880);
WIRE 16 -1 (-6825 1625)(-7750 1625);
FORCEPROP 2 LAST SIG_NAME CPU0_PWR_GOOD
J 0
(-7650 1635);
DISPLAY 0.489362 (-7650 1635);
WIRE 16 -1 (-6825 1575)(-7750 1575);
FORCEPROP 2 LAST SIG_NAME PVDDIO_P1_EN
J 0
(-7650 1585);
DISPLAY 0.489362 (-7650 1585);
WIRE 16 -1 (-6825 1525)(-7750 1525);
FORCEPROP 2 LAST SIG_NAME PWRGD_PVDDIO_P1
J 0
(-7650 1535);
DISPLAY 0.489362 (-7650 1535);
WIRE 16 -1 (-7750 1475)(-6825 1475);
FORCEPROP 0 LAST CDS_PHYS_NET_NAME GPU_3V3IO_RSVD1_ISO
J 0
(-7725 1517);
PAINT MONO (-7725 1517);
DISPLAY INVISIBLE (-7725 1517);
FORCEPROP 0 LAST SIG_NAME FM_GPU_HSC_EN
J 0
(-7650 1485);
DISPLAY 0.553191 (-7650 1485);
PAINT WHITE (-7650 1485);
WIRE 16 -1 (-7750 1425)(-6825 1425);
FORCEPROP 2 LAST SIG_NAME HP_LVC3_E1S_0_HSC_PWRGD
J 0
(-7650 1435);
DISPLAY 0.446809 (-7650 1435);
PAINT WHITE (-7650 1435);
WIRE 16 -1 (-7750 1325)(-6825 1325);
FORCEPROP 2 LAST SIG_NAME FM_NCSI_OCP_SFF_R_OE
J 0
(-7650 1335);
DISPLAY 0.510638 (-7650 1335);
PAINT WHITE (-7650 1335);
WIRE 16 -1 (-2200 1575)(-850 1575);
FORCEPROP 0 LAST CDS_PHYS_NET_NAME SWB_HSC_PWRGD_ISO
J 0
(-2175 1617);
PAINT MONO (-2175 1617);
DISPLAY INVISIBLE (-2175 1617);
FORCEPROP 0 LAST SIG_NAME FM_SWB_PWRGD_ISO
J 0
(-1700 1585);
DISPLAY 0.553191 (-1700 1585);
PAINT WHITE (-1700 1585);
WIRE 16 -1 (-3625 1575)(-2400 1575);
FORCEPROP 0 LAST CDS_PHYS_NET_NAME GPU_3V3IO_RSVD1_ISO_R
J 0
(-3600 1617);
PAINT MONO (-3600 1617);
DISPLAY INVISIBLE (-3600 1617);
FORCEPROP 0 LAST SIG_NAME FM_SWB_PWRGD_ISO_R
J 0
(-3450 1585);
DISPLAY 0.553191 (-3450 1585);
PAINT WHITE (-3450 1585);
FORCEPROP 2 LASTPROP $XRERR UNIQUE?
J 0
(-3690 1585);
DISPLAY 0.638298 (-3690 1585);
PAINT MONO (-3690 1585);
DISPLAY INVISIBLE (-3690 1585);
WIRE 16 -1 (-825 1625)(-2200 1625);
FORCEPROP 2 LAST SIG_NAME RST_PERST_M2_0_N
J 0
(-1700 1635);
DISPLAY 0.489362 (-1700 1635);
WIRE 16 -1 (-2200 1725)(-850 1725);
FORCEPROP 0 LAST CDS_PHYS_NET_NAME SWB_HSC_PWRGD_ISO
J 0
(-2175 1767);
PAINT MONO (-2175 1767);
DISPLAY INVISIBLE (-2175 1767);
FORCEPROP 0 LAST SIG_NAME FM_SMB_1_ALERT_GPU_ISO_N
J 0
(-1700 1735);
DISPLAY 0.553191 (-1700 1735);
PAINT WHITE (-1700 1735);
WIRE 16 -1 (-2200 1875)(-850 1875);
FORCEPROP 0 LAST CDS_PHYS_NET_NAME SWB_HSC_PWRGD_ISO
J 0
(-2175 1917);
PAINT MONO (-2175 1917);
DISPLAY INVISIBLE (-2175 1917);
FORCEPROP 0 LAST SIG_NAME BIC_MONITER_ISO
J 0
(-1700 1885);
DISPLAY 0.553191 (-1700 1885);
PAINT WHITE (-1700 1885);
WIRE 16 -1 (-3625 2475)(-850 2475);
FORCEPROP 0 LAST CDS_PHYS_NET_NAME GPU_3V3IO_RSVD1_ISO_R
J 0
(-3600 2517);
PAINT MONO (-3600 2517);
DISPLAY INVISIBLE (-3600 2517);
FORCEPROP 0 LAST SIG_NAME RST_PERST_CPU1_SWB_N
J 0
(-3450 2485);
DISPLAY 0.553191 (-3450 2485);
PAINT WHITE (-3450 2485);
WIRE 16 -1 (-2200 2725)(-825 2725);
FORCEPROP 2 LAST SIG_NAME RST_PERST_E1S_0_N
J 0
(-1700 2735);
DISPLAY 0.617021 (-1700 2735);
WIRE 16 -1 (-2200 2775)(-825 2775);
FORCEPROP 2 LAST SIG_NAME FM_RST_PERST_SCM_N
J 0
(-1700 2785);
DISPLAY 0.617021 (-1700 2785);
WIRE 16 -1 (-2200 2825)(-850 2825);
FORCEPROP 0 LAST CDS_PHYS_NET_NAME GPU_3V3IO_RSVD1_ISO
J 0
(-2175 2867);
PAINT MONO (-2175 2867);
DISPLAY INVISIBLE (-2175 2867);
FORCEPROP 0 LAST SIG_NAME HGX_DETECT_N
J 0
(-1700 2835);
DISPLAY 0.553191 (-1700 2835);
PAINT WHITE (-1700 2835);
WIRE 16 -1 (-2200 2925)(-850 2925);
FORCEPROP 0 LAST CDS_PHYS_NET_NAME GPU_3V3IO_RSVD1_ISO
J 0
(-2175 2967);
PAINT MONO (-2175 2967);
DISPLAY INVISIBLE (-2175 2967);
FORCEPROP 0 LAST SIG_NAME GPU_3V3IO_RSVD3_ISO
J 0
(-1700 2935);
DISPLAY 0.553191 (-1700 2935);
PAINT WHITE (-1700 2935);
WIRE 16 -1 (-2200 2975)(-850 2975);
FORCEPROP 0 LAST CDS_PHYS_NET_NAME GPU_3V3IO_RSVD1_ISO
J 0
(-2175 3017);
PAINT MONO (-2175 3017);
DISPLAY INVISIBLE (-2175 3017);
FORCEPROP 0 LAST SIG_NAME GPU_3V3IO_RSVD1_ISO
J 0
(-1700 2985);
DISPLAY 0.553191 (-1700 2985);
PAINT WHITE (-1700 2985);
WIRE 16 -1 (-3625 2875)(-2400 2875);
FORCEPROP 0 LAST CDS_PHYS_NET_NAME GPU_3V3IO_RSVD1_ISO_R
J 0
(-3600 2917);
PAINT MONO (-3600 2917);
DISPLAY INVISIBLE (-3600 2917);
FORCEPROP 0 LAST SIG_NAME GPU_3V3IO_RSVD4_ISO_R
J 0
(-3450 2885);
DISPLAY 0.553191 (-3450 2885);
PAINT WHITE (-3450 2885);
FORCEPROP 2 LASTPROP $XRERR UNIQUE?
J 0
(-3690 2885);
DISPLAY 0.638298 (-3690 2885);
PAINT MONO (-3690 2885);
DISPLAY INVISIBLE (-3690 2885);
WIRE 16 -1 (-3625 2825)(-2400 2825);
FORCEPROP 0 LAST CDS_PHYS_NET_NAME GPU_3V3IO_RSVD1_ISO_R
J 0
(-3600 2867);
PAINT MONO (-3600 2867);
DISPLAY INVISIBLE (-3600 2867);
FORCEPROP 0 LAST SIG_NAME HGX_DETECT_N_R
J 0
(-3450 2835);
DISPLAY 0.553191 (-3450 2835);
PAINT WHITE (-3450 2835);
FORCEPROP 2 LASTPROP $XRERR UNIQUE?
J 0
(-3690 2835);
DISPLAY 0.638298 (-3690 2835);
PAINT MONO (-3690 2835);
DISPLAY INVISIBLE (-3690 2835);
WIRE 16 -1 (-3625 2775)(-2400 2775);
FORCEPROP 2 LAST SIG_NAME FM_RST_PERST_SCM_R_N
J 0
(-3450 2780);
DISPLAY 0.489362 (-3450 2780);
FORCEPROP 2 LASTPROP $XRERR UNIQUE?
J 0
(-3690 2780);
DISPLAY 0.638298 (-3690 2780);
PAINT MONO (-3690 2780);
DISPLAY INVISIBLE (-3690 2780);
WIRE 16 -1 (-3625 2725)(-2400 2725);
FORCEPROP 2 LAST SIG_NAME RST_PERST_E1S_0_R_N
J 0
(-3450 2730);
DISPLAY 0.489362 (-3450 2730);
FORCEPROP 2 LASTPROP $XRERR UNIQUE?
J 0
(-3690 2730);
DISPLAY 0.638298 (-3690 2730);
PAINT MONO (-3690 2730);
DISPLAY INVISIBLE (-3690 2730);
WIRE 16 -1 (-3625 2675)(-2400 2675);
FORCEPROP 0 LAST CDS_PHYS_NET_NAME GPU_3V3IO_RSVD1_ISO_R
J 0
(-3600 2717);
PAINT MONO (-3600 2717);
DISPLAY INVISIBLE (-3600 2717);
FORCEPROP 0 LAST SIG_NAME SWB_HSC_EN_R
J 0
(-3450 2685);
DISPLAY 0.553191 (-3450 2685);
PAINT WHITE (-3450 2685);
FORCEPROP 2 LASTPROP $XRERR UNIQUE?
J 0
(-3690 2685);
DISPLAY 0.638298 (-3690 2685);
PAINT MONO (-3690 2685);
DISPLAY INVISIBLE (-3690 2685);
WIRE 16 -1 (-3625 2625)(-2400 2625);
FORCEPROP 0 LAST CDS_PHYS_NET_NAME GPU_3V3IO_RSVD1_ISO_R
J 0
(-3600 2667);
PAINT MONO (-3600 2667);
DISPLAY INVISIBLE (-3600 2667);
FORCEPROP 0 LAST SIG_NAME GPU_3V3IO_RSVD0_FFU_ISO_R
J 0
(-3450 2635);
DISPLAY 0.553191 (-3450 2635);
PAINT WHITE (-3450 2635);
FORCEPROP 2 LASTPROP $XRERR UNIQUE?
J 0
(-3690 2635);
DISPLAY 0.638298 (-3690 2635);
PAINT MONO (-3690 2635);
DISPLAY INVISIBLE (-3690 2635);
WIRE 16 -1 (-3625 2575)(-2400 2575);
FORCEPROP 0 LAST CDS_PHYS_NET_NAME GPU_3V3IO_RSVD1_ISO_R
J 0
(-3600 2617);
PAINT MONO (-3600 2617);
DISPLAY INVISIBLE (-3600 2617);
FORCEPROP 0 LAST SIG_NAME GPU_3V3IO_RSVD1_FFU_ISO_R
J 0
(-3450 2585);
DISPLAY 0.553191 (-3450 2585);
PAINT WHITE (-3450 2585);
FORCEPROP 2 LASTPROP $XRERR UNIQUE?
J 0
(-3690 2585);
DISPLAY 0.638298 (-3690 2585);
PAINT MONO (-3690 2585);
DISPLAY INVISIBLE (-3690 2585);
WIRE 16 -1 (-3625 2525)(-850 2525);
FORCEPROP 0 LAST CDS_PHYS_NET_NAME GPU_3V3IO_RSVD1_ISO_R
J 0
(-3600 2567);
PAINT MONO (-3600 2567);
DISPLAY INVISIBLE (-3600 2567);
FORCEPROP 0 LAST SIG_NAME RST_PERST_CPU0_SWB_N
J 0
(-3450 2535);
DISPLAY 0.553191 (-3450 2535);
PAINT WHITE (-3450 2535);
WIRE 16 -1 (-3625 2075)(-2400 2075);
FORCEPROP 0 LAST CDS_PHYS_NET_NAME GPU_3V3IO_RSVD1_ISO_R
J 0
(-3600 2117);
PAINT MONO (-3600 2117);
DISPLAY INVISIBLE (-3600 2117);
FORCEPROP 0 LAST SIG_NAME GPU_FPGA_OVERT_ISO_R_N
J 0
(-3450 2085);
DISPLAY 0.553191 (-3450 2085);
PAINT WHITE (-3450 2085);
FORCEPROP 2 LASTPROP $XRERR UNIQUE?
J 0
(-3690 2085);
DISPLAY 0.638298 (-3690 2085);
PAINT MONO (-3690 2085);
DISPLAY INVISIBLE (-3690 2085);
WIRE 16 -1 (-3625 2025)(-2400 2025);
FORCEPROP 0 LAST CDS_PHYS_NET_NAME GPU_3V3IO_RSVD1_ISO_R
J 0
(-3600 2067);
PAINT MONO (-3600 2067);
DISPLAY INVISIBLE (-3600 2067);
FORCEPROP 0 LAST SIG_NAME GPU_WP_HW_CTRL_R_N
J 0
(-3450 2035);
DISPLAY 0.553191 (-3450 2035);
PAINT WHITE (-3450 2035);
FORCEPROP 2 LASTPROP $XRERR UNIQUE?
J 0
(-3690 2035);
DISPLAY 0.638298 (-3690 2035);
PAINT MONO (-3690 2035);
DISPLAY INVISIBLE (-3690 2035);
WIRE 16 -1 (-3625 1975)(-2400 1975);
FORCEPROP 0 LAST CDS_PHYS_NET_NAME GPU_3V3IO_RSVD1_ISO_R
J 0
(-3600 2017);
PAINT MONO (-3600 2017);
DISPLAY INVISIBLE (-3600 2017);
FORCEPROP 0 LAST SIG_NAME GPU_PRSNT_N_ISO_R
J 0
(-3450 1985);
DISPLAY 0.553191 (-3450 1985);
PAINT WHITE (-3450 1985);
FORCEPROP 2 LASTPROP $XRERR UNIQUE?
J 0
(-3690 1985);
DISPLAY 0.638298 (-3690 1985);
PAINT MONO (-3690 1985);
DISPLAY INVISIBLE (-3690 1985);
WIRE 16 -1 (-3625 1925)(-2400 1925);
FORCEPROP 0 LAST CDS_PHYS_NET_NAME GPU_3V3IO_RSVD1_ISO_R
J 0
(-3600 1967);
PAINT MONO (-3600 1967);
DISPLAY INVISIBLE (-3600 1967);
FORCEPROP 0 LAST SIG_NAME GPU_FPGA_EROT_FATALERR_ISO_R_N
J 0
(-3450 1935);
DISPLAY 0.553191 (-3450 1935);
PAINT WHITE (-3450 1935);
FORCEPROP 2 LASTPROP $XRERR UNIQUE?
J 0
(-3690 1935);
DISPLAY 0.638298 (-3690 1935);
PAINT MONO (-3690 1935);
DISPLAY INVISIBLE (-3690 1935);
WIRE 16 -1 (-3625 1875)(-2400 1875);
FORCEPROP 0 LAST CDS_PHYS_NET_NAME GPU_3V3IO_RSVD1_ISO_R
J 0
(-3600 1917);
PAINT MONO (-3600 1917);
DISPLAY INVISIBLE (-3600 1917);
FORCEPROP 0 LAST SIG_NAME BIC_MONITER_ISO_R
J 0
(-3450 1885);
DISPLAY 0.553191 (-3450 1885);
PAINT WHITE (-3450 1885);
FORCEPROP 2 LASTPROP $XRERR UNIQUE?
J 0
(-3690 1885);
DISPLAY 0.638298 (-3690 1885);
PAINT MONO (-3690 1885);
DISPLAY INVISIBLE (-3690 1885);
WIRE 16 -1 (-3625 1475)(-2400 1475);
FORCEPROP 0 LAST CDS_PHYS_NET_NAME GPU_3V3IO_RSVD1_ISO_R
J 0
(-3600 1517);
PAINT MONO (-3600 1517);
DISPLAY INVISIBLE (-3600 1517);
FORCEPROP 0 LAST SIG_NAME FM_SMB_2_ALERT_GPU_ISO_R_N
J 0
(-3450 1485);
DISPLAY 0.553191 (-3450 1485);
PAINT WHITE (-3450 1485);
FORCEPROP 2 LASTPROP $XRERR UNIQUE?
J 0
(-3690 1485);
DISPLAY 0.638298 (-3690 1485);
PAINT MONO (-3690 1485);
DISPLAY INVISIBLE (-3690 1485);
WIRE 72 -1 (-6825 1125)(-7750 1125);
FORCEPROP 2 LAST SIG_NAME P0V9_RETIMER_CPU0_EN
J 0
(-7660 1135);
DISPLAY 0.680851 (-7660 1135);
WIRE 16 -1 (-6825 925)(-7750 925);
FORCEPROP 2 LAST SIG_NAME E1S_0_P12V_EN
J 0
(-7650 935);
DISPLAY 0.510638 (-7650 935);
PAINT WHITE (-7650 935);
WIRE 16 -1 (-7750 675)(-6825 675);
FORCEPROP 0 LAST CDS_PHYS_NET_NAME FM_SWB_PWR_EN_R
J 0
(-7725 717);
PAINT MONO (-7725 717);
DISPLAY INVISIBLE (-7725 717);
FORCEPROP 0 LAST SIG_NAME HPDB_HSC_PWRGD_ISO
J 0
(-7650 685);
DISPLAY 0.553191 (-7650 685);
PAINT WHITE (-7650 685);
WIRE 16 -1 (-3625 1075)(-2400 1075);
FORCEPROP 0 LAST CDS_PHYS_NET_NAME GPU_3V3IO_RSVD1_ISO_R
J 0
(-3600 1117);
PAINT MONO (-3600 1117);
DISPLAY INVISIBLE (-3600 1117);
FORCEPROP 0 LAST SIG_NAME GPU_BASE_STBY_EN_R
J 0
(-3450 1085);
DISPLAY 0.553191 (-3450 1085);
PAINT WHITE (-3450 1085);
FORCEPROP 2 LASTPROP $XRERR UNIQUE?
J 0
(-3690 1085);
DISPLAY 0.638298 (-3690 1085);
PAINT MONO (-3690 1085);
DISPLAY INVISIBLE (-3690 1085);
WIRE 16 -1 (-6825 3075)(-7750 3075);
FORCEPROP 2 LAST SIG_NAME PVDDIO_P0_EN
J 0
(-7650 3085);
DISPLAY 0.489362 (-7650 3085);
WIRE 16 -1 (-6825 2875)(-7750 2875);
FORCEPROP 2 LAST SIG_NAME PWRGD_PVDD11_S3_P0
J 0
(-7650 2885);
DISPLAY 0.489362 (-7650 2885);
WIRE 16 -1 (-6825 2825)(-7750 2825);
FORCEPROP 2 LAST SIG_NAME PVDDCR_CPU0_P1_EN
J 0
(-7650 2835);
DISPLAY 0.489362 (-7650 2835);
WIRE 16 -1 (-7750 2575)(-6825 2575);
FORCEPROP 0 LAST CDS_PHYS_NET_NAME GPU_3V3IO_RSVD1_ISO
J 0
(-7725 2617);
PAINT MONO (-7725 2617);
DISPLAY INVISIBLE (-7725 2617);
FORCEPROP 0 LAST SIG_NAME GPU_FPGA_EROT_RECOV_N
J 0
(-7650 2585);
DISPLAY 0.553191 (-7650 2585);
PAINT WHITE (-7650 2585);
WIRE 16 -1 (-7750 2525)(-6825 2525);
FORCEPROP 0 LAST CDS_PHYS_NET_NAME GPU_3V3IO_RSVD1_ISO
J 0
(-7725 2567);
PAINT MONO (-7725 2567);
DISPLAY INVISIBLE (-7725 2567);
FORCEPROP 0 LAST SIG_NAME BMC_MONITER_R
J 0
(-7650 2535);
DISPLAY 0.553191 (-7650 2535);
PAINT WHITE (-7650 2535);
WIRE 16 -1 (-6825 2425)(-7750 2425);
FORCEPROP 2 LAST SIG_NAME HP_LVC3_SCM_HSC_PWRGD
J 0
(-7650 2435);
DISPLAY 0.553191 (-7650 2435);
PAINT WHITE (-7650 2435);
CIRCLE (-3675 5625)(-3585 5625);
PAINT YELLOW (-3675 5625);
FORCENOTE
TBC
(-3625 5600) 0;
DISPLAY LEFT (-3625 5600);
DISPLAY 1.021277 (-3625 5600);
FORCENOTE
BANK2 P3V3_AUX
(-4400 3325) 0;
DISPLAY LEFT (-4400 3325);
DISPLAY 3.148936 (-4400 3325);
FORCENOTE
BANK1 P1V8_AUX
(-4725 6350) 0;
DISPLAY LEFT (-4725 6350);
DISPLAY 3.148936 (-4725 6350);
QUIT
